G04 ================== begin FILE IDENTIFICATION RECORD ==================*
G04 Layout Name:  15750-1.brd*
G04 Film Name:    15750-1_X_Y*
G04 File Format:  Gerber RS274X*
G04 File Origin:  Cadence Allegro 16.5-S056*
G04 Origin Date:  Fri Dec 30 13:21:26 2016*
G04 *
G04 Layer:  BOARD GEOMETRY/PANEL_DRAWING*
G04 *
G04 Offset:    (0.00 0.00)*
G04 Mirror:    No*
G04 Mode:      Positive*
G04 Rotation:  0*
G04 FullContactRelief:  No*
G04 UndefLineWidth:     6.00*
G04 ================== end FILE IDENTIFICATION RECORD ====================*
%FSLAX35Y35*MOIN*%
%IR0*IPPOS*OFA0.00000B0.00000*MIA0B0*SFA1.00000B1.00000*%
%ADD10C,.006*%
G75*
%LPD*%
G75*
G54D10*
G01X-255189Y-758263D02*
X1713315D01*
G01X-255189Y619690D02*
Y-758263D01*
G01X-250666Y-681931D02*
Y-675631D01*
X-247690D01*
G01X-248786Y-678676D02*
X-250666D01*
G01X-255189Y-561413D02*
X-237867D01*
G01X-247611Y-445710D02*
X-250745D01*
Y-439410D01*
X-247611D01*
G01X-248865Y-442455D02*
X-250745D01*
G01X-255189Y-325192D02*
X-237867D01*
G01X-250901Y-209490D02*
Y-203190D01*
X-249335D01*
X-248708Y-203505D01*
X-248238Y-203925D01*
X-247846Y-204555D01*
X-247533Y-205290D01*
X-247455Y-206340D01*
X-247533Y-207390D01*
X-247846Y-208125D01*
X-248238Y-208755D01*
X-248708Y-209175D01*
X-249335Y-209490D01*
X-250901D01*
G01X-255189Y-88972D02*
X-237867D01*
G01X-247455Y32506D02*
X-247925Y32821D01*
X-248473Y33031D01*
X-249100D01*
X-249805Y32716D01*
X-250353Y32191D01*
X-250745Y31561D01*
X-251058Y30511D01*
X-251136Y29566D01*
X-250980Y28621D01*
X-250745Y27991D01*
X-250275Y27361D01*
X-249726Y26941D01*
X-249178Y26731D01*
X-248630D01*
X-248081Y26941D01*
X-247611Y27256D01*
X-247220Y27676D01*
G01X-255189Y147249D02*
X-237867D01*
G01X-248551Y266311D02*
X-248238Y266626D01*
X-248003Y267151D01*
X-247846Y267886D01*
X-248003Y268516D01*
X-248316Y268936D01*
X-248865Y269251D01*
X-250980D01*
Y262951D01*
X-248395D01*
X-247846Y263371D01*
X-247533Y264001D01*
X-247376Y264736D01*
X-247533Y265471D01*
X-248003Y266101D01*
X-248551Y266311D01*
X-250980D01*
G01X-255189Y383469D02*
X-237867D01*
G01X-251136Y499172D02*
X-249178Y505472D01*
X-247220Y499172D01*
G01X-247925Y501377D02*
X-250431D01*
G01X-255189Y619690D02*
X1713315D01*
G01X-237867Y-740940D02*
X1695993D01*
G01X-237867Y602367D02*
Y-740940D01*
G01Y602367D02*
X1695993D01*
G01X-171224Y-752009D02*
Y-745709D01*
X-172164Y-746969D01*
G01Y-752009D02*
X-170284D01*
G01X-171224Y608621D02*
Y614921D01*
X-172164Y613661D01*
G01Y608621D02*
X-170284D01*
G01X-94413Y358504D02*
Y368347D01*
X-95889Y366379D01*
G01Y358504D02*
X-92937D01*
G01X-86908Y366707D02*
X-86169Y367691D01*
X-85308Y368183D01*
X-84324Y368347D01*
X-83094Y368019D01*
X-82232Y367199D01*
X-81986Y366215D01*
X-82109Y365230D01*
X-82602Y364410D01*
X-85062Y362769D01*
X-86169Y361621D01*
X-86908Y359980D01*
X-87154Y358504D01*
X-81986D01*
G01X-73251D02*
Y368347D01*
X-77803Y361293D01*
X-71651D01*
G01X-64884Y358176D02*
X-65130Y358340D01*
Y358668D01*
X-64884Y358832D01*
X-64638Y358668D01*
Y358340D01*
X-64884Y358176D01*
G01X-55041Y368347D02*
X-56025Y368019D01*
X-56763Y367199D01*
X-57256Y366215D01*
X-57625Y364902D01*
X-57748Y363425D01*
X-57625Y361949D01*
X-57256Y360636D01*
X-56763Y359652D01*
X-56025Y358832D01*
X-55041Y358504D01*
X-54057Y358832D01*
X-53319Y359652D01*
X-52826Y360636D01*
X-52457Y361949D01*
X-52334Y363425D01*
X-52457Y364902D01*
X-52826Y366215D01*
X-53319Y367199D01*
X-54057Y368019D01*
X-55041Y368347D01*
G01X-45444Y358504D02*
X-45198Y360636D01*
X-44829Y362441D01*
X-44337Y364082D01*
X-43722Y365886D01*
X-42737Y368347D01*
X-47659D01*
G01X-94413Y378189D02*
Y388032D01*
X-95889Y386064D01*
G01Y378189D02*
X-92937D01*
G01X-86908Y386392D02*
X-86169Y387376D01*
X-85308Y387868D01*
X-84324Y388032D01*
X-83094Y387704D01*
X-82232Y386884D01*
X-81986Y385900D01*
X-82109Y384915D01*
X-82602Y384095D01*
X-85062Y382454D01*
X-86169Y381306D01*
X-86908Y379665D01*
X-87154Y378189D01*
X-81986D01*
G01X-76819Y379337D02*
X-75957Y378517D01*
X-74973Y378189D01*
X-73989Y378517D01*
X-73128Y379501D01*
X-72512Y380978D01*
X-72266Y382454D01*
Y384259D01*
X-72512Y385735D01*
X-73128Y387048D01*
X-73866Y387704D01*
X-74727Y388032D01*
X-75711Y387704D01*
X-76449Y387048D01*
X-76942Y386064D01*
X-77188Y384751D01*
X-76942Y383603D01*
X-76326Y382454D01*
X-75588Y381798D01*
X-74727Y381634D01*
X-73743Y381962D01*
X-73005Y382782D01*
X-72266Y384259D01*
G01X-64884Y377861D02*
X-65130Y378025D01*
Y378353D01*
X-64884Y378517D01*
X-64638Y378353D01*
Y378025D01*
X-64884Y377861D01*
G01X-55041Y388032D02*
X-56025Y387704D01*
X-56763Y386884D01*
X-57256Y385900D01*
X-57625Y384587D01*
X-57748Y383110D01*
X-57625Y381634D01*
X-57256Y380321D01*
X-56763Y379337D01*
X-56025Y378517D01*
X-55041Y378189D01*
X-54057Y378517D01*
X-53319Y379337D01*
X-52826Y380321D01*
X-52457Y381634D01*
X-52334Y383110D01*
X-52457Y384587D01*
X-52826Y385900D01*
X-53319Y386884D01*
X-54057Y387704D01*
X-55041Y388032D01*
G01X-45444Y378189D02*
X-45198Y380321D01*
X-44829Y382126D01*
X-44337Y383767D01*
X-43722Y385571D01*
X-42737Y388032D01*
X-47659D01*
G01X-81960Y-740940D02*
Y-758263D01*
G01X-74727Y-120117D02*
X-75711Y-120445D01*
X-76449Y-121265D01*
X-76942Y-122249D01*
X-77311Y-123562D01*
X-77434Y-125039D01*
X-77311Y-126515D01*
X-76942Y-127828D01*
X-76449Y-128812D01*
X-75711Y-129632D01*
X-74727Y-129960D01*
X-73743Y-129632D01*
X-73005Y-128812D01*
X-72512Y-127828D01*
X-72143Y-126515D01*
X-72020Y-125039D01*
X-72143Y-123562D01*
X-72512Y-122249D01*
X-73005Y-121265D01*
X-73743Y-120445D01*
X-74727Y-120117D01*
G01X-64884Y-130288D02*
X-65130Y-130124D01*
Y-129796D01*
X-64884Y-129632D01*
X-64638Y-129796D01*
Y-130124D01*
X-64884Y-130288D01*
G01X-55041Y-120117D02*
X-56025Y-120445D01*
X-56763Y-121265D01*
X-57256Y-122249D01*
X-57625Y-123562D01*
X-57748Y-125039D01*
X-57625Y-126515D01*
X-57256Y-127828D01*
X-56763Y-128812D01*
X-56025Y-129632D01*
X-55041Y-129960D01*
X-54057Y-129632D01*
X-53319Y-128812D01*
X-52826Y-127828D01*
X-52457Y-126515D01*
X-52334Y-125039D01*
X-52457Y-123562D01*
X-52826Y-122249D01*
X-53319Y-121265D01*
X-54057Y-120445D01*
X-55041Y-120117D01*
G01X-45198D02*
X-46182Y-120445D01*
X-46920Y-121265D01*
X-47413Y-122249D01*
X-47782Y-123562D01*
X-47905Y-125039D01*
X-47782Y-126515D01*
X-47413Y-127828D01*
X-46920Y-128812D01*
X-46182Y-129632D01*
X-45198Y-129960D01*
X-44214Y-129632D01*
X-43476Y-128812D01*
X-42983Y-127828D01*
X-42614Y-126515D01*
X-42491Y-125039D01*
X-42614Y-123562D01*
X-42983Y-122249D01*
X-43476Y-121265D01*
X-44214Y-120445D01*
X-45198Y-120117D01*
G01X-78255Y-108799D02*
X-77517Y-109619D01*
X-76655Y-110111D01*
X-75548Y-110275D01*
X-74441Y-109947D01*
X-73580Y-109291D01*
X-72964Y-108143D01*
X-72841Y-106830D01*
X-73087Y-105518D01*
X-73703Y-104697D01*
X-74564Y-104041D01*
X-75425Y-103877D01*
X-76286Y-104041D01*
X-77393Y-104697D01*
X-77024Y-100432D01*
X-73703D01*
G01X-65705Y-110603D02*
X-65951Y-110439D01*
Y-110111D01*
X-65705Y-109947D01*
X-65459Y-110111D01*
Y-110439D01*
X-65705Y-110603D01*
G01X-55862Y-100432D02*
X-56846Y-100760D01*
X-57584Y-101580D01*
X-58077Y-102564D01*
X-58446Y-103877D01*
X-58569Y-105354D01*
X-58446Y-106830D01*
X-58077Y-108143D01*
X-57584Y-109127D01*
X-56846Y-109947D01*
X-55862Y-110275D01*
X-54878Y-109947D01*
X-54140Y-109127D01*
X-53647Y-108143D01*
X-53278Y-106830D01*
X-53155Y-105354D01*
X-53278Y-103877D01*
X-53647Y-102564D01*
X-54140Y-101580D01*
X-54878Y-100760D01*
X-55862Y-100432D01*
G01X-46019D02*
X-47003Y-100760D01*
X-47741Y-101580D01*
X-48234Y-102564D01*
X-48603Y-103877D01*
X-48726Y-105354D01*
X-48603Y-106830D01*
X-48234Y-108143D01*
X-47741Y-109127D01*
X-47003Y-109947D01*
X-46019Y-110275D01*
X-45035Y-109947D01*
X-44297Y-109127D01*
X-43804Y-108143D01*
X-43435Y-106830D01*
X-43312Y-105354D01*
X-43435Y-103877D01*
X-43804Y-102564D01*
X-44297Y-101580D01*
X-45035Y-100760D01*
X-46019Y-100432D01*
G01X-75989Y2520D02*
X-76059Y2496D01*
X-76112Y2437D01*
X-76148Y2366D01*
X-76174Y2272D01*
X-76183Y2165D01*
X-76174Y2059D01*
X-76148Y1965D01*
X-76112Y1894D01*
X-76059Y1835D01*
X-75989Y1811D01*
X-75918Y1835D01*
X-75865Y1894D01*
X-75829Y1965D01*
X-75803Y2059D01*
X-75794Y2165D01*
X-75803Y2272D01*
X-75829Y2366D01*
X-75865Y2437D01*
X-75918Y2496D01*
X-75989Y2520D01*
G01X-75281Y1787D02*
X-75298Y1799D01*
Y1823D01*
X-75281Y1835D01*
X-75263Y1823D01*
Y1799D01*
X-75281Y1787D01*
G01X-74573Y2520D02*
X-74643Y2496D01*
X-74696Y2437D01*
X-74732Y2366D01*
X-74758Y2272D01*
X-74767Y2165D01*
X-74758Y2059D01*
X-74732Y1965D01*
X-74696Y1894D01*
X-74643Y1835D01*
X-74573Y1811D01*
X-74502Y1835D01*
X-74449Y1894D01*
X-74413Y1965D01*
X-74387Y2059D01*
X-74378Y2165D01*
X-74387Y2272D01*
X-74413Y2366D01*
X-74449Y2437D01*
X-74502Y2496D01*
X-74573Y2520D01*
G01X-73865D02*
X-73935Y2496D01*
X-73988Y2437D01*
X-74024Y2366D01*
X-74050Y2272D01*
X-74059Y2165D01*
X-74050Y2059D01*
X-74024Y1965D01*
X-73988Y1894D01*
X-73935Y1835D01*
X-73865Y1811D01*
X-73794Y1835D01*
X-73741Y1894D01*
X-73705Y1965D01*
X-73679Y2059D01*
X-73670Y2165D01*
X-73679Y2272D01*
X-73705Y2366D01*
X-73741Y2437D01*
X-73794Y2496D01*
X-73865Y2520D01*
G01X-73157D02*
X-73227Y2496D01*
X-73280Y2437D01*
X-73316Y2366D01*
X-73342Y2272D01*
X-73351Y2165D01*
X-73342Y2059D01*
X-73316Y1965D01*
X-73280Y1894D01*
X-73227Y1835D01*
X-73157Y1811D01*
X-73086Y1835D01*
X-73033Y1894D01*
X-72997Y1965D01*
X-72971Y2059D01*
X-72962Y2165D01*
X-72971Y2272D01*
X-72997Y2366D01*
X-73033Y2437D01*
X-73086Y2496D01*
X-73157Y2520D01*
G01X-72449D02*
X-72519Y2496D01*
X-72572Y2437D01*
X-72608Y2366D01*
X-72634Y2272D01*
X-72643Y2165D01*
X-72634Y2059D01*
X-72608Y1965D01*
X-72572Y1894D01*
X-72519Y1835D01*
X-72449Y1811D01*
X-72378Y1835D01*
X-72325Y1894D01*
X-72289Y1965D01*
X-72263Y2059D01*
X-72254Y2165D01*
X-72263Y2272D01*
X-72289Y2366D01*
X-72325Y2437D01*
X-72378Y2496D01*
X-72449Y2520D01*
G01X-87482Y254298D02*
X-86620Y253478D01*
X-85636Y253150D01*
X-84652Y253478D01*
X-83791Y254462D01*
X-83175Y255939D01*
X-82929Y257415D01*
Y259220D01*
X-83175Y260696D01*
X-83791Y262009D01*
X-84529Y262665D01*
X-85390Y262993D01*
X-86374Y262665D01*
X-87112Y262009D01*
X-87605Y261025D01*
X-87851Y259712D01*
X-87605Y258564D01*
X-86989Y257415D01*
X-86251Y256759D01*
X-85390Y256595D01*
X-84406Y256923D01*
X-83668Y257743D01*
X-82929Y259220D01*
G01X-75793Y253150D02*
X-75547Y255282D01*
X-75178Y257087D01*
X-74686Y258728D01*
X-74071Y260532D01*
X-73086Y262993D01*
X-78008D01*
G01X-65704Y252822D02*
X-65950Y252986D01*
Y253314D01*
X-65704Y253478D01*
X-65458Y253314D01*
Y252986D01*
X-65704Y252822D01*
G01X-58568Y255118D02*
X-57830Y253970D01*
X-56845Y253314D01*
X-55738Y253150D01*
X-54754Y253314D01*
X-53769Y254134D01*
X-53154Y255118D01*
X-53031Y256103D01*
X-53277Y257251D01*
X-54139Y258071D01*
X-55000Y258400D01*
X-56107D01*
G01X-55000D02*
X-54262Y258892D01*
X-53646Y259712D01*
X-53400Y260696D01*
X-53646Y261681D01*
X-54262Y262501D01*
X-55369Y262993D01*
X-56476Y262829D01*
X-57583Y262173D01*
G01X-46018Y253150D02*
Y262993D01*
X-47494Y261025D01*
G01Y253150D02*
X-44542D01*
G01X-81960Y619690D02*
Y602367D01*
G01X-70970Y2165D02*
X-72387D01*
G01X-69553Y0D02*
X-70970Y2165D01*
G01X2579Y0D02*
X-69553D01*
G01X7627Y-125039D02*
X-47305D01*
G01X7627Y-105354D02*
X-47305D01*
G01X1722Y258071D02*
X-47305D01*
G01X7628Y363425D02*
X-47305D01*
G01X7628Y383110D02*
X-47305D01*
G01X-1Y-113228D02*
Y-117165D01*
G03X7873Y-125039I7874J0D01*
G01X714566D01*
G03X722440Y-117165I0J7874D01*
G01Y-113228D01*
G01X-1D02*
X13591D01*
G01X-1Y-97480D02*
G03X7873Y-105354I7874J0D01*
G01X-1Y-97480D02*
G03X7873Y-105354I7874J0D01*
G01X-1Y-97480D02*
G03X7873Y-105354I7874J0D01*
G01X-1Y-97480D02*
G03X7873Y-105354I7874J0D01*
G01X0Y-97480D02*
G03X7874Y-105354I7874J0D01*
G01X-1Y-97480D02*
Y-20709D01*
G01Y-97480D02*
Y-20709D01*
G01Y-97480D02*
Y-20709D01*
G01Y-97480D02*
Y-20709D01*
G01X0D02*
Y-97480D01*
G01X-2874Y-58499D02*
X-2850Y-58569D01*
X-2791Y-58622D01*
X-2720Y-58658D01*
X-2626Y-58684D01*
X-2519Y-58693D01*
X-2413Y-58684D01*
X-2319Y-58658D01*
X-2248Y-58622D01*
X-2189Y-58569D01*
X-2165Y-58499D01*
X-2189Y-58428D01*
X-2248Y-58375D01*
X-2319Y-58339D01*
X-2413Y-58313D01*
X-2519Y-58304D01*
X-2626Y-58313D01*
X-2720Y-58339D01*
X-2791Y-58375D01*
X-2850Y-58428D01*
X-2874Y-58499D01*
G01X-2141Y-57791D02*
X-2153Y-57808D01*
X-2177D01*
X-2189Y-57791D01*
X-2177Y-57773D01*
X-2153D01*
X-2141Y-57791D01*
G01X-2874Y-57083D02*
X-2850Y-57153D01*
X-2791Y-57206D01*
X-2720Y-57242D01*
X-2626Y-57268D01*
X-2519Y-57277D01*
X-2413Y-57268D01*
X-2319Y-57242D01*
X-2248Y-57206D01*
X-2189Y-57153D01*
X-2165Y-57083D01*
X-2189Y-57012D01*
X-2248Y-56959D01*
X-2319Y-56923D01*
X-2413Y-56897D01*
X-2519Y-56888D01*
X-2626Y-56897D01*
X-2720Y-56923D01*
X-2791Y-56959D01*
X-2850Y-57012D01*
X-2874Y-57083D01*
G01Y-56375D02*
X-2850Y-56445D01*
X-2791Y-56498D01*
X-2720Y-56534D01*
X-2626Y-56560D01*
X-2519Y-56569D01*
X-2413Y-56560D01*
X-2319Y-56534D01*
X-2248Y-56498D01*
X-2189Y-56445D01*
X-2165Y-56375D01*
X-2189Y-56304D01*
X-2248Y-56251D01*
X-2319Y-56215D01*
X-2413Y-56189D01*
X-2519Y-56180D01*
X-2626Y-56189D01*
X-2720Y-56215D01*
X-2791Y-56251D01*
X-2850Y-56304D01*
X-2874Y-56375D01*
G01Y-55667D02*
X-2850Y-55737D01*
X-2791Y-55790D01*
X-2720Y-55826D01*
X-2626Y-55852D01*
X-2519Y-55861D01*
X-2413Y-55852D01*
X-2319Y-55826D01*
X-2248Y-55790D01*
X-2189Y-55737D01*
X-2165Y-55667D01*
X-2189Y-55596D01*
X-2248Y-55543D01*
X-2319Y-55507D01*
X-2413Y-55481D01*
X-2519Y-55472D01*
X-2626Y-55481D01*
X-2720Y-55507D01*
X-2791Y-55543D01*
X-2850Y-55596D01*
X-2874Y-55667D01*
G01Y-54959D02*
X-2850Y-55029D01*
X-2791Y-55082D01*
X-2720Y-55118D01*
X-2626Y-55144D01*
X-2519Y-55153D01*
X-2413Y-55144D01*
X-2319Y-55118D01*
X-2248Y-55082D01*
X-2189Y-55029D01*
X-2165Y-54959D01*
X-2189Y-54888D01*
X-2248Y-54835D01*
X-2319Y-54799D01*
X-2413Y-54773D01*
X-2519Y-54764D01*
X-2626Y-54773D01*
X-2720Y-54799D01*
X-2791Y-54835D01*
X-2850Y-54888D01*
X-2874Y-54959D01*
G01X-2165Y-53126D02*
Y-54543D01*
G01X0Y-51709D02*
X-2165Y-53126D01*
G01X0Y7628D02*
Y-51709D01*
G01X1968Y-18740D02*
G03X-1Y-20709I0J-1969D01*
G01X1968Y-18740D02*
G03X-1Y-20709I0J-1969D01*
G01X1968Y-18740D02*
G03X-1Y-20709I0J-1969D01*
G01X1968Y-18740D02*
G03X-1Y-20709I0J-1969D01*
G01X1968Y-18740D02*
G03X0Y-20709I0J-1968D01*
G01X1968Y-18740D02*
X9842D01*
G01X1968D02*
X9842D01*
G01X1968D02*
X9842D01*
G01X1968D02*
X9842D01*
G01D02*
X1968D01*
G01X-1Y42441D02*
G03X1968Y40472I1969J0D01*
G01X-1Y42441D02*
G03X1968Y40472I1969J0D01*
G01X-1Y42441D02*
G03X1968Y40472I1969J0D01*
G01X-1Y42441D02*
G03X1968Y40472I1969J0D01*
G01X-1Y42441D02*
Y62146D01*
G01Y42441D02*
Y62146D01*
G01X1968Y40472D02*
X9842D01*
G01X1968D02*
X9842D01*
G01X-1Y42441D02*
Y62146D01*
G01Y42441D02*
Y62146D01*
G01X1968Y40472D02*
X9842D01*
G01X1968D02*
X9842D01*
G01X0Y42441D02*
G03X1968Y40473I1968J0D01*
G01X0Y62146D02*
Y42441D01*
G01X1968Y40473D02*
X9842D01*
G01X1968Y64114D02*
G03X-1Y62146I0J-1969D01*
G01X1968Y64114D02*
G03X-1Y62146I0J-1969D01*
G01X1968Y64114D02*
G03X-1Y62146I0J-1969D01*
G01X1968Y64114D02*
G03X-1Y62146I0J-1969D01*
G01D02*
Y74173D01*
G01Y54488D02*
Y62146D01*
G01X6259Y58819D02*
Y60000D01*
G01X6298Y64114D02*
Y54488D01*
G01X10235D02*
X-1D01*
G01Y57598D02*
X10235D01*
G01X-1Y58189D02*
X10235D01*
G01X-1Y58780D02*
X29921D01*
G01X24054Y58819D02*
X6259D01*
G01X24054Y60000D02*
X6259D01*
G01X29921Y60039D02*
X-1D01*
G01Y60630D02*
X29921D01*
G01X-1Y61220D02*
X29921D01*
G01X1968Y64114D02*
G03X0Y62146I0J-1968D01*
G01X2045Y68465D02*
Y76219D01*
G01X1728Y69646D02*
X2045Y68465D01*
G01X6298Y65315D02*
Y64114D01*
G01X2046Y76220D02*
X-1Y74173D01*
G01X1728Y69646D02*
X-1Y68647D01*
G01Y67283D02*
X2045Y68465D01*
G01X29921Y63346D02*
X-1D01*
G01X1968Y64114D02*
X28346D01*
G01X1968D02*
X28346D01*
G01X30155Y65315D02*
X-1D01*
G01X2045Y68465D02*
X26771D01*
G01X-1Y69646D02*
X26771D01*
G01X-1Y72402D02*
X26771D01*
G01X-1Y73583D02*
X26771D01*
G01X17322Y76220D02*
X2046D01*
G01X1968Y64114D02*
X28346D01*
G01X1968D02*
X28346D01*
G01D02*
X1968D01*
G01X1979Y94143D02*
X1968Y94208D01*
G01X2011Y94084D02*
X1979Y94143D01*
G01X2066Y94037D02*
X2011Y94084D01*
G01X3947Y89124D02*
X3936Y89059D01*
G01X3980Y89183D02*
X3947Y89124D01*
G01X4035Y89230D02*
X3980Y89183D01*
G01X3947Y92274D02*
X3936Y92209D01*
G01X3980Y92333D02*
X3947Y92274D01*
G01X4035Y92380D02*
X3980Y92333D01*
G01X3981Y90933D02*
X4035Y90888D01*
G01X3948Y90992D02*
X3981Y90933D01*
G01X3936Y91058D02*
X3948Y90992D01*
G01X3981Y87784D02*
X4035Y87738D01*
G01X3948Y87843D02*
X3981Y87784D01*
G01X3936Y87909D02*
X3948Y87843D01*
G01X2012Y95483D02*
X2066Y95529D01*
G01X1979Y95425D02*
X2012Y95483D01*
G01X1968Y95359D02*
X1979Y95425D01*
G01X2263Y93924D02*
G03X2361Y93898I98J171D01*
G01X2442Y88484D02*
G03X2304Y88428I0J-197D01*
G01Y85430D02*
G03X2442Y85374I138J141D01*
G01X2361Y95669D02*
G03X2263Y95643I0J-197D01*
G01X4232Y90774D02*
G03X4330Y90748I98J171D01*
G01Y92520D02*
G03X4232Y92493I2J-197D01*
G01Y87625D02*
G03X4330Y87598I99J170D01*
G01Y89370D02*
G03X4232Y89344I0J-197D01*
G01X4839Y95363D02*
G03X4774Y95374I-65J-186D01*
G01X5010Y93543D02*
G03X4945Y93532I0J-197D01*
G01X4774Y93484D02*
G03X4839Y93495I0J197D01*
G01X4410Y93484D02*
G03X4272Y93428I0J-197D01*
G01Y90430D02*
G03X4410Y90374I138J141D01*
G01X4839Y90363D02*
G03X4774Y90374I-65J-186D01*
G01X4945Y90326D02*
G03X5010Y90315I65J186D01*
G01X4774Y88484D02*
G03X4915Y88543I0J197D01*
G01Y85315D02*
G03X4774Y85374I-141J-138D01*
G01X4272Y95430D02*
G03X4410Y95374I138J141D01*
G01X4945Y95326D02*
G03X5010Y95315I65J186D01*
G01X-1Y214055D02*
Y84803D01*
G01X1180Y215236D02*
Y83622D01*
G01X1968Y95359D02*
Y94208D01*
G01X2125Y85605D02*
Y88253D01*
G01X2235Y95626D02*
Y93940D01*
G01X2339Y93899D02*
Y95668D01*
G01X2672Y85374D02*
Y88484D01*
G01X2848D02*
Y85374D01*
G01X3936Y91058D02*
Y92209D01*
G01Y87909D02*
Y89059D01*
G01X4094Y95605D02*
Y98253D01*
G01Y90605D02*
Y93253D01*
G01X4203Y89327D02*
Y87641D01*
G01Y92477D02*
Y90791D01*
G01X4308Y90749D02*
Y92518D01*
G01Y87600D02*
Y89369D01*
G01X4641Y93484D02*
Y90374D01*
G01Y98484D02*
Y95374D01*
G01X4817Y95369D02*
Y98489D01*
G01Y90369D02*
Y93489D01*
G01X4272Y93428D02*
X4094Y93253D01*
G01X2304Y88428D02*
X2125Y88253D01*
G01X1180Y83622D02*
X-1Y84803D01*
G01X2125Y85605D02*
X2304Y85430D01*
G01X4094Y90605D02*
X4272Y90430D01*
G01X4094Y95605D02*
X4272Y95430D01*
G01X2263Y95643D02*
X2066Y95529D01*
G01X4232Y92493D02*
X4035Y92380D01*
G01X4232Y89344D02*
X4035Y89230D01*
G01X4232Y87625D02*
X4035Y87738D01*
G01X4232Y90774D02*
X4035Y90888D01*
G01X2066Y94037D02*
X2263Y93924D01*
G01X4839Y93495D02*
X4945Y93532D01*
G01Y90326D02*
X4839Y90363D01*
G01X4945Y95326D02*
X4839Y95363D01*
G01X30128Y83622D02*
X1180D01*
G01X14485Y85315D02*
X4915D01*
G01X4774Y85374D02*
X2442D01*
G01X4330Y87598D02*
X15882D01*
G01X2442Y88484D02*
X4774D01*
G01X4915Y88543D02*
X14485D01*
G01X4330Y89370D02*
X14783D01*
G01X14485Y90315D02*
X5010D01*
G01X4774Y90374D02*
X4410D01*
G01X15882Y90748D02*
X4330D01*
G01Y92520D02*
X14783D01*
G01X4410Y93484D02*
X4774D01*
G01X5010Y93543D02*
X14485D01*
G01X15964Y93898D02*
X2361D01*
G01X14485Y95315D02*
X5010D01*
G01X4774Y95374D02*
X4410D01*
G01X2361Y95669D02*
X14783D01*
G01X1979Y103592D02*
X1968Y103657D01*
G01X2011Y103533D02*
X1979Y103592D01*
G01X2066Y103486D02*
X2011Y103533D01*
G01X3947Y98573D02*
X3936Y98508D01*
G01X3980Y98632D02*
X3947Y98573D01*
G01X4035Y98679D02*
X3980Y98632D01*
G01X3947Y101723D02*
X3936Y101658D01*
G01X3980Y101782D02*
X3947Y101723D01*
G01X4035Y101828D02*
X3980Y101782D01*
G01X3947Y108022D02*
X3936Y107957D01*
G01X3980Y108081D02*
X3947Y108022D01*
G01X4035Y108128D02*
X3980Y108081D01*
G01X3947Y111172D02*
X3936Y111107D01*
G01X3980Y111231D02*
X3947Y111172D01*
G01X4035Y111277D02*
X3980Y111231D01*
G01X3981Y109831D02*
X4035Y109785D01*
G01X3948Y109890D02*
X3981Y109831D01*
G01X3936Y109956D02*
X3948Y109890D01*
G01X3981Y106682D02*
X4035Y106636D01*
G01X3948Y106740D02*
X3981Y106682D01*
G01X3936Y106806D02*
X3948Y106740D01*
G01X3981Y100382D02*
X4035Y100337D01*
G01X3948Y100441D02*
X3981Y100382D01*
G01X3936Y100507D02*
X3948Y100441D01*
G01X3981Y97233D02*
X4035Y97187D01*
G01X3948Y97291D02*
X3981Y97233D01*
G01X3936Y97358D02*
X3948Y97291D01*
G01X2012Y104932D02*
X2066Y104978D01*
G01X1979Y104874D02*
X2012Y104932D01*
G01X1968Y104808D02*
X1979Y104874D01*
G01X2263Y103373D02*
G03X2361Y103346I100J170D01*
G01Y105118D02*
G03X2263Y105092I0J-197D01*
G01X2442Y103484D02*
G03X2304Y103428I0J-197D01*
G01Y100430D02*
G03X2442Y100374I138J141D01*
G01X4232Y100223D02*
G03X4330Y100197I98J171D01*
G01Y101969D02*
G03X4232Y101942I2J-197D01*
G01Y97074D02*
G03X4330Y97047I99J170D01*
G01Y98819D02*
G03X4232Y98793I0J-197D01*
G01X4839Y105363D02*
G03X4774Y105374I-65J-186D01*
G01Y103484D02*
G03X4915Y103543I0J197D01*
G01Y100315D02*
G03X4774Y100374I-141J-138D01*
G01X5010Y98543D02*
G03X4945Y98532I0J-197D01*
G01X4774Y98484D02*
G03X4839Y98495I0J197D01*
G01X4410Y98484D02*
G03X4272Y98428I0J-197D01*
G01X4232Y109672D02*
G03X4330Y109646I98J171D01*
G01Y111417D02*
G03X4232Y111391I0J-197D01*
G01Y106522D02*
G03X4330Y106496I98J171D01*
G01Y108268D02*
G03X4232Y108241I2J-197D01*
G01X4272Y110430D02*
G03X4410Y110374I138J141D01*
G01X4839Y110363D02*
G03X4774Y110374I-65J-186D01*
G01X4945Y110326D02*
G03X5010Y110315I65J186D01*
G01Y108543D02*
G03X4945Y108532I0J-197D01*
G01X4774Y108484D02*
G03X4839Y108495I0J197D01*
G01X4410Y108484D02*
G03X4272Y108428I0J-197D01*
G01Y105430D02*
G03X4410Y105374I138J141D01*
G01X4945Y105326D02*
G03X5010Y105315I65J186D01*
G01X1968Y104808D02*
Y103657D01*
G01X2125Y100605D02*
Y103253D01*
G01X2235Y105075D02*
Y103389D01*
G01X2339Y103348D02*
Y105117D01*
G01X2672Y100374D02*
Y103484D01*
G01X2848D02*
Y100374D01*
G01X3936Y109956D02*
Y111107D01*
G01Y106806D02*
Y107957D01*
G01Y100507D02*
Y101658D01*
G01Y97358D02*
Y98508D01*
G01X4094Y110605D02*
Y113253D01*
G01Y105605D02*
Y108253D01*
G01X4203Y98776D02*
Y97090D01*
G01Y101926D02*
Y100239D01*
G01Y108225D02*
Y106539D01*
G01Y111374D02*
Y109688D01*
G01X4308Y109647D02*
Y111416D01*
G01Y106497D02*
Y108266D01*
G01Y100198D02*
Y101967D01*
G01Y97048D02*
Y98817D01*
G01X4641Y108484D02*
Y105374D01*
G01Y113484D02*
Y110374D01*
G01X4817Y110369D02*
Y113489D01*
G01Y105369D02*
Y108489D01*
G01X4272Y108428D02*
X4094Y108253D01*
G01X2304Y103428D02*
X2125Y103253D01*
G01X4272Y98428D02*
X4094Y98253D01*
G01X2125Y100605D02*
X2304Y100430D01*
G01X4232Y111391D02*
X4035Y111277D01*
G01X4232Y108241D02*
X4035Y108128D01*
G01X2263Y105092D02*
X2066Y104978D01*
G01X4232Y101942D02*
X4035Y101828D01*
G01X4232Y98793D02*
X4035Y98679D01*
G01X4094Y105605D02*
X4272Y105430D01*
G01X4094Y110605D02*
X4272Y110430D01*
G01X4839Y108495D02*
X4945Y108532D01*
G01X4839Y98495D02*
X4945Y98532D01*
G01X4232Y97074D02*
X4035Y97187D01*
G01X4232Y100223D02*
X4035Y100337D01*
G01X2066Y103486D02*
X2263Y103373D01*
G01X4232Y106522D02*
X4035Y106636D01*
G01X4232Y109672D02*
X4035Y109785D01*
G01X4945Y105326D02*
X4839Y105363D01*
G01X4945Y110326D02*
X4839Y110363D01*
G01X15882Y97047D02*
X4330D01*
G01X4410Y98484D02*
X4774D01*
G01X5010Y98543D02*
X14485D01*
G01X4330Y98819D02*
X14783D01*
G01X15882Y100197D02*
X4330D01*
G01X14485Y100315D02*
X4915D01*
G01X4774Y100374D02*
X2442D01*
G01X4330Y101969D02*
X14783D01*
G01X15964Y103346D02*
X2361D01*
G01X2442Y103484D02*
X4774D01*
G01X4915Y103543D02*
X14485D01*
G01X2361Y105118D02*
X14783D01*
G01X14485Y105315D02*
X5010D01*
G01X4774Y105374D02*
X4410D01*
G01X15882Y106496D02*
X4330D01*
G01Y108268D02*
X14783D01*
G01X4410Y108484D02*
X4774D01*
G01X5010Y108543D02*
X14485D01*
G01X15882Y109646D02*
X4330D01*
G01X14485Y110315D02*
X5010D01*
G01X4774Y110374D02*
X4410D01*
G01X4330Y111417D02*
X14783D01*
G01X2011Y128730D02*
X1979Y128789D01*
G01X2066Y128683D02*
X2011Y128730D01*
G01X1979Y119340D02*
X1968Y119405D01*
G01X2011Y119281D02*
X1979Y119340D01*
G01X2066Y119234D02*
X2011Y119281D01*
G01X1979Y113041D02*
X1968Y113106D01*
G01X2011Y112982D02*
X1979Y113041D01*
G01X2066Y112935D02*
X2011Y112982D01*
G01X3947Y117471D02*
X3936Y117406D01*
G01X3980Y117530D02*
X3947Y117471D01*
G01X4035Y117576D02*
X3980Y117530D01*
G01X3947Y123770D02*
X3936Y123705D01*
G01X3980Y123829D02*
X3947Y123770D01*
G01X4035Y123876D02*
X3980Y123829D01*
G01X3947Y126920D02*
X3936Y126855D01*
G01X3980Y126979D02*
X3947Y126920D01*
G01X4035Y127025D02*
X3980Y126979D01*
G01X3948Y122296D02*
X3936Y122229D01*
G01X3982Y122355D02*
X3948Y122296D01*
G01X4035Y122399D02*
X3982Y122355D01*
G01X3948Y125446D02*
X3936Y125378D01*
G01X3982Y125505D02*
X3948Y125446D01*
G01X4035Y125549D02*
X3982Y125505D01*
G01X1980Y128595D02*
X1968Y128528D01*
G01X2014Y128654D02*
X1980Y128595D01*
G01X2066Y128698D02*
X2014Y128654D01*
G01X3982Y124101D02*
X4035Y124057D01*
G01X3948Y124160D02*
X3982Y124101D01*
G01X3936Y124228D02*
X3948Y124160D01*
G01X3982Y120952D02*
X4035Y120908D01*
G01X3948Y121011D02*
X3982Y120952D01*
G01X3936Y121078D02*
X3948Y121011D01*
G01X2014Y127251D02*
X2066Y127207D01*
G01X1980Y127310D02*
X2014Y127251D01*
G01X1968Y127377D02*
X1980Y127310D01*
G01X3981Y125579D02*
X4035Y125533D01*
G01X3948Y125638D02*
X3981Y125579D01*
G01X3936Y125704D02*
X3948Y125638D01*
G01X3981Y122430D02*
X4035Y122384D01*
G01X3948Y122488D02*
X3981Y122430D01*
G01X3936Y122554D02*
X3948Y122488D01*
G01X3981Y116130D02*
X4035Y116085D01*
G01X3948Y116189D02*
X3981Y116130D01*
G01X3936Y116255D02*
X3948Y116189D01*
G01X2012Y114381D02*
X2066Y114427D01*
G01X1979Y114322D02*
X2012Y114381D01*
G01X1968Y114256D02*
X1979Y114322D01*
G01X2012Y120680D02*
X2066Y120726D01*
G01X1979Y120622D02*
X2012Y120680D01*
G01X1968Y120556D02*
X1979Y120622D01*
G01X2263Y112822D02*
G03X2361Y112795I99J170D01*
G01Y114567D02*
G03X2263Y114541I0J-197D01*
G01Y119121D02*
G03X2361Y119095I98J171D01*
G01Y120866D02*
G03X2263Y120840I0J-197D01*
G01X2442Y118484D02*
G03X2304Y118428I0J-197D01*
G01Y115430D02*
G03X2442Y115374I138J141D01*
G01X4915Y115315D02*
G03X4774Y115374I-141J-138D01*
G01X5010Y113543D02*
G03X4945Y113532I0J-197D01*
G01X4774Y113484D02*
G03X4839Y113495I0J197D01*
G01X4410Y113484D02*
G03X4272Y113428I0J-197D01*
G01X4330Y124016D02*
G03X4232Y123989I2J-197D01*
G01Y122270D02*
G03X4330Y122244I98J171D01*
G01X4232Y115971D02*
G03X4330Y115945I98J171D01*
G01Y117717D02*
G03X4232Y117690I2J-197D01*
G01X4330Y125689D02*
G03X4232Y125663I0J-197D01*
G01Y123944D02*
G03X4330Y123917I99J170D01*
G01Y122539D02*
G03X4232Y122513I0J-197D01*
G01Y120794D02*
G03X4330Y120768I98J171D01*
G01X4774Y118484D02*
G03X4915Y118543I0J197D01*
G01X2263Y128570D02*
G03X2361Y128543I99J170D01*
G01X2263Y127093D02*
G03X2361Y127067I98J171D01*
G01X4330Y127165D02*
G03X4232Y127139I0J-197D01*
G01Y125420D02*
G03X4330Y125394I98J171D01*
G01X1574Y119882D02*
Y138976D01*
G01X1968Y114256D02*
Y113106D01*
G01Y120556D02*
Y119405D01*
G01Y127377D02*
Y128528D01*
G01X2125Y115605D02*
Y118253D01*
G01X2235Y114524D02*
Y112838D01*
G01Y120823D02*
Y119137D01*
G01Y130272D02*
Y128586D01*
G01D02*
Y127109D01*
G01X2339Y128545D02*
Y130313D01*
G01Y127068D02*
Y128545D01*
G01Y119096D02*
Y120865D01*
G01Y112796D02*
Y114565D01*
G01X2672Y115374D02*
Y118484D01*
G01X2848D02*
Y115374D01*
G01X3936Y125704D02*
Y126855D01*
G01Y122554D02*
Y123705D01*
G01Y124228D02*
Y125378D01*
G01Y121078D02*
Y122229D01*
G01Y116255D02*
Y117406D01*
G01X4203Y117674D02*
Y115987D01*
G01Y123973D02*
Y122287D01*
G01Y127122D02*
Y125436D01*
G01Y123973D02*
Y125436D01*
G01Y120810D02*
Y122287D01*
G01X4308Y122245D02*
Y120769D01*
G01Y125395D02*
Y124014D01*
G01Y125395D02*
Y127164D01*
G01Y122245D02*
Y124014D01*
G01Y115946D02*
Y117715D01*
G01X2304Y118428D02*
X2125Y118253D01*
G01X4272Y113428D02*
X4094Y113253D01*
G01X2263Y128812D02*
X2066Y128698D01*
G01X4232Y127139D02*
X4035Y127025D01*
G01X4232Y125663D02*
X4035Y125549D01*
G01X4232Y123989D02*
X4035Y123876D01*
G01X4232Y122513D02*
X4035Y122399D01*
G01X2263Y120840D02*
X2066Y120726D01*
G01X4232Y117690D02*
X4035Y117576D01*
G01X2263Y114541D02*
X2066Y114427D01*
G01X-1Y121457D02*
X1574Y119882D01*
G01X2125Y115605D02*
X2304Y115430D01*
G01X4839Y113495D02*
X4945Y113532D01*
G01X2066Y112935D02*
X2263Y112822D01*
G01X4232Y115971D02*
X4035Y116085D01*
G01X2066Y119234D02*
X2263Y119121D01*
G01X4035Y120908D02*
X4232Y120794D01*
G01Y122270D02*
X4035Y122384D01*
G01Y124057D02*
X4232Y123944D01*
G01Y125420D02*
X4035Y125533D01*
G01X2066Y127207D02*
X2263Y127093D01*
G01X2066Y128683D02*
X2263Y128570D01*
G01X15964Y112795D02*
X2361D01*
G01X4410Y113484D02*
X4774D01*
G01X5010Y113543D02*
X14485D01*
G01X2361Y114567D02*
X14783D01*
G01X14485Y115315D02*
X4915D01*
G01X4774Y115374D02*
X2442D01*
G01X15882Y115945D02*
X4330D01*
G01Y117717D02*
X14783D01*
G01X2442Y118484D02*
X4774D01*
G01X4915Y118543D02*
X14485D01*
G01X15964Y119095D02*
X2361D01*
G01X19291Y119882D02*
X1574D01*
G01X19238Y120768D02*
X4330D01*
G01X2361Y120866D02*
X14783D01*
G01X15882Y122244D02*
X4330D01*
G01Y122539D02*
X19238D01*
G01Y123917D02*
X4330D01*
G01Y124016D02*
X14783D01*
G01X15882Y125394D02*
X4330D01*
G01Y125689D02*
X19238D01*
G01Y127067D02*
X2361D01*
G01X4330Y127165D02*
X14783D01*
G01X15964Y128543D02*
X2361D01*
G01X1979Y144537D02*
X1968Y144602D01*
G01X2011Y144478D02*
X1979Y144537D01*
G01X2066Y144431D02*
X2011Y144478D01*
G01X1979Y138237D02*
X1968Y138302D01*
G01X2011Y138179D02*
X1979Y138237D01*
G01X2066Y138132D02*
X2011Y138179D01*
G01X1979Y128789D02*
X1968Y128854D01*
G01X3948Y131745D02*
X3936Y131678D01*
G01X3982Y131804D02*
X3948Y131745D01*
G01X4035Y131848D02*
X3982Y131804D01*
G01X3947Y133219D02*
X3936Y133154D01*
G01X3980Y133278D02*
X3947Y133219D01*
G01X4035Y133324D02*
X3980Y133278D01*
G01X3947Y136369D02*
X3936Y136304D01*
G01X3980Y136428D02*
X3947Y136369D01*
G01X4035Y136474D02*
X3980Y136428D01*
G01X3947Y142668D02*
X3936Y142603D01*
G01X3980Y142727D02*
X3947Y142668D01*
G01X4035Y142773D02*
X3980Y142727D01*
G01X3948Y134895D02*
X3936Y134827D01*
G01X3982Y134954D02*
X3948Y134895D01*
G01X4035Y134998D02*
X3982Y134954D01*
G01X1980Y138044D02*
X1968Y137977D01*
G01X2014Y138103D02*
X1980Y138044D01*
G01X2066Y138147D02*
X2014Y138103D01*
G01X3982Y133550D02*
X4035Y133506D01*
G01X3948Y133609D02*
X3982Y133550D01*
G01X3936Y133676D02*
X3948Y133609D01*
G01X3982Y130400D02*
X4035Y130356D01*
G01X3948Y130459D02*
X3982Y130400D01*
G01X3936Y130527D02*
X3948Y130459D01*
G01X2014Y136700D02*
X2066Y136656D01*
G01X1980Y136759D02*
X2014Y136700D01*
G01X1968Y136826D02*
X1980Y136759D01*
G01X3981Y141327D02*
X4035Y141282D01*
G01X3948Y141386D02*
X3981Y141327D01*
G01X3936Y141452D02*
X3948Y141386D01*
G01X3981Y135028D02*
X4035Y134982D01*
G01X3948Y135087D02*
X3981Y135028D01*
G01X3936Y135153D02*
X3948Y135087D01*
G01X3981Y131878D02*
X4035Y131833D01*
G01X3948Y131937D02*
X3981Y131878D01*
G01X3936Y132003D02*
X3948Y131937D01*
G01X2012Y130129D02*
X2066Y130175D01*
G01X1979Y130070D02*
X2012Y130129D01*
G01X1968Y130004D02*
X1979Y130070D01*
G01X2012Y139578D02*
X2066Y139624D01*
G01X1979Y139519D02*
X2012Y139578D01*
G01X1968Y139453D02*
X1979Y139519D01*
G01X2361Y130315D02*
G03X2263Y130289I0J-197D01*
G01X2361Y128839D02*
G03X2263Y128812I2J-197D01*
G01X2361Y139764D02*
G03X2263Y139737I2J-197D01*
G01Y138019D02*
G03X2361Y137992I99J170D01*
G01X2263Y144318D02*
G03X2361Y144291I99J170D01*
G01Y138287D02*
G03X2263Y138261I0J-197D01*
G01Y136542D02*
G03X2361Y136516I98J171D01*
G01X4330Y133465D02*
G03X4232Y133438I2J-197D01*
G01Y131719D02*
G03X4330Y131693I98J171D01*
G01X4232Y134869D02*
G03X4330Y134843I98J170D01*
G01Y135138D02*
G03X4232Y135111I1J-197D01*
G01Y133393D02*
G03X4330Y133366I99J169D01*
G01Y131988D02*
G03X4232Y131962I0J-197D01*
G01Y130243D02*
G03X4330Y130217I98J170D01*
G01Y136614D02*
G03X4232Y136588I0J-197D01*
G01X4330Y142913D02*
G03X4232Y142887I0J-197D01*
G01Y141168D02*
G03X4330Y141142I98J171D01*
G01X5010Y143543D02*
G03X4945Y143532I0J-197D01*
G01X4774Y143484D02*
G03X4839Y143495I0J197D01*
G01X4410Y143484D02*
G03X4272Y143428I0J-197D01*
G01Y140430D02*
G03X4410Y140374I138J141D01*
G01X4839Y140363D02*
G03X4774Y140374I-65J-186D01*
G01X4945Y140326D02*
G03X5010Y140315I65J186D01*
G01X1968Y130004D02*
Y128854D01*
G01Y139453D02*
Y138302D01*
G01Y145752D02*
Y144602D01*
G01Y136826D02*
Y137977D01*
G01X2235Y139721D02*
Y138035D01*
G01D02*
Y136558D01*
G01Y146020D02*
Y144334D01*
G01X2339Y137993D02*
Y136517D01*
G01Y144293D02*
Y146061D01*
G01Y137993D02*
Y139762D01*
G01X3936Y141452D02*
Y142603D01*
G01Y135153D02*
Y136304D01*
G01Y132003D02*
Y133154D01*
G01Y133676D02*
Y134827D01*
G01Y130527D02*
Y131678D01*
G01X4094Y140605D02*
Y143253D01*
G01X4203Y133422D02*
Y131735D01*
G01Y136571D02*
Y134885D01*
G01Y142870D02*
Y141184D01*
G01Y133422D02*
Y134885D01*
G01Y130259D02*
Y131735D01*
G01X4308Y131694D02*
Y130218D01*
G01Y134844D02*
Y133463D01*
G01Y141143D02*
Y142912D01*
G01Y134844D02*
Y136613D01*
G01Y131694D02*
Y133463D01*
G01X4272Y143428D02*
X4094Y143253D01*
G01X1574Y138976D02*
X-1Y137402D01*
G01X4641Y143484D02*
Y140374D01*
G01X4817Y140369D02*
Y143489D01*
G01X4232Y142887D02*
X4035Y142773D01*
G01X2263Y139737D02*
X2066Y139624D01*
G01X2263Y138261D02*
X2066Y138147D01*
G01X4232Y136588D02*
X4035Y136474D01*
G01X4232Y135111D02*
X4035Y134998D01*
G01X4232Y133438D02*
X4035Y133324D01*
G01X4232Y131962D02*
X4035Y131848D01*
G01X2263Y130289D02*
X2066Y130175D01*
G01X4839Y143495D02*
X4945Y143532D01*
G01X4094Y140605D02*
X4272Y140430D01*
G01X4035Y130356D02*
X4232Y130243D01*
G01Y131719D02*
X4035Y131833D01*
G01Y133506D02*
X4232Y133393D01*
G01Y134869D02*
X4035Y134982D01*
G01X2066Y136656D02*
X2263Y136542D01*
G01X2066Y138132D02*
X2263Y138019D01*
G01X4232Y141168D02*
X4035Y141282D01*
G01X2066Y144431D02*
X2263Y144318D01*
G01X4945Y140326D02*
X4839Y140363D01*
G01X2361Y128839D02*
X19238D01*
G01Y130217D02*
X4330D01*
G01X2361Y130315D02*
X14783D01*
G01X15882Y131693D02*
X4330D01*
G01Y131988D02*
X19238D01*
G01Y133366D02*
X4330D01*
G01Y133465D02*
X14783D01*
G01X15882Y134843D02*
X4330D01*
G01Y135138D02*
X19238D01*
G01Y136516D02*
X2361D01*
G01X4330Y136614D02*
X14783D01*
G01X15964Y137992D02*
X2361D01*
G01Y138287D02*
X19238D01*
G01X1574Y138976D02*
X19291D01*
G01X2361Y139764D02*
X14783D01*
G01X14485Y140315D02*
X5010D01*
G01X4774Y140374D02*
X4410D01*
G01X15882Y141142D02*
X4330D01*
G01Y142913D02*
X14783D01*
G01X4410Y143484D02*
X4774D01*
G01X5010Y143543D02*
X14485D01*
G01X15964Y144291D02*
X2361D01*
G01X1979Y153985D02*
X1968Y154050D01*
G01X2011Y153927D02*
X1979Y153985D01*
G01X2066Y153880D02*
X2011Y153927D01*
G01X3947Y148967D02*
X3936Y148902D01*
G01X3980Y149026D02*
X3947Y148967D01*
G01X4035Y149072D02*
X3980Y149026D01*
G01X3947Y152117D02*
X3936Y152052D01*
G01X3980Y152176D02*
X3947Y152117D01*
G01X4035Y152222D02*
X3980Y152176D01*
G01X3981Y160225D02*
X4035Y160179D01*
G01X3948Y160283D02*
X3981Y160225D01*
G01X3936Y160350D02*
X3948Y160283D01*
G01X3981Y157075D02*
X4035Y157030D01*
G01X3948Y157134D02*
X3981Y157075D01*
G01X3936Y157200D02*
X3948Y157134D01*
G01X3981Y150776D02*
X4035Y150730D01*
G01X3948Y150835D02*
X3981Y150776D01*
G01X3936Y150901D02*
X3948Y150835D01*
G01X3981Y147626D02*
X4035Y147581D01*
G01X3948Y147685D02*
X3981Y147626D01*
G01X3936Y147751D02*
X3948Y147685D01*
G01X2012Y145877D02*
X2066Y145923D01*
G01X1979Y145819D02*
X2012Y145877D01*
G01X1968Y145752D02*
X1979Y145819D01*
G01X2012Y155326D02*
X2066Y155372D01*
G01X1979Y155267D02*
X2012Y155326D01*
G01X1968Y155201D02*
X1979Y155267D01*
G01X3947Y158416D02*
X3936Y158351D01*
G01X3980Y158475D02*
X3947Y158416D01*
G01X4035Y158521D02*
X3980Y158475D01*
G01X3947Y161565D02*
X3936Y161500D01*
G01X3980Y161624D02*
X3947Y161565D01*
G01X4035Y161671D02*
X3980Y161624D01*
G01X2361Y146063D02*
G03X2263Y146037I0J-197D01*
G01X4272Y145430D02*
G03X4410Y145374I138J141D01*
G01X4839Y145363D02*
G03X4774Y145374I-65J-186D01*
G01X4945Y145326D02*
G03X5010Y145315I65J186D01*
G01X2361Y155512D02*
G03X2263Y155485I2J-197D01*
G01Y153767D02*
G03X2361Y153740I99J170D01*
G01X2304Y155430D02*
G03X2442Y155374I138J141D01*
G01Y153484D02*
G03X2304Y153428I0J-197D01*
G01Y150430D02*
G03X2442Y150374I138J141D01*
G01X2304Y160430D02*
G03X2442Y160374I138J141D01*
G01Y158484D02*
G03X2304Y158428I0J-197D01*
G01X4330Y149213D02*
G03X4232Y149186I2J-197D01*
G01Y147467D02*
G03X4330Y147441I98J171D01*
G01Y152362D02*
G03X4232Y152336I0J-197D01*
G01Y150617D02*
G03X4330Y150591I98J170D01*
G01X4232Y156916D02*
G03X4330Y156890I98J171D01*
G01X5010Y148543D02*
G03X4945Y148532I0J-197D01*
G01X4774Y148484D02*
G03X4839Y148495I0J197D01*
G01X4410Y148484D02*
G03X4272Y148428I0J-197D01*
G01X4915Y155315D02*
G03X4774Y155374I-141J-138D01*
G01Y153484D02*
G03X4915Y153543I0J197D01*
G01Y150315D02*
G03X4774Y150374I-141J-138D01*
G01X4330Y158661D02*
G03X4232Y158635I0J-197D01*
G01Y160066D02*
G03X4330Y160039I99J170D01*
G01X4915Y160315D02*
G03X4774Y160374I-141J-138D01*
G01Y158484D02*
G03X4915Y158543I0J197D01*
G01X2304Y158428D02*
X2125Y158253D01*
G01X2304Y153428D02*
X2125Y153253D01*
G01X4272Y148428D02*
X4094Y148253D01*
G01X1968Y155201D02*
Y154050D01*
G01X2125Y160605D02*
Y163253D01*
G01Y155605D02*
Y158253D01*
G01Y150605D02*
Y153253D01*
G01X2235Y155469D02*
Y153783D01*
G01X2339Y153741D02*
Y155510D01*
G01X2672Y153484D02*
Y150374D01*
G01Y158484D02*
Y155374D01*
G01Y163484D02*
Y160374D01*
G01X2848Y153484D02*
Y150374D01*
G01Y158484D02*
Y155374D01*
G01Y163484D02*
Y160374D01*
G01X3936Y160350D02*
Y161500D01*
G01Y157200D02*
Y158351D01*
G01Y150901D02*
Y152052D01*
G01Y147751D02*
Y148902D01*
G01X4094Y145605D02*
Y148253D01*
G01X4203Y149170D02*
Y147483D01*
G01Y152319D02*
Y150633D01*
G01Y158619D02*
Y156932D01*
G01Y161768D02*
Y160082D01*
G01X4308Y160041D02*
Y161809D01*
G01Y156891D02*
Y158660D01*
G01Y150592D02*
Y152361D01*
G01Y147442D02*
Y149211D01*
G01X4232Y161785D02*
X4035Y161671D01*
G01X4232Y158635D02*
X4035Y158521D01*
G01X2263Y155485D02*
X2066Y155372D01*
G01X4641Y148484D02*
Y145374D01*
G01X4817Y145369D02*
Y148489D01*
G01X4232Y152336D02*
X4035Y152222D01*
G01X4232Y149186D02*
X4035Y149072D01*
G01X2263Y146037D02*
X2066Y145923D01*
G01X4839Y148495D02*
X4945Y148532D01*
G01X4094Y145605D02*
X4272Y145430D01*
G01X2125Y150605D02*
X2304Y150430D01*
G01X2125Y155605D02*
X2304Y155430D01*
G01X2125Y160605D02*
X2304Y160430D01*
G01X4232Y147467D02*
X4035Y147581D01*
G01X4232Y150617D02*
X4035Y150730D01*
G01X2066Y153880D02*
X2263Y153767D01*
G01X4232Y156916D02*
X4035Y157030D01*
G01X4232Y160066D02*
X4035Y160179D01*
G01X4945Y145326D02*
X4839Y145363D01*
G01X14485Y145315D02*
X5010D01*
G01X4774Y145374D02*
X4410D01*
G01X2361Y146063D02*
X14783D01*
G01X15882Y147441D02*
X4330D01*
G01X4410Y148484D02*
X4774D01*
G01X5010Y148543D02*
X14485D01*
G01X4330Y149213D02*
X14783D01*
G01X14485Y150315D02*
X4915D01*
G01X4774Y150374D02*
X2442D01*
G01X15882Y150591D02*
X4330D01*
G01Y152362D02*
X14783D01*
G01X2442Y153484D02*
X4774D01*
G01X4915Y153543D02*
X14485D01*
G01X15964Y153740D02*
X2361D01*
G01X14485Y155315D02*
X4915D01*
G01X4774Y155374D02*
X2442D01*
G01X2361Y155512D02*
X14783D01*
G01X15882Y156890D02*
X4330D01*
G01X2442Y158484D02*
X4774D01*
G01X4915Y158543D02*
X14485D01*
G01X4330Y158661D02*
X14783D01*
G01X15882Y160039D02*
X4330D01*
G01X14485Y160315D02*
X4915D01*
G01X4774Y160374D02*
X2442D01*
G01X1979Y172883D02*
X1968Y172948D01*
G01X2011Y172824D02*
X1979Y172883D01*
G01X2066Y172778D02*
X2011Y172824D01*
G01X1979Y163434D02*
X1968Y163499D01*
G01X2011Y163376D02*
X1979Y163434D01*
G01X2066Y163329D02*
X2011Y163376D01*
G01X3981Y175973D02*
X4035Y175927D01*
G01X3948Y176032D02*
X3981Y175973D01*
G01X3936Y176098D02*
X3948Y176032D01*
G01X3981Y169674D02*
X4035Y169628D01*
G01X3948Y169732D02*
X3981Y169674D01*
G01X3936Y169798D02*
X3948Y169732D01*
G01X3981Y166524D02*
X4035Y166478D01*
G01X3948Y166583D02*
X3981Y166524D01*
G01X3936Y166649D02*
X3948Y166583D01*
G01X2012Y164775D02*
X2066Y164820D01*
G01X1979Y164716D02*
X2012Y164775D01*
G01X1968Y164650D02*
X1979Y164716D01*
G01X2012Y174224D02*
X2066Y174269D01*
G01X1979Y174165D02*
X2012Y174224D01*
G01X1968Y174099D02*
X1979Y174165D01*
G01X3947Y167865D02*
X3936Y167800D01*
G01X3980Y167924D02*
X3947Y167865D01*
G01X4035Y167970D02*
X3980Y167924D01*
G01X3947Y171014D02*
X3936Y170949D01*
G01X3980Y171073D02*
X3947Y171014D01*
G01X4035Y171120D02*
X3980Y171073D01*
G01X3947Y177313D02*
X3936Y177248D01*
G01X3980Y177372D02*
X3947Y177313D01*
G01X4035Y177419D02*
X3980Y177372D01*
G01X2361Y164961D02*
G03X2263Y164934I2J-197D01*
G01Y163215D02*
G03X2361Y163189I98J171D01*
G01X2442Y168484D02*
G03X2304Y168428I0J-197D01*
G01Y165430D02*
G03X2442Y165374I138J141D01*
G01Y163484D02*
G03X2304Y163428I0J-197D01*
G01X4330Y161811D02*
G03X4232Y161785I0J-197D01*
G01X4330Y168110D02*
G03X4232Y168084I0J-197D01*
G01Y166365D02*
G03X4330Y166339I98J171D01*
G01X4774Y168484D02*
G03X4915Y168543I0J197D01*
G01Y165315D02*
G03X4774Y165374I-141J-138D01*
G01Y163484D02*
G03X4915Y163543I0J197D01*
G01X4330Y171260D02*
G03X4232Y171233I1J-197D01*
G01Y169515D02*
G03X4330Y169488I99J170D01*
G01X2361Y174409D02*
G03X2263Y174383I0J-197D01*
G01Y172664D02*
G03X2361Y172638I98J171D01*
G01X4330Y177559D02*
G03X4232Y177533I0J-197D01*
G01Y175814D02*
G03X4330Y175787I99J170D01*
G01X4272Y175430D02*
G03X4410Y175374I138J141D01*
G01X4839Y175363D02*
G03X4774Y175374I-65J-186D01*
G01X4945Y175326D02*
G03X5010Y175315I65J186D01*
G01X4774Y173484D02*
G03X4915Y173543I0J197D01*
G01X2442Y173484D02*
G03X2304Y173428I0J-197D01*
G01Y170430D02*
G03X2442Y170374I138J141D01*
G01X4915Y170315D02*
G03X4774Y170374I-141J-138D01*
G01X4272Y178428D02*
X4094Y178253D01*
G01X2304Y173428D02*
X2125Y173253D01*
G01X4232Y177533D02*
X4035Y177419D01*
G01X2263Y174383D02*
X2066Y174269D01*
G01X2304Y168428D02*
X2125Y168253D01*
G01X2304Y163428D02*
X2125Y163253D01*
G01X1968Y164650D02*
Y163499D01*
G01Y174099D02*
Y172948D01*
G01X2125Y170605D02*
Y173253D01*
G01Y165605D02*
Y168253D01*
G01X2235Y164918D02*
Y163232D01*
G01Y174367D02*
Y172680D01*
G01X2339Y172639D02*
Y174408D01*
G01Y163190D02*
Y164959D01*
G01X2672Y168484D02*
Y165374D01*
G01Y173484D02*
Y170374D01*
G01X2848Y168484D02*
Y165374D01*
G01Y173484D02*
Y170374D01*
G01X3936Y176098D02*
Y177248D01*
G01Y169798D02*
Y170949D01*
G01Y166649D02*
Y167800D01*
G01X4094Y175605D02*
Y178253D01*
G01X4203Y168067D02*
Y166381D01*
G01Y171217D02*
Y169531D01*
G01Y177516D02*
Y175830D01*
G01X4308Y175789D02*
Y177558D01*
G01Y169489D02*
Y171258D01*
G01Y166340D02*
Y168109D01*
G01X4232Y171233D02*
X4035Y171120D01*
G01X4232Y168084D02*
X4035Y167970D01*
G01X2263Y164934D02*
X2066Y164820D01*
G01X4641Y175374D02*
Y178484D01*
G01X4817Y178489D02*
Y175369D01*
G01X2125Y165605D02*
X2304Y165430D01*
G01X2125Y170605D02*
X2304Y170430D01*
G01X4094Y175605D02*
X4272Y175430D01*
G01X2066Y163329D02*
X2263Y163215D01*
G01X4232Y166365D02*
X4035Y166478D01*
G01X4232Y169515D02*
X4035Y169628D01*
G01X2066Y172778D02*
X2263Y172664D01*
G01X4232Y175814D02*
X4035Y175927D01*
G01X4945Y175326D02*
X4839Y175363D01*
G01X4330Y161811D02*
X14783D01*
G01X15964Y163189D02*
X2361D01*
G01X2442Y163484D02*
X4774D01*
G01X4915Y163543D02*
X14485D01*
G01X2361Y164961D02*
X14783D01*
G01X14485Y165315D02*
X4915D01*
G01X4774Y165374D02*
X2442D01*
G01X15882Y166339D02*
X4330D01*
G01Y168110D02*
X14783D01*
G01X2442Y168484D02*
X4774D01*
G01X4915Y168543D02*
X14485D01*
G01X4330Y169488D02*
X15882D01*
G01X14485Y170315D02*
X4915D01*
G01X4774Y170374D02*
X2442D01*
G01X4330Y171260D02*
X14783D01*
G01X15964Y172638D02*
X2361D01*
G01X2442Y173484D02*
X4774D01*
G01X4915Y173543D02*
X14485D01*
G01X2361Y174409D02*
X14783D01*
G01X14485Y175315D02*
X5010D01*
G01X4774Y175374D02*
X4410D01*
G01X15882Y175787D02*
X4330D01*
G01Y177559D02*
X14783D01*
G01X1979Y191781D02*
X1968Y191846D01*
G01X2011Y191722D02*
X1979Y191781D01*
G01X2066Y191675D02*
X2011Y191722D01*
G01X1979Y182332D02*
X1968Y182397D01*
G01X2011Y182273D02*
X1979Y182332D01*
G01X2066Y182226D02*
X2011Y182273D01*
G01X3981Y188571D02*
X4035Y188526D01*
G01X3948Y188630D02*
X3981Y188571D01*
G01X3936Y188696D02*
X3948Y188630D01*
G01X3981Y185422D02*
X4035Y185376D01*
G01X3948Y185480D02*
X3981Y185422D01*
G01X3936Y185546D02*
X3948Y185480D01*
G01X3981Y179122D02*
X4035Y179077D01*
G01X3948Y179181D02*
X3981Y179122D01*
G01X3936Y179247D02*
X3948Y179181D01*
G01X2012Y183672D02*
X2066Y183718D01*
G01X1979Y183614D02*
X2012Y183672D01*
G01X1968Y183548D02*
X1979Y183614D01*
G01X2012Y193121D02*
X2066Y193167D01*
G01X1979Y193063D02*
X2012Y193121D01*
G01X1968Y192996D02*
X1979Y193063D01*
G01X3947Y180463D02*
X3936Y180398D01*
G01X3980Y180522D02*
X3947Y180463D01*
G01X4035Y180569D02*
X3980Y180522D01*
G01X3947Y186762D02*
X3936Y186697D01*
G01X3980Y186821D02*
X3947Y186762D01*
G01X4035Y186868D02*
X3980Y186821D01*
G01X3947Y189912D02*
X3936Y189847D01*
G01X3980Y189971D02*
X3947Y189912D01*
G01X4035Y190017D02*
X3980Y189971D01*
G01X4232Y178963D02*
G03X4330Y178937I98J171D01*
G01X5010Y178543D02*
G03X4945Y178532I0J-197D01*
G01X4774Y178484D02*
G03X4839Y178495I0J197D01*
G01X4410Y178484D02*
G03X4272Y178428I0J-197D01*
G01X4330Y180709D02*
G03X4232Y180682I2J-197D01*
G01X2361Y183858D02*
G03X2263Y183832I0J-197D01*
G01Y182113D02*
G03X2361Y182087I98J171D01*
G01X4330Y187008D02*
G03X4232Y186982I0J-197D01*
G01Y185263D02*
G03X4330Y185236I99J170D01*
G01Y190158D02*
G03X4232Y190131I2J-197D01*
G01Y188412D02*
G03X4330Y188386I98J171D01*
G01X4272Y190430D02*
G03X4410Y190374I138J141D01*
G01X4839Y190363D02*
G03X4774Y190374I-65J-186D01*
G01X4945Y190326D02*
G03X5010Y190315I65J186D01*
G01X4774Y188484D02*
G03X4915Y188543I0J197D01*
G01X2442Y188484D02*
G03X2304Y188428I0J-197D01*
G01Y185430D02*
G03X2442Y185374I138J141D01*
G01X4915Y185315D02*
G03X4774Y185374I-141J-138D01*
G01X5010Y183543D02*
G03X4945Y183532I0J-197D01*
G01X4774Y183484D02*
G03X4839Y183495I0J197D01*
G01X4410Y183484D02*
G03X4272Y183428I0J-197D01*
G01Y180430D02*
G03X4410Y180374I138J141D01*
G01X4839Y180363D02*
G03X4774Y180374I-65J-186D01*
G01X4945Y180326D02*
G03X5010Y180315I65J186D01*
G01X2361Y193307D02*
G03X2263Y193281I0J-197D01*
G01Y191562D02*
G03X2361Y191535I100J170D01*
G01X4232Y194711D02*
G03X4330Y194685I98J171D01*
G01X5010Y193543D02*
G03X4945Y193532I0J-197D01*
G01X4774Y193484D02*
G03X4839Y193495I0J197D01*
G01X4410Y193484D02*
G03X4272Y193428I0J-197D01*
G01X2263Y193281D02*
X2066Y193167D01*
G01X4272Y193428D02*
X4094Y193253D01*
G01X2304Y188428D02*
X2125Y188253D01*
G01X4272Y183428D02*
X4094Y183253D01*
G01X4232Y190131D02*
X4035Y190017D01*
G01X4232Y186982D02*
X4035Y186868D01*
G01X2263Y183832D02*
X2066Y183718D01*
G01X4232Y180682D02*
X4035Y180569D01*
G01X1968Y183548D02*
Y182397D01*
G01Y192996D02*
Y191846D01*
G01X2125Y185605D02*
Y188253D01*
G01X2235Y183815D02*
Y182129D01*
G01Y193264D02*
Y191578D01*
G01X2339Y191537D02*
Y193306D01*
G01Y182088D02*
Y183857D01*
G01X2672Y188484D02*
Y185374D01*
G01X2848Y188484D02*
Y185374D01*
G01X3936Y188696D02*
Y189847D01*
G01Y185546D02*
Y186697D01*
G01Y179247D02*
Y180398D01*
G01X4094Y190605D02*
Y193253D01*
G01Y180605D02*
Y183253D01*
G01X4203Y180666D02*
Y178980D01*
G01Y186965D02*
Y185279D01*
G01Y190115D02*
Y188428D01*
G01Y196414D02*
Y194728D01*
G01X4308Y194686D02*
Y196455D01*
G01Y188387D02*
Y190156D01*
G01Y185237D02*
Y187006D01*
G01Y178938D02*
Y180707D01*
G01X4839Y193495D02*
X4945Y193532D01*
G01X4839Y183495D02*
X4945Y183532D01*
G01X4641Y190374D02*
Y193484D01*
G01Y180374D02*
Y183484D01*
G01X4817Y183489D02*
Y180369D01*
G01Y193489D02*
Y190369D01*
G01X4839Y178495D02*
X4945Y178532D01*
G01X4094Y180605D02*
X4272Y180430D01*
G01X2125Y185605D02*
X2304Y185430D01*
G01X4094Y190605D02*
X4272Y190430D01*
G01X4232Y178963D02*
X4035Y179077D01*
G01X2066Y182226D02*
X2263Y182113D01*
G01X4232Y185263D02*
X4035Y185376D01*
G01X4232Y188412D02*
X4035Y188526D01*
G01X2066Y191675D02*
X2263Y191562D01*
G01X4232Y194711D02*
X4035Y194825D01*
G01X4945Y180326D02*
X4839Y180363D01*
G01X4945Y190326D02*
X4839Y190363D01*
G01X4410Y178484D02*
X4774D01*
G01X5010Y178543D02*
X14485D01*
G01X15882Y178937D02*
X4330D01*
G01X14485Y180315D02*
X5010D01*
G01X4774Y180374D02*
X4410D01*
G01X4330Y180709D02*
X14783D01*
G01X15964Y182087D02*
X2361D01*
G01X4410Y183484D02*
X4774D01*
G01X5010Y183543D02*
X14485D01*
G01X2361Y183858D02*
X14783D01*
G01X15882Y185236D02*
X4330D01*
G01X14485Y185315D02*
X4915D01*
G01X4774Y185374D02*
X2442D01*
G01X4330Y187008D02*
X14783D01*
G01X15882Y188386D02*
X4330D01*
G01X2442Y188484D02*
X4774D01*
G01X4915Y188543D02*
X14485D01*
G01X4330Y190158D02*
X14783D01*
G01X14485Y190315D02*
X5010D01*
G01X4774Y190374D02*
X4410D01*
G01X15964Y191535D02*
X2361D01*
G01Y193307D02*
X14783D01*
G01X4410Y193484D02*
X4774D01*
G01X5010Y193543D02*
X14485D01*
G01X15882Y194685D02*
X4330D01*
G01X1979Y210678D02*
X1968Y210743D01*
G01X2011Y210620D02*
X1979Y210678D01*
G01X2066Y210573D02*
X2011Y210620D01*
G01X1979Y201230D02*
X1968Y201295D01*
G01X2011Y201171D02*
X1979Y201230D01*
G01X2066Y201124D02*
X2011Y201171D01*
G01X3981Y207469D02*
X4035Y207423D01*
G01X3948Y207528D02*
X3981Y207469D01*
G01X3936Y207594D02*
X3948Y207528D01*
G01X3981Y204319D02*
X4035Y204274D01*
G01X3948Y204378D02*
X3981Y204319D01*
G01X3936Y204444D02*
X3948Y204378D01*
G01X3981Y198020D02*
X4035Y197974D01*
G01X3948Y198079D02*
X3981Y198020D01*
G01X3936Y198145D02*
X3948Y198079D01*
G01X3981Y194870D02*
X4035Y194825D01*
G01X3948Y194929D02*
X3981Y194870D01*
G01X3936Y194995D02*
X3948Y194929D01*
G01X2012Y202570D02*
X2066Y202616D01*
G01X1979Y202511D02*
X2012Y202570D01*
G01X1968Y202445D02*
X1979Y202511D01*
G01X3947Y196211D02*
X3936Y196146D01*
G01X3980Y196270D02*
X3947Y196211D01*
G01X4035Y196317D02*
X3980Y196270D01*
G01X3947Y199361D02*
X3936Y199296D01*
G01X3980Y199420D02*
X3947Y199361D01*
G01X4035Y199466D02*
X3980Y199420D01*
G01X3947Y205660D02*
X3936Y205595D01*
G01X3980Y205719D02*
X3947Y205660D01*
G01X4035Y205765D02*
X3980Y205719D01*
G01X3947Y208809D02*
X3936Y208745D01*
G01X3980Y208869D02*
X3947Y208809D01*
G01X4035Y208915D02*
X3980Y208869D01*
G01X4330Y196457D02*
G03X4232Y196430I2J-197D01*
G01X4330Y199606D02*
G03X4232Y199580I0J-197D01*
G01Y197861D02*
G03X4330Y197835I98J171D01*
G01X2263Y201011D02*
G03X2361Y200984I99J170D01*
G01X2304Y200430D02*
G03X2442Y200374I138J141D01*
G01X4915Y200315D02*
G03X4774Y200374I-141J-138D01*
G01Y198484D02*
G03X4915Y198543I0J197D01*
G01X2442Y198484D02*
G03X2304Y198428I0J-197D01*
G01Y195430D02*
G03X2442Y195374I138J141D01*
G01X4915Y195315D02*
G03X4774Y195374I-141J-138D01*
G01X2361Y202756D02*
G03X2263Y202730I0J-197D01*
G01X4330Y205906D02*
G03X4232Y205879I2J-197D01*
G01Y204160D02*
G03X4330Y204134I98J171D01*
G01Y209055D02*
G03X4232Y209029I0J-197D01*
G01Y207310D02*
G03X4330Y207283I99J170D01*
G01X2263Y210459D02*
G03X2361Y210433I98J171D01*
G01X4272Y210430D02*
G03X4410Y210374I138J141D01*
G01X4839Y210363D02*
G03X4774Y210374I-65J-186D01*
G01X4945Y210326D02*
G03X5010Y210315I65J186D01*
G01Y208543D02*
G03X4945Y208532I0J-197D01*
G01X4774Y208484D02*
G03X4839Y208495I0J197D01*
G01X4410Y208484D02*
G03X4272Y208428I0J-197D01*
G01Y205430D02*
G03X4410Y205374I138J141D01*
G01X4839Y205363D02*
G03X4774Y205374I-65J-186D01*
G01X4945Y205326D02*
G03X5010Y205315I65J186D01*
G01X4774Y203484D02*
G03X4915Y203543I0J197D01*
G01X2442Y203484D02*
G03X2304Y203428I0J-197D01*
G01X4272Y208428D02*
X4094Y208253D01*
G01X2304Y203428D02*
X2125Y203253D01*
G01X2304Y198428D02*
X2125Y198253D01*
G01X4232Y209029D02*
X4035Y208915D01*
G01X4232Y205879D02*
X4035Y205765D01*
G01X2263Y202730D02*
X2066Y202616D01*
G01X4232Y199580D02*
X4035Y199466D01*
G01X4232Y196430D02*
X4035Y196317D01*
G01X4839Y208495D02*
X4945Y208532D01*
G01X1968Y202445D02*
Y201295D01*
G01Y211894D02*
Y210743D01*
G01X2125Y200605D02*
Y203253D01*
G01Y195605D02*
Y198253D01*
G01X2235Y202713D02*
Y201027D01*
G01Y212162D02*
Y210476D01*
G01X2339Y210434D02*
Y212203D01*
G01Y200985D02*
Y202754D01*
G01X2672Y198484D02*
Y195374D01*
G01Y203484D02*
Y200374D01*
G01X2848Y198484D02*
Y195374D01*
G01Y203484D02*
Y200374D01*
G01X3936Y207594D02*
Y208745D01*
G01Y204444D02*
Y205595D01*
G01Y198145D02*
Y199296D01*
G01Y194995D02*
Y196146D01*
G01X4094Y210605D02*
Y213253D01*
G01Y205605D02*
Y208253D01*
G01X4203Y199563D02*
Y197877D01*
G01Y205863D02*
Y204176D01*
G01Y209012D02*
Y207326D01*
G01X4308Y207285D02*
Y209054D01*
G01Y204135D02*
Y205904D01*
G01Y197836D02*
Y199605D01*
G01X4641Y210374D02*
Y213484D01*
G01Y205374D02*
Y208484D01*
G01X4817Y208489D02*
Y205369D01*
G01Y213489D02*
Y210369D01*
G01X2125Y195605D02*
X2304Y195430D01*
G01X2125Y200605D02*
X2304Y200430D01*
G01X4094Y205605D02*
X4272Y205430D01*
G01X4094Y210605D02*
X4272Y210430D01*
G01X4232Y197861D02*
X4035Y197974D01*
G01X2066Y201124D02*
X2263Y201011D01*
G01X4232Y204160D02*
X4035Y204274D01*
G01X4232Y207310D02*
X4035Y207423D01*
G01X2066Y210573D02*
X2263Y210459D01*
G01X4945Y205326D02*
X4839Y205363D01*
G01X4945Y210326D02*
X4839Y210363D01*
G01X14485Y195315D02*
X4915D01*
G01X4774Y195374D02*
X2442D01*
G01X4330Y196457D02*
X14783D01*
G01X15882Y197835D02*
X4330D01*
G01X2442Y198484D02*
X4774D01*
G01X4915Y198543D02*
X14485D01*
G01X4330Y199606D02*
X14783D01*
G01X14485Y200315D02*
X4915D01*
G01X4774Y200374D02*
X2442D01*
G01X15964Y200984D02*
X2361D01*
G01Y202756D02*
X14783D01*
G01X2442Y203484D02*
X4774D01*
G01X4915Y203543D02*
X14485D01*
G01X15882Y204134D02*
X4330D01*
G01X14485Y205315D02*
X5010D01*
G01X4774Y205374D02*
X4410D01*
G01X4330Y205906D02*
X14783D01*
G01X15882Y207283D02*
X4330D01*
G01X4410Y208484D02*
X4774D01*
G01X5010Y208543D02*
X14485D01*
G01X4330Y209055D02*
X14783D01*
G01X14485Y210315D02*
X5010D01*
G01X4774Y210374D02*
X4410D01*
G01X15964Y210433D02*
X2361D01*
G01X2012Y212019D02*
X2066Y212065D01*
G01X1979Y211960D02*
X2012Y212019D01*
G01X1968Y211894D02*
X1979Y211960D01*
G01X2361Y212205D02*
G03X2263Y212178I2J-197D01*
G01X5010Y213543D02*
G03X4945Y213532I0J-197D01*
G01X4774Y213484D02*
G03X4839Y213495I0J197D01*
G01X4410Y213484D02*
G03X4272Y213428I0J-197D01*
G01X-1Y214055D02*
X1180Y215236D01*
G01X4272Y213428D02*
X4094Y213253D01*
G01X2263Y212178D02*
X2066Y212065D01*
G01X4839Y213495D02*
X4945Y213532D01*
G01X-1Y236673D02*
Y224685D01*
G01X2045Y230394D02*
X2046Y222638D01*
G01X-1Y224685D02*
X2046Y222638D01*
G01X2361Y212205D02*
X14783D01*
G01X4410Y213484D02*
X4774D01*
G01X5010Y213543D02*
X14485D01*
G01X30155Y215236D02*
X1180D01*
G01X17322Y222638D02*
X2046D01*
G01X-1Y225276D02*
X26771D01*
G01X-1Y226457D02*
X26771D01*
G01X-1Y236673D02*
G03X1968Y234705I1968J0D01*
G01X-1Y236673D02*
G03X1968Y234705I1968J0D01*
G01X-1Y236673D02*
G03X1968Y234705I1968J0D01*
G01X-1Y236673D02*
G03X1968Y234705I1968J0D01*
G01X2045Y230394D02*
X1728Y229213D01*
G01X-1Y256102D02*
Y236673D01*
G01Y256102D02*
Y236673D01*
G01Y244370D02*
Y236673D01*
G01X6259Y240039D02*
Y238858D01*
G01X6298Y234705D02*
Y233543D01*
G01Y244370D02*
Y234705D01*
G01X-1Y230211D02*
X1728Y229213D01*
G01X-1Y231575D02*
X2045Y230394D01*
G01X26771Y229213D02*
X-1D01*
G01X26771Y230394D02*
X2045D01*
G01X30128Y233543D02*
X-1D01*
G01X28346Y234705D02*
X1968D01*
G01X28346D02*
X1968D01*
G01X-1Y235512D02*
X29921D01*
G01Y237638D02*
X-1D01*
G01X29921Y238228D02*
X-1D01*
G01X29921Y238819D02*
X-1D01*
G01X24054Y238858D02*
X6259D01*
G01X24054Y240039D02*
X6259D01*
G01X29921Y240079D02*
X-1D01*
G01X10235Y240669D02*
X-1D01*
G01Y241260D02*
X10235D01*
G01X-1Y256102D02*
Y236673D01*
G01Y256102D02*
Y236673D01*
G01X28346Y234705D02*
X1968D01*
G01X28346D02*
X1968D01*
G01D02*
X28346D01*
G01X0Y236673D02*
G03X1968Y234705I1968J0D01*
G01X0Y256102D02*
Y236673D01*
G01X1968Y258071D02*
G03X-1Y256102I0J-1969D01*
G01X1968Y258071D02*
G03X-1Y256102I0J-1969D01*
G01X1968Y258071D02*
G03X-1Y256102I0J-1969D01*
G01X1968Y258071D02*
G03X-1Y256102I0J-1969D01*
G01X10235Y244370D02*
X-1D01*
G01X125590Y258071D02*
X1968D01*
G01X125590D02*
X1968D01*
G01X125590D02*
X1968D01*
G01X125590D02*
X1968D01*
G01D02*
G03X0Y256102I0J-1968D01*
G01X125590Y258071D02*
X1968D01*
G01X0Y273819D02*
G03X7874Y265945I7874J0D01*
G01X0Y355551D02*
Y273819D01*
G01D02*
G03X7874Y265945I7874J0D01*
G01X0Y273819D02*
G03X7874Y265945I7874J0D01*
G01X0Y273819D02*
G03X7874Y265945I7874J0D01*
G01X0Y273819D02*
G03X7874Y265945I7874J0D01*
G01X0Y355551D02*
Y273819D01*
G01Y355551D02*
Y273819D01*
G01Y355551D02*
Y273819D01*
G01Y355551D02*
Y273819D01*
G01X7874Y363425D02*
G03X0Y355551I0J-7874D01*
G01X7874Y363425D02*
G03X0Y355551I0J-7874D01*
G01X7874Y363425D02*
G03X0Y355551I0J-7874D01*
G01X7874Y363425D02*
G03X0Y355551I0J-7874D01*
G01X7874Y363425D02*
G03X0Y355551I0J-7874D01*
G01X245745Y383110D02*
X7874D01*
G03X0Y375236I0J-7874D01*
G01Y371299D01*
G01Y375482D02*
Y423796D01*
G01Y371299D02*
X13591D01*
G01X-9843Y416767D02*
X-9515Y415783D01*
X-8695Y415045D01*
X-7711Y414552D01*
X-6398Y414183D01*
X-4921Y414060D01*
X-3445Y414183D01*
X-2132Y414552D01*
X-1148Y415045D01*
X-328Y415783D01*
X0Y416767D01*
X-328Y417751D01*
X-1148Y418489D01*
X-2132Y418982D01*
X-3445Y419351D01*
X-4921Y419474D01*
X-6398Y419351D01*
X-7711Y418982D01*
X-8695Y418489D01*
X-9515Y417751D01*
X-9843Y416767D01*
G01X328Y426610D02*
X164Y426364D01*
X-164D01*
X-328Y426610D01*
X-164Y426856D01*
X164D01*
X328Y426610D01*
G01X-9843Y436453D02*
X-9515Y435469D01*
X-8695Y434731D01*
X-7711Y434238D01*
X-6398Y433869D01*
X-4921Y433746D01*
X-3445Y433869D01*
X-2132Y434238D01*
X-1148Y434731D01*
X-328Y435469D01*
X0Y436453D01*
X-328Y437437D01*
X-1148Y438175D01*
X-2132Y438668D01*
X-3445Y439037D01*
X-4921Y439160D01*
X-6398Y439037D01*
X-7711Y438668D01*
X-8695Y438175D01*
X-9515Y437437D01*
X-9843Y436453D01*
G01Y446296D02*
X-9515Y445312D01*
X-8695Y444574D01*
X-7711Y444081D01*
X-6398Y443712D01*
X-4921Y443589D01*
X-3445Y443712D01*
X-2132Y444081D01*
X-1148Y444574D01*
X-328Y445312D01*
X0Y446296D01*
X-328Y447280D01*
X-1148Y448018D01*
X-2132Y448511D01*
X-3445Y448880D01*
X-4921Y449003D01*
X-6398Y448880D01*
X-7711Y448511D01*
X-8695Y448018D01*
X-9515Y447280D01*
X-9843Y446296D01*
G01X10516Y-746759D02*
X10986Y-746129D01*
X11534Y-745814D01*
X12161Y-745709D01*
X12944Y-745919D01*
X13492Y-746444D01*
X13649Y-747074D01*
X13571Y-747704D01*
X13257Y-748229D01*
X11691Y-749279D01*
X10986Y-750014D01*
X10516Y-751064D01*
X10359Y-752009D01*
X13649D01*
G01X30379Y-114844D02*
G03I-4292J0D01*
G01X13591Y-113228D02*
G03Y-105354I0J3937D01*
G01X7873D02*
X341535D01*
G01X7873D02*
X341535D01*
G01X7873D02*
X341535D01*
G01X7873D02*
X341535D01*
G01X7874D02*
X341535D01*
G01X9842Y-18740D02*
G03X11810Y-16772I0J1968D01*
G01X9842Y-18740D02*
G03X11810Y-16772I0J1968D01*
G01X9842Y-18740D02*
G03X11810Y-16772I0J1968D01*
G01X9842Y-18740D02*
G03X11810Y-16772I0J1968D01*
G01D02*
Y38504D01*
G01Y-16772D02*
Y38504D01*
G01Y-16772D02*
Y38504D01*
G01Y-16772D02*
Y38504D01*
G01X9842Y-18740D02*
G03X11811Y-16772I0J1969D01*
G01Y38504D02*
Y-16772D01*
G01X11810Y38504D02*
G03X9842Y40472I-1968J0D01*
G01X11810Y38504D02*
G03X9842Y40472I-1968J0D01*
G01X11810Y38504D02*
G03X9842Y40472I-1968J0D01*
G01X11810Y38504D02*
G03X9842Y40472I-1968J0D01*
G01X11811Y38504D02*
G03X9842Y40473I-1969J0D01*
G01X18906Y58776D02*
X18896Y58758D01*
G01X19004Y58808D02*
X18906Y58776D01*
G01X19209Y58818D02*
X19004Y58808D01*
G01X11298Y59984D02*
X11387Y59953D01*
G01X11166Y59996D02*
X11298Y59984D01*
G01X11004Y60000D02*
X11166Y59996D01*
G01X11272Y58811D02*
X11080Y58818D01*
G01X11387Y58790D02*
X11272Y58811D01*
G01X11413Y58743D02*
X11417Y58758D01*
G01X11398Y58723D02*
X11413Y58743D01*
G01X11416Y59908D02*
X11417Y59902D01*
G01X11408Y59933D02*
X11416Y59908D01*
G01X11387Y59953D02*
X11408Y59933D01*
G01X19189Y59998D02*
X19286Y60000D01*
G01X19097Y59994D02*
X19189Y59998D01*
G01X19015Y59984D02*
X19097Y59994D01*
G01X18950Y59966D02*
X19015Y59984D01*
G01X18909Y59937D02*
X18950Y59966D01*
G01X18897Y59902D02*
X18909Y59937D01*
G01X11213Y58458D02*
X11398Y58723D01*
G01X11029Y58048D02*
X11213Y58458D01*
G01X10845Y57528D02*
X11029Y58048D01*
G01Y58766D02*
X10845Y57934D01*
G01X11213Y59423D02*
X11029Y58766D01*
G01X11398Y59847D02*
X11213Y59423D01*
G01X19284Y58048D02*
X19469Y57528D01*
G01X19100Y58458D02*
X19284Y58048D01*
G01X18916Y58723D02*
X19100Y58458D01*
G01X18897Y59897D02*
Y59902D01*
G01X18916Y59847D02*
X18897Y59897D01*
G01X11408Y58777D02*
X11387Y58790D01*
G01X11416Y58761D02*
X11408Y58777D01*
G01X11417Y58758D02*
X11416Y58761D01*
G01X19479Y57873D02*
X19469Y57934D01*
G01X19485Y57811D02*
X19479Y57873D01*
G01X19487Y57748D02*
X19485Y57811D01*
G01X10834Y57490D02*
X10845Y57528D01*
G01X10828Y57451D02*
X10834Y57490D01*
G01X10826Y57411D02*
X10828Y57451D01*
G01X11413Y59880D02*
X11398Y59847D01*
G01X11417Y59902D02*
X11413Y59880D01*
G01X10828Y57811D02*
X10826Y57748D01*
G01X10834Y57873D02*
X10828Y57811D01*
G01X10845Y57934D02*
X10834Y57873D01*
G01X19485Y57451D02*
X19487Y57411D01*
G01X19479Y57490D02*
X19485Y57451D01*
G01X19469Y57528D02*
X19479Y57490D01*
G01X19100Y59423D02*
X18916Y59847D01*
G01X19284Y58766D02*
X19100Y59423D01*
G01X19469Y57934D02*
X19284Y58766D01*
G01X18306Y49803D02*
G03X19487Y50984I0J1181D01*
G01X10826D02*
G03X12007Y49803I1181J0D01*
G01X6850Y58819D02*
Y60000D01*
G01X8149Y58819D02*
Y60000D01*
G01X8626D02*
Y58819D01*
G01X8711D02*
Y60000D01*
G01X8958D02*
Y58819D01*
G01X9961D02*
Y60000D01*
G01X10039D02*
Y58819D01*
G01X10235Y58780D02*
Y54488D01*
G01X10826Y57747D02*
Y50984D01*
G01Y60000D02*
Y58819D01*
G01X10845Y57528D02*
Y57934D01*
G01X11387Y59953D02*
Y58790D01*
G01X11398Y58723D02*
Y59847D01*
G01X11417Y58758D02*
Y59902D01*
G01X12086Y60000D02*
Y58819D01*
G01X12480D02*
Y60000D01*
G01X13267D02*
Y58819D01*
G01X17046Y60000D02*
Y58819D01*
G01X17834D02*
Y60000D01*
G01X18228Y58819D02*
Y60000D01*
G01X18897Y59902D02*
Y58758D01*
G01X18916Y58723D02*
Y59847D01*
G01X19469Y57934D02*
Y57528D01*
G01X19487Y57747D02*
Y50984D01*
G01Y60000D02*
Y58819D01*
G01X20078Y58780D02*
Y54488D01*
G01X20275Y58819D02*
Y60000D01*
G01X20352D02*
Y58819D01*
G01X18896Y58758D02*
X18916Y58723D01*
G01X21356Y58819D02*
Y60000D01*
G01X21602D02*
Y58819D01*
G01X21687D02*
Y60000D01*
G01X22007Y60433D02*
Y58386D01*
G01X22165Y58819D02*
Y60000D01*
G01X22401Y60433D02*
Y58386D01*
G01X22007Y58780D02*
X22401Y58386D01*
G01X22007Y60039D02*
X22401Y60433D01*
G01X18306Y49803D02*
X12007D01*
G01X29921Y54488D02*
X20078D01*
G01X10826Y56850D02*
X19487D01*
G01X20078Y57598D02*
X29921D01*
G01Y58189D02*
X20078D01*
G01X22401Y58386D02*
X22007D01*
G01X10235D02*
X20078D01*
G01X22007Y60433D02*
X22401D01*
G01X7873Y68465D02*
Y65315D01*
G01X19291Y78189D02*
Y220669D01*
G01Y78189D02*
X17322Y76220D01*
G01X18931Y89176D02*
X18897Y89173D01*
G01X18964Y89185D02*
X18931Y89176D01*
G01X18995Y89200D02*
X18964Y89185D01*
G01X18931Y92326D02*
X18897Y92323D01*
G01X18964Y92335D02*
X18931Y92326D01*
G01X18995Y92349D02*
X18964Y92335D01*
G01X18995Y94068D02*
G03X18897Y94095I-100J-170D01*
G01X18995Y90919D02*
G03X18897Y90945I-98J-171D01*
G01X16243D02*
G03X16103Y90887I0J-197D01*
G01X15882Y90748D02*
G03X16022Y90806I1J197D01*
G01X14922Y92462D02*
G03X14783Y92520I-140J-139D01*
G01X15004Y92380D02*
G03X15143Y92323I138J140D01*
G01X18995Y87769D02*
G03X18897Y87795I-98J-171D01*
G01X16243D02*
G03X16103Y87737I0J-197D01*
G01X15882Y87598D02*
G03X16022Y87656I0J197D01*
G01X14922Y89312D02*
G03X14783Y89370I-140J-139D01*
G01X15004Y89231D02*
G03X15143Y89173I139J139D01*
G01X17714Y93150D02*
G03X17765Y93156I3J197D01*
G01X14902Y93207D02*
G03X15041Y93150I138J140D01*
G01X14624Y93485D02*
G03X14485Y93543I-139J-139D01*
G01Y90315D02*
G03X14624Y90372I0J197D01*
G01X15041Y90709D02*
G03X14902Y90651I1J-197D01*
G01X17765Y90702D02*
G03X17714Y90709I-52J-190D01*
G01Y88150D02*
G03X17765Y88156I3J197D01*
G01X14902Y88207D02*
G03X15041Y88150I138J140D01*
G01X14624Y88485D02*
G03X14485Y88543I-139J-139D01*
G01Y85315D02*
G03X14624Y85372I0J197D01*
G01X15041Y85709D02*
G03X14902Y85651I1J-197D01*
G01X17765Y85702D02*
G03X17714Y85709I-52J-190D01*
G01X18897Y95472D02*
G03X18995Y95499I-1J197D01*
G01X14485Y95315D02*
G03X14624Y95372I0J197D01*
G01X15041Y95709D02*
G03X14902Y95651I1J-197D01*
G01X17765Y95702D02*
G03X17714Y95709I-52J-190D01*
G01X21259Y86752D02*
G03X23228Y84783I1969J0D01*
G01X21259Y86752D02*
G03X23228Y84783I1969J0D01*
G01X21259Y86752D02*
G03X23228Y84783I1969J0D01*
G01X21259Y86752D02*
G03X23228Y84783I1969J0D01*
G01X18109Y95079D02*
Y93780D01*
G01Y88780D02*
Y90079D01*
G01Y83622D02*
Y85079D01*
G01X21259Y86752D02*
Y212067D01*
G01Y86752D02*
Y212067D01*
G01X14624Y95372D02*
X14902Y95651D01*
G01X15964Y93898D02*
X16161Y94095D01*
G01X14624Y90372D02*
X14902Y90651D01*
G01X16022Y90806D02*
X16103Y90887D01*
G01X16022Y87656D02*
X16103Y87737D01*
G01X14902Y88207D02*
X14624Y88485D01*
G01X15004Y89231D02*
X14922Y89312D01*
G01X14624Y85372D02*
X14902Y85651D01*
G01X15004Y92380D02*
X14922Y92462D01*
G01X14902Y93207D02*
X14624Y93485D01*
G01X14980Y95472D02*
X14783Y95669D01*
G01X19291D02*
X18995Y95499D01*
G01X19291Y92520D02*
X18995Y92349D01*
G01X19291Y89370D02*
X18995Y89200D01*
G01Y87769D02*
X19291Y87598D01*
G01X18995Y90919D02*
X19291Y90748D01*
G01X18995Y94068D02*
X19291Y93898D01*
G01Y83334D02*
X26771Y79846D01*
G01X17765Y85702D02*
X19291Y85293D01*
G01X17765Y90702D02*
X19291Y90293D01*
G01X17765Y95702D02*
X19291Y95293D01*
G01X18109Y85079D02*
X19291D01*
G01X17714Y85709D02*
X15041D01*
G01X16243Y87795D02*
X18897D01*
G01X15041Y88150D02*
X17714D01*
G01X19291Y88780D02*
X18109D01*
G01X15143Y89173D02*
X18897D01*
G01X19291Y90079D02*
X18109D01*
G01X17714Y90709D02*
X15041D01*
G01X18897Y90945D02*
X16243D01*
G01X18897Y92323D02*
X15143D01*
G01X15041Y93150D02*
X17714D01*
G01X19291Y93780D02*
X18109D01*
G01X18897Y94095D02*
X16161D01*
G01X19291Y95079D02*
X18109D01*
G01X14980Y95472D02*
X18897D01*
G01X17714Y95709D02*
X15041D01*
G01X19291Y88565D02*
X17765Y88156D01*
G01X19291Y93565D02*
X17765Y93156D01*
G01X21259Y86752D02*
Y212067D01*
G01Y86752D02*
Y212067D01*
G01Y86752D02*
G03X23228Y84784I1968J0D01*
G01X21259Y212067D02*
Y86752D01*
G01X18931Y98625D02*
X18897Y98622D01*
G01X18964Y98634D02*
X18931Y98625D01*
G01X18995Y98648D02*
X18964Y98634D01*
G01X18931Y101774D02*
X18897Y101772D01*
G01X18964Y101783D02*
X18931Y101774D01*
G01X18995Y101798D02*
X18964Y101783D01*
G01X18931Y108074D02*
X18897Y108071D01*
G01X18964Y108083D02*
X18931Y108074D01*
G01X18995Y108097D02*
X18964Y108083D01*
G01X18931Y111223D02*
X18897Y111220D01*
G01X18964Y111232D02*
X18931Y111223D01*
G01X18995Y111247D02*
X18964Y111232D01*
G01X18897Y104921D02*
G03X18995Y104948I-1J197D01*
G01Y103517D02*
G03X18897Y103543I-98J-171D01*
G01X18995Y100367D02*
G03X18897Y100394I-100J-170D01*
G01X16243D02*
G03X16103Y100336I0J-197D01*
G01X15882Y100197D02*
G03X16022Y100254I1J197D01*
G01X14922Y101911D02*
G03X14783Y101969I-140J-139D01*
G01X15004Y101829D02*
G03X15143Y101772I138J140D01*
G01X18995Y97218D02*
G03X18897Y97244I-98J-171D01*
G01X16243D02*
G03X16103Y97186I0J-197D01*
G01X15882Y97047D02*
G03X16022Y97105I0J197D01*
G01X14922Y98761D02*
G03X14783Y98819I-140J-139D01*
G01X15004Y98680D02*
G03X15143Y98622I139J139D01*
G01X17714Y103150D02*
G03X17765Y103156I3J197D01*
G01X14902Y103207D02*
G03X15041Y103150I138J140D01*
G01X14624Y103485D02*
G03X14485Y103543I-139J-139D01*
G01Y100315D02*
G03X14624Y100372I0J197D01*
G01X15041Y100709D02*
G03X14902Y100651I1J-197D01*
G01X17765Y100702D02*
G03X17714Y100709I-52J-190D01*
G01Y98150D02*
G03X17765Y98156I3J197D01*
G01X14902Y98207D02*
G03X15041Y98150I138J140D01*
G01X14624Y98485D02*
G03X14485Y98543I-139J-139D01*
G01X18995Y109816D02*
G03X18897Y109843I-100J-170D01*
G01X16243D02*
G03X16103Y109785I0J-197D01*
G01X15882Y109646D02*
G03X16022Y109703I1J197D01*
G01X14922Y111359D02*
G03X14783Y111417I-139J-139D01*
G01X15004Y111278D02*
G03X15143Y111220I140J139D01*
G01X18995Y106667D02*
G03X18897Y106693I-98J-171D01*
G01X16243D02*
G03X16103Y106635I0J-197D01*
G01X15882Y106496D02*
G03X16022Y106554I1J197D01*
G01X14922Y108210D02*
G03X14783Y108268I-140J-139D01*
G01X15004Y108128D02*
G03X15143Y108071I138J140D01*
G01X14485Y110315D02*
G03X14624Y110372I0J197D01*
G01X15041Y110709D02*
G03X14902Y110651I1J-197D01*
G01X17765Y110702D02*
G03X17714Y110709I-52J-190D01*
G01Y108150D02*
G03X17765Y108156I3J197D01*
G01X14902Y108207D02*
G03X15041Y108150I138J140D01*
G01X14624Y108485D02*
G03X14485Y108543I-139J-139D01*
G01Y105315D02*
G03X14624Y105372I0J197D01*
G01X15041Y105709D02*
G03X14902Y105651I1J-197D01*
G01X17765Y105702D02*
G03X17714Y105709I-52J-190D01*
G01X18109Y110079D02*
Y108780D01*
G01Y103780D02*
Y105079D01*
G01Y98780D02*
Y100079D01*
G01X14624Y110372D02*
X14902Y110651D01*
G01X16022Y109703D02*
X16103Y109785D01*
G01X14624Y105372D02*
X14902Y105651D01*
G01X16022Y106554D02*
X16103Y106635D01*
G01X15964Y103346D02*
X16161Y103543D01*
G01X14624Y100372D02*
X14902Y100651D01*
G01X16022Y100254D02*
X16103Y100336D01*
G01X16022Y97105D02*
X16103Y97186D01*
G01X19291Y111417D02*
X18995Y111247D01*
G01X19291Y108268D02*
X18995Y108097D01*
G01X14902Y98207D02*
X14624Y98485D01*
G01X15004Y98680D02*
X14922Y98761D01*
G01X15004Y101829D02*
X14922Y101911D01*
G01X14902Y103207D02*
X14624Y103485D01*
G01X14980Y104921D02*
X14783Y105118D01*
G01X14902Y108207D02*
X14624Y108485D01*
G01X15004Y108128D02*
X14922Y108210D01*
G01X15004Y111278D02*
X14922Y111359D01*
G01X19291Y105118D02*
X18995Y104948D01*
G01X19291Y101969D02*
X18995Y101798D01*
G01X19291Y98819D02*
X18995Y98648D01*
G01Y97218D02*
X19291Y97047D01*
G01X18995Y100367D02*
X19291Y100197D01*
G01X18995Y103517D02*
X19291Y103346D01*
G01X18995Y106667D02*
X19291Y106496D01*
G01X18995Y109816D02*
X19291Y109646D01*
G01X17765Y100702D02*
X19291Y100293D01*
G01X17765Y105702D02*
X19291Y105293D01*
G01X17765Y110702D02*
X19291Y110293D01*
G01X18897Y97244D02*
X16243D01*
G01X15041Y98150D02*
X17714D01*
G01X18897Y98622D02*
X15143D01*
G01X19291Y98780D02*
X18109D01*
G01Y100079D02*
X19291D01*
G01X18897Y100394D02*
X16243D01*
G01X17714Y100709D02*
X15041D01*
G01X18897Y101772D02*
X15143D01*
G01X15041Y103150D02*
X17714D01*
G01X18897Y103543D02*
X16161D01*
G01X18109Y103780D02*
X19291D01*
G01X14980Y104921D02*
X18897D01*
G01X18109Y105079D02*
X19291D01*
G01X17714Y105709D02*
X15041D01*
G01X18897Y106693D02*
X16243D01*
G01X18897Y108071D02*
X15143D01*
G01X15041Y108150D02*
X17714D01*
G01X18109Y108780D02*
X19291D01*
G01X18897Y109843D02*
X16243D01*
G01X19291Y110079D02*
X18109D01*
G01X17714Y110709D02*
X15041D01*
G01X18897Y111220D02*
X15143D01*
G01X19291Y98565D02*
X17765Y98156D01*
G01X19291Y103565D02*
X17765Y103156D01*
G01X19291Y108565D02*
X17765Y108156D01*
G01X18931Y117522D02*
X18897Y117520D01*
G01X18964Y117532D02*
X18931Y117522D01*
G01X18995Y117546D02*
X18964Y117532D01*
G01X18931Y123822D02*
X18897Y123819D01*
G01X18964Y123831D02*
X18931Y123822D01*
G01X18995Y123845D02*
X18964Y123831D01*
G01X18931Y126971D02*
X18897Y126969D01*
G01X18964Y126980D02*
X18931Y126971D01*
G01X18995Y126995D02*
X18964Y126980D01*
G01X18897Y114370D02*
G03X18995Y114396I0J197D01*
G01Y112966D02*
G03X18897Y112992I-98J-171D01*
G01X17714Y113150D02*
G03X17765Y113156I3J197D01*
G01X14902Y113207D02*
G03X15041Y113150I138J140D01*
G01X14624Y113485D02*
G03X14485Y113543I-139J-139D01*
G01X14922Y123958D02*
G03X14783Y124016I-140J-139D01*
G01X15882Y122244D02*
G03X16022Y122302I0J197D01*
G01X16243Y122441D02*
G03X16103Y122383I0J-197D01*
G01X18995Y122415D02*
G03X18897Y122441I-98J-171D01*
G01X15004Y123876D02*
G03X15143Y123819I139J140D01*
G01X18897Y120669D02*
G03X18995Y120696I-1J197D01*
G01Y119265D02*
G03X18897Y119291I-98J-171D01*
G01X16243Y125591D02*
G03X16103Y125533I0J-197D01*
G01X18995Y125564D02*
G03X18897Y125591I-100J-170D01*
G01X18995Y116115D02*
G03X18897Y116142I-100J-170D01*
G01X16243D02*
G03X16103Y116084I0J-197D01*
G01X15882Y115945D02*
G03X16022Y116002I1J197D01*
G01X14922Y117659D02*
G03X14783Y117717I-140J-139D01*
G01X15004Y117577D02*
G03X15143Y117520I138J140D01*
G01X17714Y118150D02*
G03X17765Y118156I3J197D01*
G01X14902Y118207D02*
G03X15041Y118150I138J140D01*
G01X14624Y118485D02*
G03X14485Y118543I-139J-139D01*
G01Y115315D02*
G03X14624Y115372I0J197D01*
G01X15041Y115709D02*
G03X14902Y115651I1J-197D01*
G01X17765Y115702D02*
G03X17714Y115709I-52J-190D01*
G01X19291Y123910D02*
G03X19238Y123917I-52J-190D01*
G01Y122539D02*
G03X19291Y122546I1J197D01*
G01Y120760D02*
G03X19238Y120768I-56J-189D01*
G01X15004Y127026D02*
G03X15143Y126969I138J140D01*
G01X14922Y127108D02*
G03X14783Y127165I-139J-140D01*
G01X15882Y125394D02*
G03X16022Y125451I1J197D01*
G01X18995Y128714D02*
G03X18897Y128740I-98J-171D01*
G01X19291Y127059D02*
G03X19238Y127067I-56J-189D01*
G01Y125689D02*
G03X19291Y125696I1J197D01*
G01X18109Y115079D02*
Y113780D01*
G01Y119882D02*
Y118780D01*
G01X15964Y128543D02*
X16161Y128740D01*
G01X16022Y125451D02*
X16103Y125533D01*
G01X16022Y122302D02*
X16103Y122383D01*
G01X15964Y119095D02*
X16161Y119291D01*
G01X14624Y115372D02*
X14902Y115651D01*
G01X16022Y116002D02*
X16103Y116084D01*
G01X15964Y112795D02*
X16161Y112992D01*
G01X19291Y127165D02*
X18995Y126995D01*
G01X19291Y124016D02*
X18995Y123845D01*
G01X19291Y120866D02*
X18995Y120696D01*
G01X19291Y117717D02*
X18995Y117546D01*
G01X19291Y114567D02*
X18995Y114396D01*
G01X14902Y113207D02*
X14624Y113485D01*
G01X14980Y114370D02*
X14783Y114567D01*
G01X15004Y117577D02*
X14922Y117659D01*
G01X14902Y118207D02*
X14624Y118485D01*
G01X14980Y120669D02*
X14783Y120866D01*
G01X15004Y123876D02*
X14922Y123958D01*
G01X15004Y127026D02*
X14922Y127108D01*
G01X18995Y112966D02*
X19291Y112795D01*
G01X18995Y116115D02*
X19291Y115945D01*
G01X18995Y119265D02*
X19291Y119095D01*
G01X18995Y122415D02*
X19291Y122244D01*
G01X18995Y125564D02*
X19291Y125394D01*
G01X18995Y128714D02*
X19291Y128543D01*
G01X17765Y115702D02*
X19291Y115293D01*
G01X18897Y112992D02*
X16161D01*
G01X15041Y113150D02*
X17714D01*
G01X18109Y113780D02*
X19291D01*
G01X14980Y114370D02*
X18897D01*
G01X18109Y115079D02*
X19291D01*
G01X17714Y115709D02*
X15041D01*
G01X18897Y116142D02*
X16243D01*
G01X18897Y117520D02*
X15143D01*
G01X15041Y118150D02*
X17714D01*
G01X19291Y118780D02*
X18109D01*
G01X18897Y119291D02*
X16161D01*
G01X14980Y120669D02*
X18897D01*
G01Y122441D02*
X16243D01*
G01X18897Y123819D02*
X15143D01*
G01X18897Y125591D02*
X16243D01*
G01X18897Y126969D02*
X15143D01*
G01X18897Y128740D02*
X16161D01*
G01X19291Y113565D02*
X17765Y113156D01*
G01X19291Y118565D02*
X17765Y118156D01*
G01X18931Y133270D02*
X18897Y133268D01*
G01X18964Y133280D02*
X18931Y133270D01*
G01X18995Y133294D02*
X18964Y133280D01*
G01X18931Y136420D02*
X18897Y136417D01*
G01X18964Y136429D02*
X18931Y136420D01*
G01X18995Y136444D02*
X18964Y136429D01*
G01X18931Y142719D02*
X18897Y142717D01*
G01X18964Y142728D02*
X18931Y142719D01*
G01X18995Y142743D02*
X18964Y142728D01*
G01X18897Y130118D02*
G03X18995Y130145I-1J197D01*
G01X15004Y133325D02*
G03X15143Y133268I138J140D01*
G01X14922Y133407D02*
G03X14783Y133465I-140J-139D01*
G01X15882Y131693D02*
G03X16022Y131750I1J197D01*
G01X16243Y131890D02*
G03X16103Y131832I0J-197D01*
G01X18995Y131863D02*
G03X18897Y131890I-100J-170D01*
G01X15882Y134843D02*
G03X16022Y134900I2J197D01*
G01X16243Y135039D02*
G03X16103Y134982I-1J-197D01*
G01X18995Y135013D02*
G03X18897Y135039I-98J-171D01*
G01X15004Y136475D02*
G03X15143Y136417I140J139D01*
G01X14922Y136556D02*
G03X14783Y136614I-139J-139D01*
G01X18995Y138163D02*
G03X18897Y138189I-98J-171D01*
G01Y139567D02*
G03X18995Y139593I0J197D01*
G01X15004Y142774D02*
G03X15143Y142717I138J140D01*
G01X14922Y142856D02*
G03X14783Y142913I-139J-140D01*
G01X15882Y141142D02*
G03X16022Y141199I1J197D01*
G01X16243Y141339D02*
G03X16103Y141281I0J-197D01*
G01X18995Y141312D02*
G03X18897Y141339I-100J-170D01*
G01X18995Y144462D02*
G03X18897Y144488I-98J-171D01*
G01X17714Y143150D02*
G03X17765Y143156I3J197D01*
G01X14902Y143207D02*
G03X15041Y143150I138J140D01*
G01X14624Y143485D02*
G03X14485Y143543I-139J-139D01*
G01Y140315D02*
G03X14624Y140372I0J197D01*
G01X15041Y140709D02*
G03X14902Y140651I1J-197D01*
G01X17765Y140702D02*
G03X17714Y140709I-52J-190D01*
G01X19238Y135138D02*
G03X19291Y135145I1J197D01*
G01Y133359D02*
G03X19238Y133366I-52J-190D01*
G01Y131988D02*
G03X19291Y131995I1J197D01*
G01Y130209D02*
G03X19238Y130217I-56J-189D01*
G01Y128839D02*
G03X19291Y128846I1J197D01*
G01X19238Y138287D02*
G03X19291Y138295I-3J197D01*
G01Y136508D02*
G03X19238Y136516I-56J-189D01*
G01X15964Y144291D02*
X16161Y144488D01*
G01X14624Y140372D02*
X14902Y140651D01*
G01X16022Y141199D02*
X16103Y141281D01*
G01X15964Y137992D02*
X16161Y138189D01*
G01X16022Y134900D02*
X16103Y134982D01*
G01X18109Y143780D02*
Y145079D01*
G01Y138976D02*
Y140079D01*
G01X16022Y131750D02*
X16103Y131832D01*
G01X19291Y142913D02*
X18995Y142743D01*
G01X19291Y139764D02*
X18995Y139593D01*
G01X19291Y136614D02*
X18995Y136444D01*
G01X19291Y133465D02*
X18995Y133294D01*
G01X19291Y130315D02*
X18995Y130145D01*
G01X14980Y130118D02*
X14783Y130315D01*
G01X15004Y133325D02*
X14922Y133407D01*
G01X15004Y136475D02*
X14922Y136556D01*
G01X14980Y139567D02*
X14783Y139764D01*
G01X15004Y142774D02*
X14922Y142856D01*
G01X14902Y143207D02*
X14624Y143485D01*
G01X18995Y131863D02*
X19291Y131693D01*
G01X18995Y135013D02*
X19291Y134843D01*
G01X18995Y138163D02*
X19291Y137992D01*
G01X18995Y141312D02*
X19291Y141142D01*
G01X18995Y144462D02*
X19291Y144291D01*
G01X17765Y140702D02*
X19291Y140293D01*
G01X14980Y130118D02*
X18897D01*
G01Y131890D02*
X16243D01*
G01X18897Y133268D02*
X15143D01*
G01X18897Y135039D02*
X16243D01*
G01X18897Y136417D02*
X15143D01*
G01X18897Y138189D02*
X16161D01*
G01X14980Y139567D02*
X18897D01*
G01X19291Y140079D02*
X18109D01*
G01X17714Y140709D02*
X15041D01*
G01X18897Y141339D02*
X16243D01*
G01X18897Y142717D02*
X15143D01*
G01X15041Y143150D02*
X17714D01*
G01X19291Y143780D02*
X18109D01*
G01X18897Y144488D02*
X16161D01*
G01X18109Y145079D02*
X19291D01*
G01Y143565D02*
X17765Y143156D01*
G01X18931Y149019D02*
X18897Y149016D01*
G01X18964Y149028D02*
X18931Y149019D01*
G01X18995Y149042D02*
X18964Y149028D01*
G01X18931Y152168D02*
X18897Y152165D01*
G01X18964Y152177D02*
X18931Y152168D01*
G01X18995Y152192D02*
X18964Y152177D01*
G01X18931Y158467D02*
X18897Y158465D01*
G01X18964Y158476D02*
X18931Y158467D01*
G01X18995Y158491D02*
X18964Y158476D01*
G01X18931Y161617D02*
X18897Y161614D01*
G01X18964Y161626D02*
X18931Y161617D01*
G01X18995Y161641D02*
X18964Y161626D01*
G01X18897Y145866D02*
G03X18995Y145893I-1J197D01*
G01X14485Y145315D02*
G03X14624Y145372I0J197D01*
G01X15041Y145709D02*
G03X14902Y145651I1J-197D01*
G01X17765Y145702D02*
G03X17714Y145709I-52J-190D01*
G01X15004Y149073D02*
G03X15143Y149016I138J140D01*
G01X14922Y149155D02*
G03X14783Y149213I-140J-139D01*
G01X15882Y147441D02*
G03X16022Y147498I1J197D01*
G01X16243Y147638D02*
G03X16103Y147580I0J-197D01*
G01X18995Y147611D02*
G03X18897Y147638I-100J-170D01*
G01X15004Y152223D02*
G03X15143Y152165I140J139D01*
G01X14922Y152304D02*
G03X14783Y152362I-139J-139D01*
G01X15882Y150591D02*
G03X16022Y150648I2J197D01*
G01X16243Y150787D02*
G03X16103Y150730I-1J-197D01*
G01X18995Y150761D02*
G03X18897Y150787I-98J-171D01*
G01X18995Y153911D02*
G03X18897Y153937I-98J-171D01*
G01Y155315D02*
G03X18995Y155341I0J197D01*
G01X15882Y156890D02*
G03X16022Y156947I1J197D01*
G01X16243Y157087D02*
G03X16103Y157029I0J-197D01*
G01X18995Y157060D02*
G03X18897Y157087I-100J-170D01*
G01X17714Y148150D02*
G03X17765Y148156I3J197D01*
G01X14902Y148207D02*
G03X15041Y148150I138J140D01*
G01X14624Y148485D02*
G03X14485Y148543I-139J-139D01*
G01Y155315D02*
G03X14624Y155372I0J197D01*
G01X15041Y155709D02*
G03X14902Y155651I1J-197D01*
G01X17765Y155702D02*
G03X17714Y155709I-52J-190D01*
G01Y153150D02*
G03X17765Y153156I3J197D01*
G01X14902Y153207D02*
G03X15041Y153150I138J140D01*
G01X14624Y153485D02*
G03X14485Y153543I-139J-139D01*
G01Y150315D02*
G03X14624Y150372I0J197D01*
G01X15041Y150709D02*
G03X14902Y150651I1J-197D01*
G01X17765Y150702D02*
G03X17714Y150709I-52J-190D01*
G01X15004Y158522D02*
G03X15143Y158465I138J140D01*
G01X14922Y158604D02*
G03X14783Y158661I-139J-140D01*
G01X15004Y161672D02*
G03X15143Y161614I139J139D01*
G01X14922Y161753D02*
G03X14783Y161811I-140J-139D01*
G01X15882Y160039D02*
G03X16022Y160097I0J197D01*
G01X16243Y160236D02*
G03X16103Y160178I0J-197D01*
G01X18995Y160210D02*
G03X18897Y160236I-98J-171D01*
G01X14485Y160315D02*
G03X14624Y160372I0J197D01*
G01X15041Y160709D02*
G03X14902Y160651I1J-197D01*
G01X17765Y160702D02*
G03X17714Y160709I-52J-190D01*
G01Y158150D02*
G03X17765Y158156I3J197D01*
G01X14902Y158207D02*
G03X15041Y158150I138J140D01*
G01X14624Y158485D02*
G03X14485Y158543I-139J-139D01*
G01X14624Y160372D02*
X14902Y160651D01*
G01X16022Y160097D02*
X16103Y160178D01*
G01X16022Y156947D02*
X16103Y157029D01*
G01X14624Y155372D02*
X14902Y155651D01*
G01X15964Y153740D02*
X16161Y153937D01*
G01X14624Y150372D02*
X14902Y150651D01*
G01X16022Y150648D02*
X16103Y150730D01*
G01X16022Y147498D02*
X16103Y147580D01*
G01X14624Y145372D02*
X14902Y145651D01*
G01X18109Y150079D02*
Y148780D01*
G01Y160079D02*
Y158780D01*
G01Y153780D02*
Y155079D01*
G01X19291Y161811D02*
X18995Y161641D01*
G01X19291Y158661D02*
X18995Y158491D01*
G01X19291Y155512D02*
X18995Y155341D01*
G01X19291Y152362D02*
X18995Y152192D01*
G01X19291Y149213D02*
X18995Y149042D01*
G01X19291Y146063D02*
X18995Y145893D01*
G01X14980Y145866D02*
X14783Y146063D01*
G01X14902Y148207D02*
X14624Y148485D01*
G01X15004Y149073D02*
X14922Y149155D01*
G01X15004Y152223D02*
X14922Y152304D01*
G01X14902Y153207D02*
X14624Y153485D01*
G01X14980Y155315D02*
X14783Y155512D01*
G01X14902Y158207D02*
X14624Y158485D01*
G01X15004Y158522D02*
X14922Y158604D01*
G01X15004Y161672D02*
X14922Y161753D01*
G01X18995Y147611D02*
X19291Y147441D01*
G01X18995Y150761D02*
X19291Y150591D01*
G01X18995Y153911D02*
X19291Y153740D01*
G01X18995Y157060D02*
X19291Y156890D01*
G01X18995Y160210D02*
X19291Y160039D01*
G01X17765Y145702D02*
X19291Y145293D01*
G01X17765Y150702D02*
X19291Y150293D01*
G01X17765Y155702D02*
X19291Y155293D01*
G01X17765Y160702D02*
X19291Y160293D01*
G01X17714Y145709D02*
X15041D01*
G01X14980Y145866D02*
X18897D01*
G01Y147638D02*
X16243D01*
G01X15041Y148150D02*
X17714D01*
G01X18109Y148780D02*
X19291D01*
G01X18897Y149016D02*
X15143D01*
G01X18109Y150079D02*
X19291D01*
G01X17714Y150709D02*
X15041D01*
G01X18897Y150787D02*
X16243D01*
G01X18897Y152165D02*
X15143D01*
G01X15041Y153150D02*
X17714D01*
G01X18109Y153780D02*
X19291D01*
G01X18897Y153937D02*
X16161D01*
G01X18109Y155079D02*
X19291D01*
G01X14980Y155315D02*
X18897D01*
G01X17714Y155709D02*
X15041D01*
G01X18897Y157087D02*
X16243D01*
G01X15041Y158150D02*
X17714D01*
G01X18897Y158465D02*
X15143D01*
G01X19291Y158780D02*
X18109D01*
G01Y160079D02*
X19291D01*
G01X18897Y160236D02*
X16243D01*
G01X17714Y160709D02*
X15041D01*
G01X18897Y161614D02*
X15143D01*
G01X19291Y148565D02*
X17765Y148156D01*
G01X19291Y153565D02*
X17765Y153156D01*
G01X18931Y158467D02*
X17765Y158156D01*
G01X19291Y158565D02*
X18964Y158476D01*
G01X18931Y167916D02*
X18897Y167913D01*
G01X18964Y167925D02*
X18931Y167916D01*
G01X18995Y167940D02*
X18964Y167925D01*
G01X18931Y171066D02*
X18897Y171063D01*
G01X18964Y171075D02*
X18931Y171066D01*
G01X18995Y171089D02*
X18964Y171075D01*
G01X18931Y177365D02*
X18897Y177362D01*
G01X18964Y177374D02*
X18931Y177365D01*
G01X18995Y177389D02*
X18964Y177374D01*
G01X18995Y163359D02*
G03X18897Y163386I-100J-170D01*
G01Y164764D02*
G03X18995Y164790I0J197D01*
G01X15004Y167971D02*
G03X15143Y167913I140J139D01*
G01X14922Y168052D02*
G03X14783Y168110I-139J-139D01*
G01X15882Y166339D02*
G03X16022Y166396I2J197D01*
G01X16243Y166535D02*
G03X16103Y166478I-1J-197D01*
G01X18995Y166509D02*
G03X18897Y166535I-98J-171D01*
G01X17714Y168150D02*
G03X17765Y168156I3J197D01*
G01X14902Y168207D02*
G03X15041Y168150I138J140D01*
G01X14624Y168485D02*
G03X14485Y168543I-139J-139D01*
G01Y165315D02*
G03X14624Y165372I0J197D01*
G01X15041Y165709D02*
G03X14902Y165651I1J-197D01*
G01X17765Y165702D02*
G03X17714Y165709I-52J-190D01*
G01Y163150D02*
G03X17765Y163156I3J197D01*
G01X14902Y163207D02*
G03X15041Y163150I138J140D01*
G01X14624Y163485D02*
G03X14485Y163543I-139J-139D01*
G01X15004Y171120D02*
G03X15143Y171063I139J140D01*
G01X14922Y171202D02*
G03X14783Y171260I-140J-139D01*
G01X15004Y177420D02*
G03X15143Y177362I139J139D01*
G01X14922Y177501D02*
G03X14783Y177559I-140J-139D01*
G01X14902Y178207D02*
G03X15041Y178150I138J140D01*
G01X14485Y175315D02*
G03X14624Y175372I0J197D01*
G01X15041Y175709D02*
G03X14902Y175651I1J-197D01*
G01Y173207D02*
G03X15041Y173150I138J140D01*
G01X14624Y173485D02*
G03X14485Y173543I-139J-139D01*
G01Y170315D02*
G03X14624Y170372I0J197D01*
G01X15041Y170709D02*
G03X14902Y170651I1J-197D01*
G01X15882Y169488D02*
G03X16022Y169546I0J197D01*
G01X16243Y169685D02*
G03X16103Y169627I0J-197D01*
G01X18995Y169659D02*
G03X18897Y169685I-98J-171D01*
G01X18995Y172808D02*
G03X18897Y172835I-100J-170D01*
G01Y174213D02*
G03X18995Y174239I0J197D01*
G01X15882Y175787D02*
G03X16022Y175845I0J197D01*
G01X16243Y175984D02*
G03X16103Y175926I0J-197D01*
G01X18995Y175958D02*
G03X18897Y175984I-98J-171D01*
G01X17714Y178150D02*
G03X17765Y178156I3J197D01*
G01Y175702D02*
G03X17714Y175709I-52J-190D01*
G01Y173150D02*
G03X17765Y173156I3J197D01*
G01Y170702D02*
G03X17714Y170709I-52J-190D01*
G01X14624Y175372D02*
X14902Y175651D01*
G01X16022Y175845D02*
X16103Y175926D01*
G01X15964Y172638D02*
X16161Y172835D01*
G01X14624Y170372D02*
X14902Y170651D01*
G01X16022Y169546D02*
X16103Y169627D01*
G01X14624Y165372D02*
X14902Y165651D01*
G01X16022Y166396D02*
X16103Y166478D01*
G01X15964Y163189D02*
X16161Y163386D01*
G01X19291Y177559D02*
X18995Y177389D01*
G01X19291Y174409D02*
X18995Y174239D01*
G01X19291Y171260D02*
X18995Y171089D01*
G01X19291Y168110D02*
X18995Y167940D01*
G01X19291Y164961D02*
X18995Y164790D01*
G01X18109Y170079D02*
Y168780D01*
G01Y175079D02*
Y173780D01*
G01Y163780D02*
Y165079D01*
G01X14902Y163207D02*
X14624Y163485D01*
G01X14980Y164764D02*
X14783Y164961D01*
G01X15004Y167971D02*
X14922Y168052D01*
G01X14902Y168207D02*
X14624Y168485D01*
G01X15004Y171120D02*
X14922Y171202D01*
G01X14902Y173207D02*
X14624Y173485D01*
G01X14980Y174213D02*
X14783Y174409D01*
G01X15004Y177420D02*
X14922Y177501D01*
G01X14902Y178207D02*
X14624Y178485D01*
G01X18995Y163359D02*
X19291Y163189D01*
G01X18995Y166509D02*
X19291Y166339D01*
G01X18995Y169659D02*
X19291Y169488D01*
G01X18995Y172808D02*
X19291Y172638D01*
G01X18995Y175958D02*
X19291Y175787D01*
G01X17765Y165702D02*
X19291Y165293D01*
G01X17765Y170702D02*
X19291Y170293D01*
G01X17765Y175702D02*
X19291Y175293D01*
G01X15041Y163150D02*
X17714D01*
G01X18897Y163386D02*
X16161D01*
G01X18109Y163780D02*
X19291D01*
G01X14980Y164764D02*
X18897D01*
G01X19291Y165079D02*
X18109D01*
G01X17714Y165709D02*
X15041D01*
G01X18897Y166535D02*
X16243D01*
G01X18897Y167913D02*
X15143D01*
G01X15041Y168150D02*
X17714D01*
G01X18109Y168780D02*
X19291D01*
G01X16243Y169685D02*
X18897D01*
G01X19291Y170079D02*
X18109D01*
G01X17714Y170709D02*
X15041D01*
G01X15143Y171063D02*
X18897D01*
G01Y172835D02*
X16161D01*
G01X15041Y173150D02*
X17714D01*
G01X18109Y173780D02*
X19291D01*
G01X14980Y174213D02*
X18897D01*
G01X18109Y175079D02*
X19291D01*
G01X17714Y175709D02*
X15041D01*
G01X18897Y175984D02*
X16243D01*
G01X18897Y177362D02*
X15143D01*
G01X15041Y178150D02*
X17714D01*
G01X19291Y163565D02*
X17765Y163156D01*
G01X19291Y168565D02*
X17765Y168156D01*
G01X19291Y173565D02*
X17765Y173156D01*
G01X19291Y178565D02*
X17765Y178156D01*
G01X18931Y180515D02*
X18897Y180512D01*
G01X18964Y180524D02*
X18931Y180515D01*
G01X18995Y180538D02*
X18964Y180524D01*
G01X18931Y186814D02*
X18897Y186811D01*
G01X18964Y186823D02*
X18931Y186814D01*
G01X18995Y186837D02*
X18964Y186823D01*
G01X18931Y189963D02*
X18897Y189961D01*
G01X18964Y189972D02*
X18931Y189963D01*
G01X18995Y189987D02*
X18964Y189972D01*
G01X14624Y178485D02*
G03X14485Y178543I-139J-139D01*
G01X15004Y180569D02*
G03X15143Y180512I138J140D01*
G01X14922Y180651D02*
G03X14783Y180709I-140J-139D01*
G01X15004Y186869D02*
G03X15143Y186811I139J139D01*
G01X14922Y186950D02*
G03X14783Y187008I-140J-139D01*
G01X15004Y190018D02*
G03X15143Y189961I138J140D01*
G01X14922Y190100D02*
G03X14783Y190158I-140J-139D01*
G01X14485Y190315D02*
G03X14624Y190372I0J197D01*
G01X15041Y190709D02*
G03X14902Y190651I1J-197D01*
G01Y188207D02*
G03X15041Y188150I138J140D01*
G01X14624Y188485D02*
G03X14485Y188543I-139J-139D01*
G01Y185315D02*
G03X14624Y185372I0J197D01*
G01X15041Y185709D02*
G03X14902Y185651I1J-197D01*
G01Y183207D02*
G03X15041Y183150I138J140D01*
G01X14624Y183485D02*
G03X14485Y183543I-139J-139D01*
G01Y180315D02*
G03X14624Y180372I0J197D01*
G01X15041Y180709D02*
G03X14902Y180651I1J-197D01*
G01Y193207D02*
G03X15041Y193150I138J140D01*
G01X14624Y193485D02*
G03X14485Y193543I-139J-139D01*
G01X15882Y178937D02*
G03X16022Y178995I1J197D01*
G01X16243Y179134D02*
G03X16103Y179076I0J-197D01*
G01X18995Y179108D02*
G03X18897Y179134I-98J-171D01*
G01X18995Y182257D02*
G03X18897Y182283I-98J-171D01*
G01Y183661D02*
G03X18995Y183688I-1J197D01*
G01X15882Y185236D02*
G03X16022Y185294I0J197D01*
G01X16243Y185433D02*
G03X16103Y185375I0J-197D01*
G01X18995Y185407D02*
G03X18897Y185433I-98J-171D01*
G01X15882Y188386D02*
G03X16022Y188443I1J197D01*
G01X16243Y188583D02*
G03X16103Y188525I0J-197D01*
G01X18995Y188556D02*
G03X18897Y188583I-100J-170D01*
G01X17765Y190702D02*
G03X17714Y190709I-52J-190D01*
G01Y188150D02*
G03X17765Y188156I3J197D01*
G01Y185702D02*
G03X17714Y185709I-52J-190D01*
G01Y183150D02*
G03X17765Y183156I3J197D01*
G01Y180702D02*
G03X17714Y180709I-52J-190D01*
G01X18995Y191706D02*
G03X18897Y191732I-98J-171D01*
G01Y193110D02*
G03X18995Y193137I-1J197D01*
G01X15882Y194685D02*
G03X16022Y194743I1J197D01*
G01X17714Y193150D02*
G03X17765Y193156I3J197D01*
G01X16022Y194743D02*
X16103Y194824D01*
G01X14624Y190372D02*
X14902Y190651D01*
G01X15964Y191535D02*
X16161Y191732D01*
G01X16022Y188443D02*
X16103Y188525D01*
G01X14624Y185372D02*
X14902Y185651D01*
G01X16022Y185294D02*
X16103Y185375D01*
G01X19291Y193307D02*
X18995Y193137D01*
G01X19291Y190158D02*
X18995Y189987D01*
G01X19291Y187008D02*
X18995Y186837D01*
G01X19291Y183858D02*
X18995Y183688D01*
G01X15964Y182087D02*
X16161Y182283D01*
G01X14624Y180372D02*
X14902Y180651D01*
G01X16022Y178995D02*
X16103Y179076D01*
G01X19291Y180709D02*
X18995Y180538D01*
G01X18109Y185079D02*
Y183780D01*
G01Y190079D02*
Y188780D01*
G01Y195079D02*
Y193780D01*
G01Y178780D02*
Y180079D01*
G01X15004Y180569D02*
X14922Y180651D01*
G01X14902Y183207D02*
X14624Y183485D01*
G01X14980Y183661D02*
X14783Y183858D01*
G01X15004Y186869D02*
X14922Y186950D01*
G01X14902Y188207D02*
X14624Y188485D01*
G01X15004Y190018D02*
X14922Y190100D01*
G01X14980Y193110D02*
X14783Y193307D01*
G01X14902Y193207D02*
X14624Y193485D01*
G01X18995Y179108D02*
X19291Y178937D01*
G01X18995Y182257D02*
X19291Y182087D01*
G01X18995Y185407D02*
X19291Y185236D01*
G01X18995Y188556D02*
X19291Y188386D01*
G01X18995Y191706D02*
X19291Y191535D01*
G01X18995Y194856D02*
X19291Y194685D01*
G01X17765Y180702D02*
X19291Y180293D01*
G01X17765Y185702D02*
X19291Y185293D01*
G01X17765Y190702D02*
X19291Y190293D01*
G01X18109Y178780D02*
X19291D01*
G01X18897Y179134D02*
X16243D01*
G01X19291Y180079D02*
X18109D01*
G01X18897Y180512D02*
X15143D01*
G01X17714Y180709D02*
X15041D01*
G01X18897Y182283D02*
X16161D01*
G01X15041Y183150D02*
X17714D01*
G01X14980Y183661D02*
X18897D01*
G01X18109Y183780D02*
X19291D01*
G01Y185079D02*
X18109D01*
G01X18897Y185433D02*
X16243D01*
G01X17714Y185709D02*
X15041D01*
G01X18897Y186811D02*
X15143D01*
G01X15041Y188150D02*
X17714D01*
G01X18897Y188583D02*
X16243D01*
G01X19291Y188780D02*
X18109D01*
G01X18897Y189961D02*
X15143D01*
G01X19291Y190079D02*
X18109D01*
G01X17714Y190709D02*
X15041D01*
G01X18897Y191732D02*
X16161D01*
G01X14980Y193110D02*
X18897D01*
G01X15041Y193150D02*
X17714D01*
G01X19291Y193780D02*
X18109D01*
G01X19291Y183565D02*
X17765Y183156D01*
G01X19291Y188565D02*
X17765Y188156D01*
G01X19291Y193565D02*
X17765Y193156D01*
G01X18931Y196263D02*
X18897Y196260D01*
G01X18964Y196272D02*
X18931Y196263D01*
G01X18995Y196286D02*
X18964Y196272D01*
G01X18931Y199412D02*
X18897Y199409D01*
G01X18964Y199421D02*
X18931Y199412D01*
G01X18995Y199436D02*
X18964Y199421D01*
G01X18931Y205711D02*
X18897Y205709D01*
G01X18964Y205720D02*
X18931Y205711D01*
G01X18995Y205735D02*
X18964Y205720D01*
G01X18931Y208861D02*
X18897Y208858D01*
G01X18964Y208870D02*
X18931Y208861D01*
G01X18995Y208885D02*
X18964Y208870D01*
G01X15004Y196317D02*
G03X15143Y196260I138J140D01*
G01X14922Y196399D02*
G03X14783Y196457I-140J-139D01*
G01X15004Y199467D02*
G03X15143Y199409I140J139D01*
G01X14922Y199548D02*
G03X14783Y199606I-139J-139D01*
G01X14485Y200315D02*
G03X14624Y200372I0J197D01*
G01X15041Y200709D02*
G03X14902Y200651I1J-197D01*
G01Y198207D02*
G03X15041Y198150I138J140D01*
G01X14624Y198485D02*
G03X14485Y198543I-139J-139D01*
G01Y195315D02*
G03X14624Y195372I0J197D01*
G01X15041Y195709D02*
G03X14902Y195651I1J-197D01*
G01X15004Y205766D02*
G03X15143Y205709I138J140D01*
G01X14922Y205848D02*
G03X14783Y205906I-140J-139D01*
G01X15004Y208916D02*
G03X15143Y208858I139J139D01*
G01X14922Y208997D02*
G03X14783Y209055I-140J-139D01*
G01X14485Y210315D02*
G03X14624Y210372I0J197D01*
G01X15041Y210709D02*
G03X14902Y210651I1J-197D01*
G01Y208207D02*
G03X15041Y208150I138J140D01*
G01X14624Y208485D02*
G03X14485Y208543I-139J-139D01*
G01Y205315D02*
G03X14624Y205372I0J197D01*
G01X15041Y205709D02*
G03X14902Y205651I1J-197D01*
G01Y203207D02*
G03X15041Y203150I138J140D01*
G01X14624Y203485D02*
G03X14485Y203543I-139J-139D01*
G01X16243Y194882D02*
G03X16103Y194824I0J-197D01*
G01X18995Y194856D02*
G03X18897Y194882I-98J-171D01*
G01X15882Y197835D02*
G03X16022Y197892I2J197D01*
G01X16243Y198032D02*
G03X16103Y197974I0J-197D01*
G01X18995Y198005D02*
G03X18897Y198032I-100J-170D01*
G01X18995Y201155D02*
G03X18897Y201181I-98J-171D01*
G01X17765Y200702D02*
G03X17714Y200709I-52J-190D01*
G01Y198150D02*
G03X17765Y198156I3J197D01*
G01Y195702D02*
G03X17714Y195709I-52J-190D01*
G01X18897Y202559D02*
G03X18995Y202585I0J197D01*
G01X15882Y204134D02*
G03X16022Y204191I1J197D01*
G01X16243Y204331D02*
G03X16103Y204273I0J-197D01*
G01X18995Y204304D02*
G03X18897Y204331I-100J-170D01*
G01X15882Y207283D02*
G03X16022Y207341I0J197D01*
G01X16243Y207480D02*
G03X16103Y207422I0J-197D01*
G01X18995Y207454D02*
G03X18897Y207480I-98J-171D01*
G01X18995Y210604D02*
G03X18897Y210630I-98J-171D01*
G01X17765Y210702D02*
G03X17714Y210709I-52J-190D01*
G01Y208150D02*
G03X17765Y208156I3J197D01*
G01Y205702D02*
G03X17714Y205709I-52J-190D01*
G01Y203150D02*
G03X17765Y203156I3J197D01*
G01X14624Y210372D02*
X14902Y210651D01*
G01X15964Y210433D02*
X16161Y210630D01*
G01X16022Y207341D02*
X16103Y207422D01*
G01X14624Y205372D02*
X14902Y205651D01*
G01X19291Y209055D02*
X18995Y208885D01*
G01X19291Y205906D02*
X18995Y205735D01*
G01X19291Y202756D02*
X18995Y202585D01*
G01X16022Y204191D02*
X16103Y204273D01*
G01X14624Y200372D02*
X14902Y200651D01*
G01X15964Y200984D02*
X16161Y201181D01*
G01X16022Y197892D02*
X16103Y197974D01*
G01X14624Y195372D02*
X14902Y195651D01*
G01X19291Y199606D02*
X18995Y199436D01*
G01X19291Y196457D02*
X18995Y196286D01*
G01X18109Y200079D02*
Y198780D01*
G01Y205079D02*
Y203780D01*
G01Y210079D02*
Y208780D01*
G01X15004Y196317D02*
X14922Y196399D01*
G01X14902Y198207D02*
X14624Y198485D01*
G01X15004Y199467D02*
X14922Y199548D01*
G01X14980Y202559D02*
X14783Y202756D01*
G01X14902Y203207D02*
X14624Y203485D01*
G01X15004Y205766D02*
X14922Y205848D01*
G01X14902Y208207D02*
X14624Y208485D01*
G01X15004Y208916D02*
X14922Y208997D01*
G01X18995Y198005D02*
X19291Y197835D01*
G01X18995Y201155D02*
X19291Y200984D01*
G01X18995Y204304D02*
X19291Y204134D01*
G01X18995Y207454D02*
X19291Y207283D01*
G01X18995Y210604D02*
X19291Y210433D01*
G01X17765Y195702D02*
X19291Y195293D01*
G01X17765Y200702D02*
X19291Y200293D01*
G01X17765Y205702D02*
X19291Y205293D01*
G01X17765Y210702D02*
X19291Y210293D01*
G01X18897Y194882D02*
X16243D01*
G01X19291Y195079D02*
X18109D01*
G01X17714Y195709D02*
X15041D01*
G01X18897Y196260D02*
X15143D01*
G01X18897Y198032D02*
X16243D01*
G01X15041Y198150D02*
X17714D01*
G01X19291Y198780D02*
X18109D01*
G01X18897Y199409D02*
X15143D01*
G01X19291Y200079D02*
X18109D01*
G01X17714Y200709D02*
X15041D01*
G01X18897Y201181D02*
X16161D01*
G01X14980Y202559D02*
X18897D01*
G01X15041Y203150D02*
X17714D01*
G01X19291Y203780D02*
X18109D01*
G01X18897Y204331D02*
X16243D01*
G01X18109Y205079D02*
X19291D01*
G01X15143Y205709D02*
X15041D01*
G01X18897D02*
X15143D01*
G01X18897Y207480D02*
X16243D01*
G01X15041Y208150D02*
X17714D01*
G01X18109Y208780D02*
X19291D01*
G01X18897Y208858D02*
X15143D01*
G01X18109Y210079D02*
X19291D01*
G01X18897Y210630D02*
X16161D01*
G01X17714Y210709D02*
X15041D01*
G01X19291Y198565D02*
X17765Y198156D01*
G01X19291Y203565D02*
X17765Y203156D01*
G01X19291Y208565D02*
X17765Y208156D01*
G01X18897Y212008D02*
G03X18995Y212034I0J197D01*
G01X23228Y214035D02*
G03X21259Y212067I-1J-1968D01*
G01X23228Y214035D02*
G03X21259Y212067I-1J-1968D01*
G01X17714Y213150D02*
G03X17765Y213156I3J197D01*
G01X14902Y213207D02*
G03X15041Y213150I138J140D01*
G01X14624Y213485D02*
G03X14485Y213543I-139J-139D01*
G01X23228Y214035D02*
G03X21259Y212067I-1J-1968D01*
G01X23228Y214035D02*
G03X21259Y212067I-1J-1968D01*
G01X26771Y219012D02*
X19291Y215524D01*
G01Y212205D02*
X18995Y212034D01*
G01X18109Y213780D02*
Y215236D01*
G01X14980Y212008D02*
X14783Y212205D01*
G01X14902Y213207D02*
X14624Y213485D01*
G01X17322Y222638D02*
X19291Y220669D01*
G01X14980Y212008D02*
X18897D01*
G01X15041Y213150D02*
X17714D01*
G01X19291Y213780D02*
X18109D01*
G01X19291Y213565D02*
X17765Y213156D01*
G01X23228Y214036D02*
G03X21259Y212067I0J-1969D01*
G01X11408Y240082D02*
X11417Y240100D01*
G01X11309Y240050D02*
X11408Y240082D01*
G01X11105Y240040D02*
X11309Y240050D01*
G01X18904Y238929D02*
X18898Y238956D01*
G01X18976Y238883D02*
X18904Y238929D01*
G01X19108Y238863D02*
X18976Y238883D01*
G01X19289Y238858D02*
X19108Y238863D01*
G01X11029Y240810D02*
X10845Y241330D01*
G01X11213Y240400D02*
X11029Y240810D01*
G01X11398Y240135D02*
X11213Y240400D01*
G01X11416Y238961D02*
X11417Y238956D01*
G01X11398Y239011D02*
X11416Y238961D01*
G01X10828Y241407D02*
X10826Y241446D01*
G01X10834Y241368D02*
X10828Y241407D01*
G01X10845Y241330D02*
X10834Y241368D01*
G01X19074Y240044D02*
X19255Y240040D01*
G01X18954Y240059D02*
X19074Y240044D01*
G01X18900Y240089D02*
X18954Y240059D01*
G01X18897Y240100D02*
X18900Y240089D01*
G01X11213Y239435D02*
X11398Y239011D01*
G01X11029Y240092D02*
X11213Y239435D01*
G01X10845Y240924D02*
X11029Y240092D01*
G01X10834Y240985D02*
X10845Y240924D01*
G01X10828Y241047D02*
X10834Y240985D01*
G01X10826Y241110D02*
X10828Y241047D01*
G01X19479Y241368D02*
X19469Y241330D01*
G01X19485Y241407D02*
X19479Y241368D01*
G01X19487Y241446D02*
X19485Y241407D01*
G01Y241047D02*
X19487Y241110D01*
G01X19479Y240985D02*
X19485Y241047D01*
G01X19469Y240924D02*
X19479Y240985D01*
G01X19100Y240400D02*
X18916Y240135D01*
G01X19284Y240810D02*
X19100Y240400D01*
G01X19469Y241330D02*
X19284Y240810D01*
G01X11124Y238860D02*
X11026Y238858D01*
G01X11217Y238864D02*
X11124Y238860D01*
G01X11298Y238874D02*
X11217Y238864D01*
G01X11363Y238892D02*
X11298Y238874D01*
G01X11404Y238921D02*
X11363Y238892D01*
G01X11417Y238956D02*
X11404Y238921D01*
G01X19284Y240092D02*
X19469Y240924D01*
G01X19100Y239435D02*
X19284Y240092D01*
G01X18916Y239011D02*
X19100Y239435D01*
G01X22401Y240472D02*
X22007Y240079D01*
G01X18916Y240135D02*
X18897Y240100D01*
G01X18898Y238956D02*
X18916Y239011D01*
G01X6850Y240039D02*
Y238858D01*
G01X7873Y230394D02*
Y233543D01*
G01X8149Y240039D02*
Y238858D01*
G01X8626Y240039D02*
Y238858D01*
G01X8711D02*
Y240039D01*
G01X8958D02*
Y238858D01*
G01X9961D02*
Y240039D01*
G01X10039D02*
Y238858D01*
G01X10235Y244370D02*
Y240079D01*
G01X10826Y240039D02*
Y238858D01*
G01Y241111D02*
Y247874D01*
G01X10845Y240924D02*
Y241330D01*
G01X11398Y240135D02*
Y239011D01*
G01X11417Y238956D02*
Y240100D01*
G01X12086Y240039D02*
Y238858D01*
G01X12480D02*
Y240039D01*
G01X13267Y238858D02*
Y240039D01*
G01X17046Y238858D02*
Y240039D01*
G01X17834Y238858D02*
Y240039D01*
G01X18228Y238858D02*
Y240039D01*
G01X18897Y240100D02*
Y238956D01*
G01X18916Y239011D02*
Y240135D01*
G01X19469Y241330D02*
Y240924D01*
G01X19487Y247874D02*
Y241111D01*
G01Y238858D02*
Y240039D01*
G01X20078Y240079D02*
Y244370D01*
G01X20275Y238858D02*
Y240039D01*
G01X20352D02*
Y238858D01*
G01X21356D02*
Y240039D01*
G01X21602D02*
Y238858D01*
G01X21687D02*
Y240039D01*
G01X22007Y240472D02*
Y238425D01*
G01X22165Y240039D02*
Y238858D01*
G01X22401Y238425D02*
Y240472D01*
G01X11417Y240100D02*
X11398Y240135D01*
G01X22401Y238425D02*
X22007Y238819D01*
G01Y238425D02*
X22401D01*
G01Y240472D02*
X22007D01*
G01X10235D02*
X20078D01*
G01Y240669D02*
X29921D01*
G01X20078Y241260D02*
X29921D01*
G01X10826Y242008D02*
X19487D01*
G01Y247874D02*
G03X18306Y249055I-1181J0D01*
G01X12007D02*
G03X10826Y247874I0J-1181D01*
G01X20078Y244370D02*
X29921D01*
G01X12007Y249055D02*
X18306D01*
G01X13591Y258071D02*
G03Y265945I0J3937D01*
G01X7874D02*
X208071D01*
G01X7874D02*
X208071D01*
G01D02*
X7874D01*
G01D02*
X288189D01*
G01X7874D02*
X208071D01*
G01X32578Y316181D02*
G03X18603I-6987J0D01*
G03X32578I6987J0D01*
G01D02*
G03X18603I-6987J0D01*
G03X32578I6987J0D01*
G01X41338D02*
G03X9843I-15748J0D01*
G03X41338I15747J0D01*
G01X32578D02*
G03X18603I-6987J0D01*
G03X32578I6987J0D01*
G01X41338D02*
G03X9843I-15748J0D01*
G03X41338I15747J0D01*
G01X25591Y323169D02*
G03Y309193I0J-6988D01*
G01X30727Y373984D02*
G03I-4291J0D01*
G01X13591Y363425D02*
G03Y371299I0J3937D01*
G01X341535Y363425D02*
X7874D01*
G01X341535D02*
X7874D01*
G01X341535D02*
X7874D01*
G01X341535D02*
X7874D01*
G01X341535D02*
X7874D01*
G01X10516Y613871D02*
X10986Y614501D01*
X11534Y614816D01*
X12161Y614921D01*
X12944Y614711D01*
X13492Y614186D01*
X13649Y613556D01*
X13571Y612926D01*
X13257Y612401D01*
X11691Y611351D01*
X10986Y610616D01*
X10516Y609566D01*
X10359Y608621D01*
X13649D01*
G01X38787Y-105354D02*
G03Y-113228I1J-3937D01*
G01D02*
X237000D01*
G01X37795Y-105354D02*
Y-62047D01*
G01X30314Y232736D02*
Y-105354D01*
G01X37795Y-62047D02*
X85039D01*
G01X82873Y984D02*
X30314D01*
G01X23464Y58819D02*
Y60000D01*
G01X24015Y54488D02*
Y64114D01*
G01X24054Y58819D02*
Y60000D01*
G01X29921Y64964D02*
Y54488D01*
G01X40354Y72657D02*
G03X35235I-2560J0D01*
G03X40354I2559J0D01*
G01X40747D02*
G03X34842I-2953J0D01*
G03X40747I2952J0D01*
G01X41014D02*
G03X34575I-3220J0D01*
G03X41014I3219J0D01*
G01X28346Y64114D02*
G03X30314Y66083I0J1968D01*
G01X28346Y64114D02*
G03X30314Y66083I0J1968D01*
G01X28346Y64114D02*
G03X30314Y66083I0J1968D01*
G01X28346Y64114D02*
G03X30314Y66083I0J1968D01*
G01X24015Y64114D02*
Y65315D01*
G01X26771Y79846D02*
Y68465D01*
G01X29133Y68071D02*
Y80866D01*
G01X29921Y65315D02*
Y64964D01*
G01Y83622D02*
Y65315D01*
G01X30314Y66083D02*
Y82815D01*
G01Y66083D02*
Y82815D01*
G01X31889Y65315D02*
Y83622D01*
G01X32283Y77382D02*
Y67933D01*
G01X26377Y65315D02*
X29133Y68071D01*
G01X46062Y65315D02*
X30155D01*
G01X41732Y67933D02*
X32283D01*
G01X26771Y69252D02*
X29921D01*
G01X34575Y72658D02*
X35235D01*
G01X41732Y77382D02*
X32283D01*
G01X30314Y66083D02*
Y82815D01*
G01X28346Y64114D02*
G03X30315Y66083I0J1969D01*
G01Y82815D02*
Y66083D01*
G01X36440Y95578D02*
X36467Y95609D01*
G01X36410Y95558D02*
X36440Y95578D01*
G01X36377Y95551D02*
X36410Y95558D01*
G01X31357Y93281D02*
X31331Y93249D01*
G01X31388Y93300D02*
X31357Y93281D01*
G01X31421Y93307D02*
X31388Y93300D01*
G01X31753Y92743D02*
X31780Y92774D01*
G01X31723Y92723D02*
X31753Y92743D01*
G01X31690Y92717D02*
X31723Y92723D01*
G01X37552Y91115D02*
X37526Y91084D01*
G01X37583Y91135D02*
X37552Y91115D01*
G01X37615Y91142D02*
X37583Y91135D01*
G01X36440Y90578D02*
X36467Y90609D01*
G01X36410Y90558D02*
X36440Y90578D01*
G01X36377Y90551D02*
X36410Y90558D01*
G01X31357Y88281D02*
X31331Y88249D01*
G01X31388Y88300D02*
X31357Y88281D01*
G01X31421Y88307D02*
X31388Y88300D01*
G01X31753Y87743D02*
X31780Y87774D01*
G01X31723Y87723D02*
X31753Y87743D01*
G01X31690Y87717D02*
X31723Y87723D01*
G01X37552Y86115D02*
X37526Y86084D01*
G01X37583Y86135D02*
X37552Y86115D01*
G01X37615Y86142D02*
X37583Y86135D01*
G01X36440Y85578D02*
X36467Y85609D01*
G01X36410Y85558D02*
X36440Y85578D01*
G01X36377Y85551D02*
X36410Y85558D01*
G01X32111Y95578D02*
X32085Y95609D01*
G01X32142Y95558D02*
X32111Y95578D01*
G01X32174Y95551D02*
X32142Y95558D01*
G01X37194Y93281D02*
X37221Y93249D01*
G01X37164Y93300D02*
X37194Y93281D01*
G01X37131Y93307D02*
X37164Y93300D01*
G01X36798Y92743D02*
X36772Y92774D01*
G01X36829Y92723D02*
X36798Y92743D01*
G01X36861Y92717D02*
X36829Y92723D01*
G01X30999Y91115D02*
X31026Y91084D01*
G01X30969Y91135D02*
X30999Y91115D01*
G01X30936Y91142D02*
X30969Y91135D01*
G01X32111Y90578D02*
X32085Y90609D01*
G01X32142Y90558D02*
X32111Y90578D01*
G01X32174Y90551D02*
X32142Y90558D01*
G01X37194Y88281D02*
X37221Y88249D01*
G01X37164Y88300D02*
X37194Y88281D01*
G01X37131Y88307D02*
X37164Y88300D01*
G01X36798Y87743D02*
X36772Y87774D01*
G01X36829Y87723D02*
X36798Y87743D01*
G01X36861Y87717D02*
X36829Y87723D01*
G01X30999Y86115D02*
X31026Y86084D01*
G01X30969Y86135D02*
X30999Y86115D01*
G01X30936Y86142D02*
X30969Y86135D01*
G01X32111Y85578D02*
X32085Y85609D01*
G01X32142Y85558D02*
X32111Y85578D01*
G01X32174Y85551D02*
X32142Y85558D01*
G01X37583Y92723D02*
X37615Y92717D01*
G01X37552Y92743D02*
X37583Y92723D01*
G01X37526Y92774D02*
X37552Y92743D01*
G01X36410Y93300D02*
X36377Y93307D01*
G01X36440Y93281D02*
X36410Y93300D01*
G01X36467Y93249D02*
X36440Y93281D01*
G01X31388Y95558D02*
X31421Y95551D01*
G01X31357Y95578D02*
X31388Y95558D01*
G01X31331Y95609D02*
X31357Y95578D01*
G01X37583Y87723D02*
X37615Y87717D01*
G01X37552Y87743D02*
X37583Y87723D01*
G01X37526Y87774D02*
X37552Y87743D01*
G01X36410Y88300D02*
X36377Y88307D01*
G01X36440Y88281D02*
X36410Y88300D01*
G01X36467Y88249D02*
X36440Y88281D01*
G01X31723Y91135D02*
X31690Y91142D01*
G01X31753Y91115D02*
X31723Y91135D01*
G01X31780Y91084D02*
X31753Y91115D01*
G01X31388Y90558D02*
X31421Y90551D01*
G01X31357Y90578D02*
X31388Y90558D01*
G01X31331Y90609D02*
X31357Y90578D01*
G01X37164Y85558D02*
X37131Y85551D01*
G01X37194Y85578D02*
X37164Y85558D01*
G01X37221Y85609D02*
X37194Y85578D01*
G01X36829Y86135D02*
X36861Y86142D01*
G01X36798Y86115D02*
X36829Y86135D01*
G01X36772Y86084D02*
X36798Y86115D01*
G01X37164Y90558D02*
X37131Y90551D01*
G01X37194Y90578D02*
X37164Y90558D01*
G01X37221Y90609D02*
X37194Y90578D01*
G01X36829Y91135D02*
X36861Y91142D01*
G01X36798Y91115D02*
X36829Y91135D01*
G01X36772Y91084D02*
X36798Y91115D01*
G01X32142Y88300D02*
X32174Y88307D01*
G01X32111Y88281D02*
X32142Y88300D01*
G01X32085Y88249D02*
X32111Y88281D01*
G01X30969Y87723D02*
X30936Y87717D01*
G01X30999Y87743D02*
X30969Y87723D01*
G01X31026Y87774D02*
X30999Y87743D01*
G01X37164Y95558D02*
X37131Y95551D01*
G01X37194Y95578D02*
X37164Y95558D01*
G01X37221Y95609D02*
X37194Y95578D01*
G01X31723Y86135D02*
X31690Y86142D01*
G01X31753Y86115D02*
X31723Y86135D01*
G01X31780Y86084D02*
X31753Y86115D01*
G01X31388Y85558D02*
X31421Y85551D01*
G01X31357Y85578D02*
X31388Y85558D01*
G01X31331Y85609D02*
X31357Y85578D01*
G01X32142Y93300D02*
X32174Y93307D01*
G01X32111Y93281D02*
X32142Y93300D01*
G01X32085Y93249D02*
X32111Y93281D01*
G01X30969Y92723D02*
X30936Y92717D01*
G01X30999Y92743D02*
X30969Y92723D01*
G01X31026Y92774D02*
X30999Y92743D01*
G01X23959Y87894D02*
G03X23582Y87815I-180J-79D01*
G01Y89154D02*
G03X23959Y89075I197J0D01*
G01Y91043D02*
G03X23582Y90964I-180J-79D01*
G01Y92303D02*
G03X23959Y92224I197J0D01*
G01Y94193D02*
G03X23582Y94114I-180J-79D01*
G01Y95453D02*
G03X23959Y95374I197J0D01*
G01X28941Y92913D02*
G03X29138Y92717I197J1D01*
G01Y91142D02*
G03X28941Y90945I0J-197D01*
G01Y87913D02*
G03X29138Y87717I197J1D01*
G01Y86142D02*
G03X28941Y85945I0J-197D01*
G01X30314Y82815D02*
G03X28346Y84783I-1968J0D01*
G01X30314Y82815D02*
G03X28346Y84783I-1968J0D01*
G01X30314Y82815D02*
G03X28346Y84783I-1968J0D01*
G01X30314Y82815D02*
G03X28346Y84783I-1968J0D01*
G01X26602Y94193D02*
X26681Y94350D01*
G01X27363D02*
X27284Y94193D01*
G01X26602Y91043D02*
X26681Y91201D01*
G01X27363D02*
X27284Y91043D01*
G01X26602Y87894D02*
X26681Y88051D01*
G01X27363D02*
X27284Y87894D01*
G01X23385Y84783D02*
Y83622D01*
G01Y214035D02*
Y84783D01*
G01X23582Y87815D02*
Y87296D01*
G01Y89682D02*
Y89154D01*
G01Y90964D02*
Y90445D01*
G01Y92831D02*
Y92303D01*
G01Y94114D02*
Y93595D01*
G01Y95981D02*
Y95453D01*
G01X24190Y94193D02*
Y95374D01*
G01Y91043D02*
Y92224D01*
G01Y87894D02*
Y89075D01*
G01X25043D02*
Y87894D01*
G01Y92224D02*
Y91043D01*
G01Y95374D02*
Y94193D01*
G01X25590Y214035D02*
Y84783D01*
G01Y83622D02*
Y84783D01*
G01X25724Y94193D02*
Y95374D01*
G01Y91043D02*
Y92224D01*
G01Y87894D02*
Y89075D01*
G01X27346Y94350D02*
Y95217D01*
G01Y91201D02*
Y92067D01*
G01Y88051D02*
Y88917D01*
G01X28028D02*
Y88051D01*
G01Y92067D02*
Y91201D01*
G01Y95217D02*
Y94350D01*
G01X28881D02*
Y95217D01*
G01Y91201D02*
Y92067D01*
G01Y88051D02*
Y88917D01*
G01X28941Y88898D02*
Y87913D01*
G01Y90945D02*
Y89961D01*
G01Y93898D02*
Y92913D01*
G01Y95945D02*
Y94961D01*
G01Y84961D02*
Y85945D01*
G01X29728Y87717D02*
Y86142D01*
G01Y91142D02*
Y92717D01*
G01X30482Y91142D02*
Y92717D01*
G01Y86142D02*
Y87717D01*
G01X31236D02*
Y86142D01*
G01Y92717D02*
Y91142D01*
G01X31637Y95217D02*
Y94350D01*
G01Y91201D02*
Y92067D01*
G01Y88051D02*
Y88917D01*
G01X37339Y87717D02*
Y86142D01*
G01Y92717D02*
Y91142D01*
G01X26681Y88917D02*
X26602Y89075D01*
G01X27284D02*
X27363Y88917D01*
G01X26681Y92067D02*
X26602Y92224D01*
G01X27284D02*
X27363Y92067D01*
G01X26681Y95217D02*
X26602Y95374D01*
G01X27284D02*
X27363Y95217D01*
G01X31331Y93249D02*
X31026Y92774D01*
G01X31780D02*
X32085Y93249D01*
G01X31331Y88249D02*
X31026Y87774D01*
G01X36467Y95609D02*
X36772Y96084D01*
G01X31780Y87774D02*
X32085Y88249D01*
G01X37526Y96084D02*
X37221Y95609D01*
G01X36467Y90609D02*
X36772Y91084D01*
G01X37526D02*
X37221Y90609D01*
G01X36467Y85609D02*
X36772Y86084D01*
G01X37526D02*
X37221Y85609D01*
G01X38093Y91142D02*
Y92717D01*
G01Y86142D02*
Y87717D01*
G01X38847Y91142D02*
Y92717D01*
G01Y86142D02*
Y87717D01*
G01X31026Y86084D02*
X31331Y85609D01*
G01X32085D02*
X31780Y86084D01*
G01X31026Y91084D02*
X31331Y90609D01*
G01X32085D02*
X31780Y91084D01*
G01X31026Y96084D02*
X31331Y95609D01*
G01X36772Y87774D02*
X36467Y88249D01*
G01X32085Y95609D02*
X31780Y96084D01*
G01X37221Y88249D02*
X37526Y87774D01*
G01X36772Y92774D02*
X36467Y93249D01*
G01X37221D02*
X37526Y92774D01*
G01X29133Y80866D02*
X26377Y83622D01*
G01X30128D02*
X46062D01*
G01X28346Y84783D02*
X23228D01*
G01X28346D02*
X23228D01*
G01X28941Y84961D02*
X25590D01*
G01X37131Y85551D02*
X31421D01*
G01X36467Y85609D02*
X37221D01*
G01X31331D02*
X32085D01*
G01X37526Y86084D02*
X36772D01*
G01X31026D02*
X31780D01*
G01X31690Y86142D02*
X29138D01*
G01X41603D02*
X36861D01*
G01X23582Y87296D02*
X23385D01*
G01X31690Y87717D02*
X29138D01*
G01X41603D02*
X36861D01*
G01X37526Y87774D02*
X36772D01*
G01X31026D02*
X31780D01*
G01X27284Y87894D02*
X23959D01*
G01X31637Y88051D02*
X26681D01*
G01X32085Y88249D02*
X31331D01*
G01X36467D02*
X37221D01*
G01X31421Y88307D02*
X37131D01*
G01X25590Y88898D02*
X28941D01*
G01X26681Y88917D02*
X31637D01*
G01X27284Y89075D02*
X23959D01*
G01X23385Y89682D02*
X23582D01*
G01X28941Y89961D02*
X25590D01*
G01X23582Y90445D02*
X23385D01*
G01X37131Y90551D02*
X31421D01*
G01X36467Y90609D02*
X37221D01*
G01X31331D02*
X32085D01*
G01X27284Y91043D02*
X23959D01*
G01X37526Y91084D02*
X36772D01*
G01X31026D02*
X31780D01*
G01X31690Y91142D02*
X29138D01*
G01X41603D02*
X36861D01*
G01X31637Y91201D02*
X26681D01*
G01Y92067D02*
X31637D01*
G01X27284Y92224D02*
X23959D01*
G01X31690Y92717D02*
X29138D01*
G01X41603D02*
X36861D01*
G01X37526Y92774D02*
X36772D01*
G01X31026D02*
X31780D01*
G01X23385Y92831D02*
X23582D01*
G01X32085Y93249D02*
X31331D01*
G01X36467D02*
X37221D01*
G01X31421Y93307D02*
X37131D01*
G01X23385Y93595D02*
X23582D01*
G01X28941Y93898D02*
X25590D01*
G01X27284Y94193D02*
X23959D01*
G01X31637Y94350D02*
X26681D01*
G01X28941Y94961D02*
X25590D01*
G01X26681Y95217D02*
X31637D01*
G01X27284Y95374D02*
X23959D01*
G01X37131Y95551D02*
X31421D01*
G01X32085Y95609D02*
X31331D01*
G01X36467D02*
X37221D01*
G01X28346Y84783D02*
X23228D01*
G01X28346D02*
X23228D01*
G01X30315Y82815D02*
G03X28346Y84784I-1969J0D01*
G01X23228D02*
X28346D01*
G01X37552Y111115D02*
X37526Y111084D01*
G01X37583Y111135D02*
X37552Y111115D01*
G01X37615Y111142D02*
X37583Y111135D01*
G01X36440Y110578D02*
X36467Y110609D01*
G01X36410Y110558D02*
X36440Y110578D01*
G01X36377Y110551D02*
X36410Y110558D01*
G01X31357Y108281D02*
X31331Y108249D01*
G01X31388Y108300D02*
X31357Y108281D01*
G01X31421Y108307D02*
X31388Y108300D01*
G01X31753Y107743D02*
X31780Y107774D01*
G01X31723Y107723D02*
X31753Y107743D01*
G01X31690Y107717D02*
X31723Y107723D01*
G01X37552Y106115D02*
X37526Y106084D01*
G01X37583Y106135D02*
X37552Y106115D01*
G01X37615Y106142D02*
X37583Y106135D01*
G01X36440Y105578D02*
X36467Y105609D01*
G01X36410Y105558D02*
X36440Y105578D01*
G01X36377Y105551D02*
X36410Y105558D01*
G01X31357Y103281D02*
X31331Y103249D01*
G01X31388Y103300D02*
X31357Y103281D01*
G01X31421Y103307D02*
X31388Y103300D01*
G01X31753Y102743D02*
X31780Y102774D01*
G01X31723Y102723D02*
X31753Y102743D01*
G01X31690Y102717D02*
X31723Y102723D01*
G01X37552Y101115D02*
X37526Y101084D01*
G01X37583Y101135D02*
X37552Y101115D01*
G01X37615Y101142D02*
X37583Y101135D01*
G01X36440Y100578D02*
X36467Y100609D01*
G01X36410Y100558D02*
X36440Y100578D01*
G01X36377Y100551D02*
X36410Y100558D01*
G01X31357Y98281D02*
X31331Y98249D01*
G01X31388Y98300D02*
X31357Y98281D01*
G01X31421Y98307D02*
X31388Y98300D01*
G01X31753Y97743D02*
X31780Y97774D01*
G01X31723Y97723D02*
X31753Y97743D01*
G01X31690Y97717D02*
X31723Y97723D01*
G01X37552Y96115D02*
X37526Y96084D01*
G01X37583Y96135D02*
X37552Y96115D01*
G01X37615Y96142D02*
X37583Y96135D01*
G01X30999Y111115D02*
X31026Y111084D01*
G01X30969Y111135D02*
X30999Y111115D01*
G01X30936Y111142D02*
X30969Y111135D01*
G01X32111Y110578D02*
X32085Y110609D01*
G01X32142Y110558D02*
X32111Y110578D01*
G01X32174Y110551D02*
X32142Y110558D01*
G01X37194Y108281D02*
X37221Y108249D01*
G01X37164Y108300D02*
X37194Y108281D01*
G01X37131Y108307D02*
X37164Y108300D01*
G01X36798Y107743D02*
X36772Y107774D01*
G01X36829Y107723D02*
X36798Y107743D01*
G01X36861Y107717D02*
X36829Y107723D01*
G01X30999Y106115D02*
X31026Y106084D01*
G01X30969Y106135D02*
X30999Y106115D01*
G01X30936Y106142D02*
X30969Y106135D01*
G01X32111Y105578D02*
X32085Y105609D01*
G01X32142Y105558D02*
X32111Y105578D01*
G01X32174Y105551D02*
X32142Y105558D01*
G01X37194Y103281D02*
X37221Y103249D01*
G01X37164Y103300D02*
X37194Y103281D01*
G01X37131Y103307D02*
X37164Y103300D01*
G01X36798Y102743D02*
X36772Y102774D01*
G01X36829Y102723D02*
X36798Y102743D01*
G01X36861Y102717D02*
X36829Y102723D01*
G01X30999Y101115D02*
X31026Y101084D01*
G01X30969Y101135D02*
X30999Y101115D01*
G01X30936Y101142D02*
X30969Y101135D01*
G01X32111Y100578D02*
X32085Y100609D01*
G01X32142Y100558D02*
X32111Y100578D01*
G01X32174Y100551D02*
X32142Y100558D01*
G01X37194Y98281D02*
X37221Y98249D01*
G01X37164Y98300D02*
X37194Y98281D01*
G01X37131Y98307D02*
X37164Y98300D01*
G01X36798Y97743D02*
X36772Y97774D01*
G01X36829Y97723D02*
X36798Y97743D01*
G01X36861Y97717D02*
X36829Y97723D01*
G01X30999Y96115D02*
X31026Y96084D01*
G01X30969Y96135D02*
X30999Y96115D01*
G01X30936Y96142D02*
X30969Y96135D01*
G01X37583Y107723D02*
X37615Y107717D01*
G01X37552Y107743D02*
X37583Y107723D01*
G01X37526Y107774D02*
X37552Y107743D01*
G01X36410Y108300D02*
X36377Y108307D01*
G01X36440Y108281D02*
X36410Y108300D01*
G01X36467Y108249D02*
X36440Y108281D01*
G01X31723Y111135D02*
X31690Y111142D01*
G01X31753Y111115D02*
X31723Y111135D01*
G01X31780Y111084D02*
X31753Y111115D01*
G01X31388Y110558D02*
X31421Y110551D01*
G01X31357Y110578D02*
X31388Y110558D01*
G01X31331Y110609D02*
X31357Y110578D01*
G01X37583Y102723D02*
X37615Y102717D01*
G01X37552Y102743D02*
X37583Y102723D01*
G01X37526Y102774D02*
X37552Y102743D01*
G01X36410Y103300D02*
X36377Y103307D01*
G01X36440Y103281D02*
X36410Y103300D01*
G01X36467Y103249D02*
X36440Y103281D01*
G01X31723Y106135D02*
X31690Y106142D01*
G01X31753Y106115D02*
X31723Y106135D01*
G01X31780Y106084D02*
X31753Y106115D01*
G01X31388Y105558D02*
X31421Y105551D01*
G01X31357Y105578D02*
X31388Y105558D01*
G01X31331Y105609D02*
X31357Y105578D01*
G01X37583Y97723D02*
X37615Y97717D01*
G01X37552Y97743D02*
X37583Y97723D01*
G01X37526Y97774D02*
X37552Y97743D01*
G01X36410Y98300D02*
X36377Y98307D01*
G01X36440Y98281D02*
X36410Y98300D01*
G01X36467Y98249D02*
X36440Y98281D01*
G01X31723Y101135D02*
X31690Y101142D01*
G01X31753Y101115D02*
X31723Y101135D01*
G01X31780Y101084D02*
X31753Y101115D01*
G01X31388Y100558D02*
X31421Y100551D01*
G01X31357Y100578D02*
X31388Y100558D01*
G01X31331Y100609D02*
X31357Y100578D01*
G01X31723Y96135D02*
X31690Y96142D01*
G01X31753Y96115D02*
X31723Y96135D01*
G01X31780Y96084D02*
X31753Y96115D01*
G01X36829Y96135D02*
X36861Y96142D01*
G01X36798Y96115D02*
X36829Y96135D01*
G01X36772Y96084D02*
X36798Y96115D01*
G01X37164Y100558D02*
X37131Y100551D01*
G01X37194Y100578D02*
X37164Y100558D01*
G01X37221Y100609D02*
X37194Y100578D01*
G01X36829Y101135D02*
X36861Y101142D01*
G01X36798Y101115D02*
X36829Y101135D01*
G01X36772Y101084D02*
X36798Y101115D01*
G01X32142Y98300D02*
X32174Y98307D01*
G01X32111Y98281D02*
X32142Y98300D01*
G01X32085Y98249D02*
X32111Y98281D01*
G01X30969Y97723D02*
X30936Y97717D01*
G01X30999Y97743D02*
X30969Y97723D01*
G01X31026Y97774D02*
X30999Y97743D01*
G01X37164Y105558D02*
X37131Y105551D01*
G01X37194Y105578D02*
X37164Y105558D01*
G01X37221Y105609D02*
X37194Y105578D01*
G01X36829Y106135D02*
X36861Y106142D01*
G01X36798Y106115D02*
X36829Y106135D01*
G01X36772Y106084D02*
X36798Y106115D01*
G01X32142Y103300D02*
X32174Y103307D01*
G01X32111Y103281D02*
X32142Y103300D01*
G01X32085Y103249D02*
X32111Y103281D01*
G01X30969Y102723D02*
X30936Y102717D01*
G01X30999Y102743D02*
X30969Y102723D01*
G01X31026Y102774D02*
X30999Y102743D01*
G01X37164Y110558D02*
X37131Y110551D01*
G01X37194Y110578D02*
X37164Y110558D01*
G01X37221Y110609D02*
X37194Y110578D01*
G01X36829Y111135D02*
X36861Y111142D01*
G01X36798Y111115D02*
X36829Y111135D01*
G01X36772Y111084D02*
X36798Y111115D01*
G01X32142Y108300D02*
X32174Y108307D01*
G01X32111Y108281D02*
X32142Y108300D01*
G01X32085Y108249D02*
X32111Y108281D01*
G01X30969Y107723D02*
X30936Y107717D01*
G01X30999Y107743D02*
X30969Y107723D01*
G01X31026Y107774D02*
X30999Y107743D01*
G01X23959Y100492D02*
G03X23582Y100413I-180J-79D01*
G01Y101752D02*
G03X23959Y101673I197J0D01*
G01Y97343D02*
G03X23582Y97263I-180J-79D01*
G01Y98602D02*
G03X23959Y98524I197J1D01*
G01X23582Y104902D02*
G03X23959Y104823I197J0D01*
G01Y103642D02*
G03X23582Y103563I-180J-79D01*
G01X23959Y109941D02*
G03X23582Y109862I-180J-79D01*
G01Y111201D02*
G03X23959Y111122I197J0D01*
G01Y106791D02*
G03X23582Y106712I-180J-79D01*
G01Y108051D02*
G03X23959Y107972I197J0D01*
G01X28941Y107913D02*
G03X29138Y107717I197J1D01*
G01Y106142D02*
G03X28941Y105945I0J-197D01*
G01X29138Y111142D02*
G03X28941Y110945I0J-197D01*
G01Y97913D02*
G03X29138Y97717I197J1D01*
G01Y96142D02*
G03X28941Y95945I0J-197D01*
G01Y102913D02*
G03X29138Y102717I197J1D01*
G01Y101142D02*
G03X28941Y100945I0J-197D01*
G01X31331Y108249D02*
X31026Y107774D01*
G01X31780D02*
X32085Y108249D01*
G01X26602Y109941D02*
X26681Y110098D01*
G01X27363D02*
X27284Y109941D01*
G01X26602Y106791D02*
X26681Y106949D01*
G01X27363D02*
X27284Y106791D01*
G01X26602Y103642D02*
X26681Y103799D01*
G01X27363D02*
X27284Y103642D01*
G01X26602Y100492D02*
X26681Y100650D01*
G01X27363D02*
X27284Y100492D01*
G01X26602Y97343D02*
X26681Y97500D01*
G01X27363D02*
X27284Y97343D01*
G01X23582Y97263D02*
Y96745D01*
G01Y99130D02*
Y98602D01*
G01Y100413D02*
Y99894D01*
G01Y102280D02*
Y101752D01*
G01Y103563D02*
Y103044D01*
G01Y106712D02*
Y106193D01*
G01Y108579D02*
Y108051D01*
G01Y109862D02*
Y109343D01*
G01Y111729D02*
Y111201D01*
G01Y104902D02*
Y105430D01*
G01X24190Y109941D02*
Y111122D01*
G01Y106791D02*
Y107972D01*
G01Y103642D02*
Y104823D01*
G01Y100492D02*
Y101673D01*
G01Y97343D02*
Y98524D01*
G01X25043D02*
Y97343D01*
G01Y101673D02*
Y100492D01*
G01Y104823D02*
Y103642D01*
G01Y107972D02*
Y106791D01*
G01Y111122D02*
Y109941D01*
G01X25724D02*
Y111122D01*
G01Y106791D02*
Y107972D01*
G01Y103642D02*
Y104823D01*
G01Y100492D02*
Y101673D01*
G01Y97343D02*
Y98524D01*
G01X27346Y110098D02*
Y110965D01*
G01Y106949D02*
Y107815D01*
G01Y103799D02*
Y104665D01*
G01Y100650D02*
Y101516D01*
G01Y97500D02*
Y98366D01*
G01X28028D02*
Y97500D01*
G01Y101516D02*
Y100650D01*
G01Y104665D02*
Y103799D01*
G01Y107815D02*
Y106949D01*
G01Y110965D02*
Y110098D01*
G01X28881D02*
Y110965D01*
G01Y106949D02*
Y107815D01*
G01Y103799D02*
Y104665D01*
G01Y100650D02*
Y101516D01*
G01Y97500D02*
Y98366D01*
G01X28941Y98898D02*
Y97913D01*
G01Y103898D02*
Y102913D01*
G01Y105945D02*
Y104961D01*
G01Y108898D02*
Y107913D01*
G01Y110945D02*
Y109961D01*
G01Y99961D02*
Y100945D01*
G01X29728Y102717D02*
Y101142D01*
G01Y111142D02*
Y112717D01*
G01Y106142D02*
Y107717D01*
G01Y96142D02*
Y97717D01*
G01X30482Y111142D02*
Y112717D01*
G01Y106142D02*
Y107717D01*
G01Y101142D02*
Y102717D01*
G01Y96142D02*
Y97717D01*
G01X31236D02*
Y96142D01*
G01Y102717D02*
Y101142D01*
G01Y107717D02*
Y106142D01*
G01Y112717D02*
Y111142D01*
G01X31637Y104665D02*
Y103799D01*
G01Y110098D02*
Y110965D01*
G01Y106949D02*
Y107815D01*
G01Y100650D02*
Y101516D01*
G01Y97500D02*
Y98366D01*
G01X37339Y97717D02*
Y96142D01*
G01Y102717D02*
Y101142D01*
G01Y107717D02*
Y106142D01*
G01Y112717D02*
Y111142D01*
G01X26681Y98366D02*
X26602Y98524D01*
G01X27284D02*
X27363Y98366D01*
G01X26681Y101516D02*
X26602Y101673D01*
G01X27284D02*
X27363Y101516D01*
G01X31331Y103249D02*
X31026Y102774D01*
G01X36467Y110609D02*
X36772Y111084D01*
G01X31780Y102774D02*
X32085Y103249D01*
G01X37526Y111084D02*
X37221Y110609D01*
G01X31331Y98249D02*
X31026Y97774D01*
G01X36467Y105609D02*
X36772Y106084D01*
G01X31780Y97774D02*
X32085Y98249D01*
G01X37526Y106084D02*
X37221Y105609D01*
G01X36467Y100609D02*
X36772Y101084D01*
G01X37526D02*
X37221Y100609D01*
G01X38093Y111142D02*
Y112717D01*
G01Y106142D02*
Y107717D01*
G01Y101142D02*
Y102717D01*
G01Y96142D02*
Y97717D01*
G01X38847Y111142D02*
Y112717D01*
G01Y106142D02*
Y107717D01*
G01Y101142D02*
Y102717D01*
G01Y96142D02*
Y97717D01*
G01X26681Y104665D02*
X26602Y104823D01*
G01X27284D02*
X27363Y104665D01*
G01X26681Y107815D02*
X26602Y107972D01*
G01X27284D02*
X27363Y107815D01*
G01X26681Y110965D02*
X26602Y111122D01*
G01X27284D02*
X27363Y110965D01*
G01X31026Y101084D02*
X31331Y100609D01*
G01X32085D02*
X31780Y101084D01*
G01X31026Y106084D02*
X31331Y105609D01*
G01X36772Y97774D02*
X36467Y98249D01*
G01X32085Y105609D02*
X31780Y106084D01*
G01X37221Y98249D02*
X37526Y97774D01*
G01X31026Y111084D02*
X31331Y110609D01*
G01X36772Y102774D02*
X36467Y103249D01*
G01X32085Y110609D02*
X31780Y111084D01*
G01X37221Y103249D02*
X37526Y102774D01*
G01X36772Y107774D02*
X36467Y108249D01*
G01X37221D02*
X37526Y107774D01*
G01X23385Y95981D02*
X23582D01*
G01X36772Y96084D02*
X37526D01*
G01X31026D02*
X31780D01*
G01X31690Y96142D02*
X29138D01*
G01X41603D02*
X36861D01*
G01X23582Y96745D02*
X23385D01*
G01X27284Y97343D02*
X23959D01*
G01X31637Y97500D02*
X26681D01*
G01X31690Y97717D02*
X29138D01*
G01X41603D02*
X36861D01*
G01X37526Y97774D02*
X36772D01*
G01X31026D02*
X31780D01*
G01X32085Y98249D02*
X31331D01*
G01X36467D02*
X37221D01*
G01X31421Y98307D02*
X37131D01*
G01X26681Y98366D02*
X31637D01*
G01X27284Y98524D02*
X23959D01*
G01X25590Y98898D02*
X28941D01*
G01X23385Y99130D02*
X23582D01*
G01Y99894D02*
X23385D01*
G01X28941Y99961D02*
X25590D01*
G01X27284Y100492D02*
X23959D01*
G01X37131Y100551D02*
X31421D01*
G01X36467Y100609D02*
X37221D01*
G01X31331D02*
X32085D01*
G01X31637Y100650D02*
X26681D01*
G01X37526Y101084D02*
X36772D01*
G01X31026D02*
X31780D01*
G01X31690Y101142D02*
X29138D01*
G01X41603D02*
X36861D01*
G01X26681Y101516D02*
X31637D01*
G01X27284Y101673D02*
X23959D01*
G01X23385Y102280D02*
X23582D01*
G01X31690Y102717D02*
X29138D01*
G01X41603D02*
X36861D01*
G01X37526Y102774D02*
X36772D01*
G01X31026D02*
X31780D01*
G01X23385Y103044D02*
X23582D01*
G01X32085Y103249D02*
X31331D01*
G01X36467D02*
X37221D01*
G01X31421Y103307D02*
X37131D01*
G01X27284Y103642D02*
X23959D01*
G01X31637Y103799D02*
X26681D01*
G01X25590Y103898D02*
X28941D01*
G01X26681Y104665D02*
X31637D01*
G01X27284Y104823D02*
X23959D01*
G01X28941Y104961D02*
X25590D01*
G01X23582Y105430D02*
X23385D01*
G01X37131Y105551D02*
X31421D01*
G01X36467Y105609D02*
X37221D01*
G01X31331D02*
X32085D01*
G01X37526Y106084D02*
X36772D01*
G01X31026D02*
X31780D01*
G01X31690Y106142D02*
X29138D01*
G01X41603D02*
X36861D01*
G01X23582Y106193D02*
X23385D01*
G01X27284Y106791D02*
X23959D01*
G01X31637Y106949D02*
X26681D01*
G01X31690Y107717D02*
X29138D01*
G01X41603D02*
X36861D01*
G01X37526Y107774D02*
X36772D01*
G01X31026D02*
X31780D01*
G01X26681Y107815D02*
X31637D01*
G01X27284Y107972D02*
X23959D01*
G01X32085Y108249D02*
X31331D01*
G01X36467D02*
X37221D01*
G01X31421Y108307D02*
X37131D01*
G01X23385Y108579D02*
X23582D01*
G01X28941Y108898D02*
X25590D01*
G01X23582Y109343D02*
X23385D01*
G01X27284Y109941D02*
X23959D01*
G01X28941Y109961D02*
X25590D01*
G01X31637Y110098D02*
X26681D01*
G01X37131Y110551D02*
X31421D01*
G01X32085Y110609D02*
X31331D01*
G01X36467D02*
X37221D01*
G01X26681Y110965D02*
X31637D01*
G01X36772Y111084D02*
X37526D01*
G01X31026D02*
X31780D01*
G01X27284Y111122D02*
X23959D01*
G01X31690Y111142D02*
X29138D01*
G01X41603D02*
X36861D01*
G01X23385Y111729D02*
X23582D01*
G01X28846Y128714D02*
X28820Y128682D01*
G01X28877Y128733D02*
X28846Y128714D01*
G01X28910Y128740D02*
X28877Y128733D01*
G01X29345Y128570D02*
X29371Y128601D01*
G01X29314Y128550D02*
X29345Y128570D01*
G01X29282Y128543D02*
X29314Y128550D01*
G01X37548Y127493D02*
X37522Y127462D01*
G01X37578Y127513D02*
X37548Y127493D01*
G01X37611Y127520D02*
X37578Y127513D01*
G01X36739Y127192D02*
X36765Y127223D01*
G01X36708Y127172D02*
X36739Y127192D01*
G01X36675Y127165D02*
X36708Y127172D01*
G01X37548Y124344D02*
X37522Y124312D01*
G01X37578Y124363D02*
X37548Y124344D01*
G01X37611Y124370D02*
X37578Y124363D01*
G01X36739Y124042D02*
X36765Y124073D01*
G01X36708Y124022D02*
X36739Y124042D01*
G01X36675Y124016D02*
X36708Y124022D01*
G01X37548Y121194D02*
X37522Y121163D01*
G01X37578Y121214D02*
X37548Y121194D01*
G01X37611Y121220D02*
X37578Y121214D01*
G01X36739Y120893D02*
X36765Y120924D01*
G01X36708Y120873D02*
X36739Y120893D01*
G01X36675Y120866D02*
X36708Y120873D01*
G01X31357Y118281D02*
X31331Y118249D01*
G01X31388Y118300D02*
X31357Y118281D01*
G01X31421Y118307D02*
X31388Y118300D01*
G01X31753Y117743D02*
X31780Y117774D01*
G01X31723Y117723D02*
X31753Y117743D01*
G01X31690Y117717D02*
X31723Y117723D01*
G01X37552Y116115D02*
X37526Y116084D01*
G01X37583Y116135D02*
X37552Y116115D01*
G01X37615Y116142D02*
X37583Y116135D01*
G01X36440Y115578D02*
X36467Y115609D01*
G01X36410Y115558D02*
X36440Y115578D01*
G01X36377Y115551D02*
X36410Y115558D01*
G01X31357Y113281D02*
X31331Y113249D01*
G01X31388Y113300D02*
X31357Y113281D01*
G01X31421Y113307D02*
X31388Y113300D01*
G01X31753Y112743D02*
X31780Y112774D01*
G01X31723Y112723D02*
X31753Y112743D01*
G01X31690Y112717D02*
X31723Y112723D01*
G01X37342Y128714D02*
X37368Y128682D01*
G01X37311Y128733D02*
X37342Y128714D01*
G01X37278Y128740D02*
X37311Y128733D01*
G01X36945Y128412D02*
X36919Y128443D01*
G01X36975Y128393D02*
X36945Y128412D01*
G01X37008Y128386D02*
X36975Y128393D01*
G01X28742Y127336D02*
X28768Y127304D01*
G01X28711Y127356D02*
X28742Y127336D01*
G01X28678Y127362D02*
X28711Y127356D01*
G01X37342Y125564D02*
X37368Y125533D01*
G01X37311Y125584D02*
X37342Y125564D01*
G01X37278Y125591D02*
X37311Y125584D01*
G01X29450Y127192D02*
X29423Y127223D01*
G01X29480Y127172D02*
X29450Y127192D01*
G01X29513Y127165D02*
X29480Y127172D01*
G01X36945Y125263D02*
X36919Y125294D01*
G01X36975Y125243D02*
X36945Y125263D01*
G01X37008Y125236D02*
X36975Y125243D01*
G01X37342Y122415D02*
X37368Y122383D01*
G01X37311Y122434D02*
X37342Y122415D01*
G01X37278Y122441D02*
X37311Y122434D01*
G01X36945Y122113D02*
X36919Y122144D01*
G01X36975Y122093D02*
X36945Y122113D01*
G01X37008Y122087D02*
X36975Y122093D01*
G01X37194Y118281D02*
X37221Y118249D01*
G01X37164Y118300D02*
X37194Y118281D01*
G01X37131Y118307D02*
X37164Y118300D01*
G01X36798Y117743D02*
X36772Y117774D01*
G01X36829Y117723D02*
X36798Y117743D01*
G01X36861Y117717D02*
X36829Y117723D01*
G01X30999Y116115D02*
X31026Y116084D01*
G01X30969Y116135D02*
X30999Y116115D01*
G01X30936Y116142D02*
X30969Y116135D01*
G01X32111Y115578D02*
X32085Y115609D01*
G01X32142Y115558D02*
X32111Y115578D01*
G01X32174Y115551D02*
X32142Y115558D01*
G01X37194Y113281D02*
X37221Y113249D01*
G01X37164Y113300D02*
X37194Y113281D01*
G01X37131Y113307D02*
X37164Y113300D01*
G01X36798Y112743D02*
X36772Y112774D01*
G01X36829Y112723D02*
X36798Y112743D01*
G01X36861Y112717D02*
X36829Y112723D01*
G01X37578Y128393D02*
X37611Y128386D01*
G01X37548Y128412D02*
X37578Y128393D01*
G01X37522Y128443D02*
X37548Y128412D01*
G01X36708Y128733D02*
X36675Y128740D01*
G01X36739Y128714D02*
X36708Y128733D01*
G01X36765Y128682D02*
X36739Y128714D01*
G01X37578Y125243D02*
X37611Y125236D01*
G01X37548Y125263D02*
X37578Y125243D01*
G01X37522Y125294D02*
X37548Y125263D01*
G01X36708Y125584D02*
X36675Y125591D01*
G01X36739Y125564D02*
X36708Y125584D01*
G01X36765Y125533D02*
X36739Y125564D01*
G01X37578Y122093D02*
X37611Y122087D01*
G01X37548Y122113D02*
X37578Y122093D01*
G01X37522Y122144D02*
X37548Y122113D01*
G01X36708Y122434D02*
X36675Y122441D01*
G01X36739Y122415D02*
X36708Y122434D01*
G01X36765Y122383D02*
X36739Y122415D01*
G01X37583Y117723D02*
X37615Y117717D01*
G01X37552Y117743D02*
X37583Y117723D01*
G01X37526Y117774D02*
X37552Y117743D01*
G01X29314Y127356D02*
X29282Y127362D01*
G01X29345Y127336D02*
X29314Y127356D01*
G01X29371Y127304D02*
X29345Y127336D01*
G01X36410Y118300D02*
X36377Y118307D01*
G01X36440Y118281D02*
X36410Y118300D01*
G01X36467Y118249D02*
X36440Y118281D01*
G01X28877Y127172D02*
X28910Y127165D01*
G01X28846Y127192D02*
X28877Y127172D01*
G01X28820Y127223D02*
X28846Y127192D01*
G01X37583Y112723D02*
X37615Y112717D01*
G01X37552Y112743D02*
X37583Y112723D01*
G01X37526Y112774D02*
X37552Y112743D01*
G01X36410Y113300D02*
X36377Y113307D01*
G01X36440Y113281D02*
X36410Y113300D01*
G01X36467Y113249D02*
X36440Y113281D01*
G01X31723Y116135D02*
X31690Y116142D01*
G01X31753Y116115D02*
X31723Y116135D01*
G01X31780Y116084D02*
X31753Y116115D01*
G01X31388Y115558D02*
X31421Y115551D01*
G01X31357Y115578D02*
X31388Y115558D01*
G01X31331Y115609D02*
X31357Y115578D01*
G01X37164Y115558D02*
X37131Y115551D01*
G01X37194Y115578D02*
X37164Y115558D01*
G01X37221Y115609D02*
X37194Y115578D01*
G01X36829Y116135D02*
X36861Y116142D01*
G01X36798Y116115D02*
X36829Y116135D01*
G01X36772Y116084D02*
X36798Y116115D01*
G01X32142Y113300D02*
X32174Y113307D01*
G01X32111Y113281D02*
X32142Y113300D01*
G01X32085Y113249D02*
X32111Y113281D01*
G01X30969Y112723D02*
X30936Y112717D01*
G01X30999Y112743D02*
X30969Y112723D01*
G01X31026Y112774D02*
X30999Y112743D01*
G01X37311Y120873D02*
X37278Y120866D01*
G01X37342Y120893D02*
X37311Y120873D01*
G01X37368Y120924D02*
X37342Y120893D01*
G01X36975Y121214D02*
X37008Y121220D01*
G01X36945Y121194D02*
X36975Y121214D01*
G01X36919Y121163D02*
X36945Y121194D01*
G01X37311Y124022D02*
X37278Y124016D01*
G01X37342Y124042D02*
X37311Y124022D01*
G01X37368Y124073D02*
X37342Y124042D01*
G01X32142Y118300D02*
X32174Y118307D01*
G01X32111Y118281D02*
X32142Y118300D01*
G01X32085Y118249D02*
X32111Y118281D01*
G01X36975Y124363D02*
X37008Y124370D01*
G01X36945Y124344D02*
X36975Y124363D01*
G01X36919Y124312D02*
X36945Y124344D01*
G01X30969Y117723D02*
X30936Y117717D01*
G01X30999Y117743D02*
X30969Y117723D01*
G01X31026Y117774D02*
X30999Y117743D01*
G01X37311Y127172D02*
X37278Y127165D01*
G01X37342Y127192D02*
X37311Y127172D01*
G01X37368Y127223D02*
X37342Y127192D01*
G01X36975Y127513D02*
X37008Y127520D01*
G01X36945Y127493D02*
X36975Y127513D01*
G01X36919Y127462D02*
X36945Y127493D01*
G01X29480Y128733D02*
X29513Y128740D01*
G01X29450Y128714D02*
X29480Y128733D01*
G01X29423Y128682D02*
X29450Y128714D01*
G01X28711Y128550D02*
X28678Y128543D01*
G01X28742Y128570D02*
X28711Y128550D01*
G01X28768Y128601D02*
X28742Y128570D01*
G01X23582Y114350D02*
G03X23959Y114272I197J1D01*
G01Y113091D02*
G03X23582Y113012I-180J-79D01*
G01X23959Y116240D02*
G03X23582Y116161I-180J-79D01*
G01Y117500D02*
G03X23959Y117421I197J0D01*
G01Y122539D02*
G03X23582Y122460I-180J-79D01*
G01Y123799D02*
G03X23959Y123720I197J0D01*
G01X23582Y120650D02*
G03X23959Y120571I197J0D01*
G01Y119390D02*
G03X23582Y119311I-180J-79D01*
G01X23959Y125689D02*
G03X23582Y125610I-180J-79D01*
G01Y126949D02*
G03X23959Y126870I197J0D01*
G01X26164Y121063D02*
G03X25787Y120984I-180J-79D01*
G01Y122323D02*
G03X26164Y122244I197J0D01*
G01Y124213D02*
G03X25787Y124134I-180J-79D01*
G01Y125472D02*
G03X26164Y125394I197J1D01*
G01X28941Y112913D02*
G03X29138Y112717I197J1D01*
G01X28941Y117913D02*
G03X29138Y117717I197J1D01*
G01Y116142D02*
G03X28941Y115945I0J-197D01*
G01X25787Y128622D02*
G03X26164Y128543I197J0D01*
G01Y127362D02*
G03X25787Y127283I-180J-79D01*
G01X26602Y125689D02*
X26681Y125846D01*
G01X27363D02*
X27284Y125689D01*
G01X28820Y128682D02*
X28768Y128601D01*
G01X29371D02*
X29423Y128682D01*
G01X28858Y125591D02*
X28731Y125394D01*
G01X29334D02*
X29461Y125591D01*
G01X28858Y122441D02*
X28731Y122244D01*
G01X29334D02*
X29461Y122441D01*
G01X36765Y127223D02*
X36919Y127462D01*
G01X31331Y118249D02*
X31026Y117774D01*
G01X37522Y127462D02*
X37368Y127223D01*
G01X31780Y117774D02*
X32085Y118249D01*
G01X36765Y124073D02*
X36919Y124312D01*
G01X37522D02*
X37368Y124073D01*
G01X31331Y113249D02*
X31026Y112774D01*
G01X36765Y120924D02*
X36919Y121163D01*
G01X31780Y112774D02*
X32085Y113249D01*
G01X37522Y121163D02*
X37368Y120924D01*
G01X36467Y115609D02*
X36772Y116084D01*
G01X37526D02*
X37221Y115609D01*
G01X26602Y122539D02*
X26681Y122697D01*
G01X27363D02*
X27284Y122539D01*
G01X26602Y119390D02*
X26681Y119547D01*
G01X27363D02*
X27284Y119390D01*
G01X26602Y116240D02*
X26681Y116398D01*
G01X27363D02*
X27284Y116240D01*
G01X26602Y113091D02*
X26681Y113248D01*
G01X27363D02*
X27284Y113091D01*
G01X23582Y113012D02*
Y112493D01*
G01Y114878D02*
Y114350D01*
G01Y116161D02*
Y115642D01*
G01Y118028D02*
Y117500D01*
G01Y119311D02*
Y118792D01*
G01Y122460D02*
Y121941D01*
G01Y124327D02*
Y123799D01*
G01Y125610D02*
Y125091D01*
G01Y127477D02*
Y126949D01*
G01Y128760D02*
Y128241D01*
G01Y120650D02*
Y121178D01*
G01X23818Y117776D02*
Y141083D01*
G01X24190Y125689D02*
Y126870D01*
G01Y122539D02*
Y123720D01*
G01Y119390D02*
Y120571D01*
G01Y116240D02*
Y117421D01*
G01Y113091D02*
Y114272D01*
G01X25043D02*
Y113091D01*
G01Y117421D02*
Y116240D01*
G01Y120571D02*
Y119390D01*
G01Y123720D02*
Y122539D01*
G01Y126870D02*
Y125689D01*
G01X25724D02*
Y126870D01*
G01Y122539D02*
Y123720D01*
G01Y119390D02*
Y120571D01*
G01Y116240D02*
Y117421D01*
G01Y113091D02*
Y114272D01*
G01X25787Y120984D02*
Y120456D01*
G01Y122842D02*
Y122323D01*
G01Y124134D02*
Y123606D01*
G01Y125992D02*
Y125472D01*
G01Y127283D02*
Y126755D01*
G01Y129141D02*
Y128622D01*
G01X26968Y127362D02*
Y128543D01*
G01Y124213D02*
Y125394D01*
G01Y121063D02*
Y122244D01*
G01X27346Y125846D02*
Y126713D01*
G01Y122697D02*
Y123563D01*
G01Y119547D02*
Y120413D01*
G01Y116398D02*
Y117264D01*
G01Y113248D02*
Y114114D01*
G01X27722Y127362D02*
Y128543D01*
G01Y124213D02*
Y125394D01*
G01Y121063D02*
Y122244D01*
G01X28028Y114114D02*
Y113248D01*
G01Y117264D02*
Y116398D01*
G01Y120413D02*
Y119547D01*
G01Y123563D02*
Y122697D01*
G01Y126713D02*
Y125846D01*
G01X28189Y127047D02*
Y128858D01*
G01Y123898D02*
Y125709D01*
G01Y120748D02*
Y122559D01*
G01X28325Y128543D02*
Y127362D01*
G01Y124213D02*
Y125394D01*
G01Y121063D02*
Y122244D01*
G01X28881Y125846D02*
Y126713D01*
G01Y122697D02*
Y123563D01*
G01Y119547D02*
Y120413D01*
G01Y116398D02*
Y117264D01*
G01Y113248D02*
Y114114D01*
G01X28941Y113898D02*
Y112913D01*
G01Y115945D02*
Y114961D01*
G01Y117913D02*
Y118898D01*
G01X29728Y117717D02*
Y116142D01*
G01X30482D02*
Y117717D01*
G01X30573Y125936D02*
Y126820D01*
G01Y122786D02*
Y123670D01*
G01Y120079D02*
Y120520D01*
G01X30771Y122559D02*
Y120748D01*
G01Y125709D02*
Y123898D01*
G01Y127047D02*
Y128858D01*
G01X31165D02*
Y127047D01*
G01Y123898D02*
Y125709D01*
G01Y120748D02*
Y122559D01*
G01X31236Y116142D02*
Y117717D01*
G01X31495Y120079D02*
Y138976D01*
G01X31637Y114114D02*
Y113248D01*
G01Y120413D02*
Y119547D01*
G01Y125846D02*
Y126713D01*
G01Y122697D02*
Y123563D01*
G01Y116398D02*
Y117264D01*
G01X37339Y117717D02*
Y116142D01*
G01X38093D02*
Y117717D01*
G01X38172Y122087D02*
Y121220D01*
G01Y125236D02*
Y124370D01*
G01Y128386D02*
Y127520D01*
G01X38776Y122087D02*
Y121220D01*
G01Y125236D02*
Y124370D01*
G01Y128386D02*
Y127520D01*
G01X38847Y116142D02*
Y117717D01*
G01X39530Y127520D02*
Y128386D01*
G01Y124370D02*
Y125236D01*
G01Y121220D02*
Y122087D01*
G01X26681Y114114D02*
X26602Y114272D01*
G01X27284D02*
X27363Y114114D01*
G01X26681Y117264D02*
X26602Y117421D01*
G01X27284D02*
X27363Y117264D01*
G01X26681Y120413D02*
X26602Y120571D01*
G01X27284D02*
X27363Y120413D01*
G01X26681Y123563D02*
X26602Y123720D01*
G01X27284D02*
X27363Y123563D01*
G01X26681Y126713D02*
X26602Y126870D01*
G01X27284D02*
X27363Y126713D01*
G01X31026Y116084D02*
X31331Y115609D01*
G01X32085D02*
X31780Y116084D01*
G01X28731Y121063D02*
X28858Y120866D01*
G01X29461D02*
X29334Y121063D01*
G01X28731Y124213D02*
X28858Y124016D01*
G01X29461D02*
X29334Y124213D01*
G01X36772Y112774D02*
X36467Y113249D01*
G01X37221D02*
X37526Y112774D01*
G01X28768Y127304D02*
X28820Y127223D01*
G01X29423D02*
X29371Y127304D01*
G01X36772Y117774D02*
X36467Y118249D01*
G01X37221D02*
X37526Y117774D01*
G01X36919Y122144D02*
X36765Y122383D01*
G01X37368D02*
X37522Y122144D01*
G01X36919Y125294D02*
X36765Y125533D01*
G01X37368D02*
X37522Y125294D01*
G01X36919Y128443D02*
X36765Y128682D01*
G01X37368D02*
X37522Y128443D01*
G01X30016Y125709D02*
X30573Y125936D01*
G01X30016Y122559D02*
X30573Y122786D01*
G01Y120520D02*
X30016Y120748D01*
G01X30573Y123670D02*
X30016Y123898D01*
G01X30573Y126820D02*
X30016Y127047D01*
G01X23385Y112493D02*
X23582D01*
G01X31690Y112717D02*
X29138D01*
G01X41603D02*
X36861D01*
G01X37526Y112774D02*
X36772D01*
G01X31026D02*
X31780D01*
G01X27284Y113091D02*
X23959D01*
G01X31637Y113248D02*
X26681D01*
G01X32085Y113249D02*
X31637Y113248D01*
G01X36467Y113249D02*
X37221D01*
G01X31421Y113307D02*
X37131D01*
G01X25590Y113898D02*
X28941D01*
G01X26681Y114114D02*
X31637D01*
G01X27284Y114272D02*
X23959D01*
G01X23385Y114878D02*
X23582D01*
G01X28941Y114961D02*
X25590D01*
G01X37131Y115551D02*
X31421D01*
G01X32085Y115609D02*
X31331D01*
G01X36467D02*
X37221D01*
G01X23582Y115642D02*
X23385D01*
G01X36772Y116084D02*
X37526D01*
G01X31026D02*
X31780D01*
G01X31690Y116142D02*
X29138D01*
G01X41603D02*
X36861D01*
G01X27284Y116240D02*
X23959D01*
G01X31637Y116398D02*
X26681D01*
G01Y117264D02*
X31637D01*
G01X27284Y117421D02*
X23959D01*
G01X31690Y117717D02*
X29138D01*
G01X41603D02*
X36861D01*
G01X37526Y117774D02*
X36772D01*
G01X31026D02*
X31780D01*
G01X23385Y117776D02*
X23818D01*
G01X23385Y118028D02*
X23582D01*
G01X32085Y118249D02*
X31331D01*
G01X36467D02*
X37221D01*
G01X31421Y118307D02*
X37131D01*
G01X23385Y118792D02*
X23582D01*
G01X25590Y118898D02*
X28941D01*
G01X27284Y119390D02*
X23959D01*
G01X31637Y119547D02*
X26681D01*
G01X31495Y120079D02*
X25590D01*
G01X26681Y120413D02*
X31637D01*
G01X25787Y120456D02*
X25590D01*
G01X30573Y120520D02*
X31495D01*
G01X27284Y120571D02*
X23959D01*
G01X28189Y120748D02*
X31495D01*
G01X37278Y120866D02*
X28858D01*
G01X37368Y120924D02*
X36765D01*
G01X29334Y121063D02*
X26164D01*
G01X36919Y121163D02*
X37522D01*
G01X23582Y121178D02*
X23385D01*
G01X41689Y121220D02*
X37008D01*
G01X23582Y121941D02*
X23385D01*
G01X37008Y122087D02*
X41688D01*
G01X37522Y122144D02*
X36919D01*
G01X29334Y122244D02*
X26164D01*
G01X36765Y122383D02*
X37368D01*
G01X37278Y122441D02*
X28858D01*
G01X27284Y122539D02*
X23959D01*
G01X31495Y122559D02*
X28189D01*
G01X31637Y122697D02*
X26681D01*
G01X31495Y122786D02*
X30573D01*
G01X25590Y122842D02*
X25787D01*
G01X26681Y123563D02*
X31637D01*
G01X25787Y123606D02*
X25590D01*
G01X31495Y123670D02*
X30573D01*
G01X27284Y123720D02*
X23959D01*
G01X28189Y123898D02*
X31495D01*
G01X37278Y124016D02*
X28858D01*
G01X37368Y124073D02*
X36765D01*
G01X29334Y124213D02*
X26164D01*
G01X36919Y124312D02*
X37522D01*
G01X23385Y124327D02*
X23582D01*
G01X41689Y124370D02*
X37008D01*
G01X23582Y125091D02*
X23385D01*
G01X37008Y125236D02*
X41688D01*
G01X37522Y125294D02*
X36919D01*
G01X29334Y125394D02*
X26164D01*
G01X36765Y125533D02*
X37368D01*
G01X37278Y125591D02*
X28858D01*
G01X27284Y125689D02*
X23959D01*
G01X31495Y125709D02*
X28189D01*
G01X31637Y125846D02*
X26681D01*
G01X31495Y125936D02*
X30573D01*
G01X25590Y125992D02*
X25787D01*
G01X26681Y126713D02*
X31637D01*
G01X25590Y126755D02*
X25787D01*
G01X31495Y126820D02*
X30573D01*
G01X27284Y126870D02*
X23959D01*
G01X28189Y127047D02*
X31495D01*
G01X37278Y127165D02*
X28910D01*
G01X37368Y127223D02*
X36765D01*
G01X28820D02*
X29423D01*
G01X29371Y127304D02*
X28768D01*
G01X29282Y127362D02*
X26164D01*
G01X36919Y127462D02*
X37522D01*
G01X23385Y127477D02*
X23582D01*
G01X41689Y127520D02*
X37008D01*
G01X23385Y128241D02*
X23582D01*
G01X37008Y128386D02*
X41688D01*
G01X37522Y128443D02*
X36919D01*
G01X29282Y128543D02*
X26164D01*
G01X28768Y128601D02*
X29371D01*
G01X29423Y128682D02*
X28820D01*
G01X36765D02*
X37368D01*
G01X37278Y128740D02*
X28910D01*
G01X31357Y143281D02*
X31331Y143249D01*
G01X31388Y143300D02*
X31357Y143281D01*
G01X31421Y143307D02*
X31388Y143300D01*
G01X31753Y142743D02*
X31780Y142774D01*
G01X31723Y142723D02*
X31753Y142743D01*
G01X31690Y142717D02*
X31723Y142723D01*
G01X37552Y141115D02*
X37526Y141084D01*
G01X37583Y141135D02*
X37552Y141115D01*
G01X37615Y141142D02*
X37583Y141135D01*
G01X36440Y140578D02*
X36467Y140609D01*
G01X36410Y140558D02*
X36440Y140578D01*
G01X36377Y140551D02*
X36410Y140558D01*
G01X28846Y138163D02*
X28820Y138131D01*
G01X28877Y138182D02*
X28846Y138163D01*
G01X28910Y138189D02*
X28877Y138182D01*
G01X29345Y138019D02*
X29371Y138050D01*
G01X29314Y137999D02*
X29345Y138019D01*
G01X29282Y137992D02*
X29314Y137999D01*
G01X37548Y136942D02*
X37522Y136911D01*
G01X37578Y136962D02*
X37548Y136942D01*
G01X37611Y136969D02*
X37578Y136962D01*
G01X36739Y136641D02*
X36765Y136672D01*
G01X36708Y136621D02*
X36739Y136641D01*
G01X36675Y136614D02*
X36708Y136621D01*
G01X37548Y133793D02*
X37522Y133761D01*
G01X37578Y133812D02*
X37548Y133793D01*
G01X37611Y133819D02*
X37578Y133812D01*
G01X36739Y133491D02*
X36765Y133522D01*
G01X36708Y133471D02*
X36739Y133491D01*
G01X36675Y133465D02*
X36708Y133471D01*
G01X37548Y130643D02*
X37522Y130611D01*
G01X37578Y130663D02*
X37548Y130643D01*
G01X37611Y130669D02*
X37578Y130663D01*
G01X36739Y130341D02*
X36765Y130372D01*
G01X36708Y130322D02*
X36739Y130341D01*
G01X36675Y130315D02*
X36708Y130322D01*
G01X37194Y143281D02*
X37221Y143249D01*
G01X37164Y143300D02*
X37194Y143281D01*
G01X37131Y143307D02*
X37164Y143300D01*
G01X36798Y142743D02*
X36772Y142774D01*
G01X36829Y142723D02*
X36798Y142743D01*
G01X36861Y142717D02*
X36829Y142723D01*
G01X30999Y141115D02*
X31026Y141084D01*
G01X30969Y141135D02*
X30999Y141115D01*
G01X30936Y141142D02*
X30969Y141135D01*
G01X32111Y140578D02*
X32085Y140609D01*
G01X32142Y140558D02*
X32111Y140578D01*
G01X32174Y140551D02*
X32142Y140558D01*
G01X37342Y138163D02*
X37368Y138131D01*
G01X37311Y138182D02*
X37342Y138163D01*
G01X37278Y138189D02*
X37311Y138182D01*
G01X36945Y137861D02*
X36919Y137892D01*
G01X36975Y137841D02*
X36945Y137861D01*
G01X37008Y137835D02*
X36975Y137841D01*
G01X28742Y136785D02*
X28768Y136753D01*
G01X28711Y136804D02*
X28742Y136785D01*
G01X28678Y136811D02*
X28711Y136804D01*
G01X37342Y135013D02*
X37368Y134982D01*
G01X37311Y135033D02*
X37342Y135013D01*
G01X37278Y135039D02*
X37311Y135033D01*
G01X29450Y136641D02*
X29423Y136672D01*
G01X29480Y136621D02*
X29450Y136641D01*
G01X29513Y136614D02*
X29480Y136621D01*
G01X36945Y134711D02*
X36919Y134743D01*
G01X36975Y134692D02*
X36945Y134711D01*
G01X37008Y134685D02*
X36975Y134692D01*
G01X37342Y131863D02*
X37368Y131832D01*
G01X37311Y131883D02*
X37342Y131863D01*
G01X37278Y131890D02*
X37311Y131883D01*
G01X36945Y131562D02*
X36919Y131593D01*
G01X36975Y131542D02*
X36945Y131562D01*
G01X37008Y131535D02*
X36975Y131542D01*
G01X37583Y142723D02*
X37615Y142717D01*
G01X37552Y142743D02*
X37583Y142723D01*
G01X37526Y142774D02*
X37552Y142743D01*
G01X36410Y143300D02*
X36377Y143307D01*
G01X36440Y143281D02*
X36410Y143300D01*
G01X36467Y143249D02*
X36440Y143281D01*
G01X37578Y137841D02*
X37611Y137835D01*
G01X37548Y137861D02*
X37578Y137841D01*
G01X37522Y137892D02*
X37548Y137861D01*
G01X36708Y138182D02*
X36675Y138189D01*
G01X36739Y138163D02*
X36708Y138182D01*
G01X36765Y138131D02*
X36739Y138163D01*
G01X37578Y134692D02*
X37611Y134685D01*
G01X37548Y134711D02*
X37578Y134692D01*
G01X37522Y134743D02*
X37548Y134711D01*
G01X31723Y141135D02*
X31690Y141142D01*
G01X31753Y141115D02*
X31723Y141135D01*
G01X31780Y141084D02*
X31753Y141115D01*
G01X36708Y135033D02*
X36675Y135039D01*
G01X36739Y135013D02*
X36708Y135033D01*
G01X36765Y134982D02*
X36739Y135013D01*
G01X31388Y140558D02*
X31421Y140551D01*
G01X31357Y140578D02*
X31388Y140558D01*
G01X31331Y140609D02*
X31357Y140578D01*
G01X37578Y131542D02*
X37611Y131535D01*
G01X37548Y131562D02*
X37578Y131542D01*
G01X37522Y131593D02*
X37548Y131562D01*
G01X36708Y131883D02*
X36675Y131890D01*
G01X36739Y131863D02*
X36708Y131883D01*
G01X36765Y131832D02*
X36739Y131863D01*
G01X29314Y136804D02*
X29282Y136811D01*
G01X29345Y136785D02*
X29314Y136804D01*
G01X29371Y136753D02*
X29345Y136785D01*
G01X28877Y136621D02*
X28910Y136614D01*
G01X28846Y136641D02*
X28877Y136621D01*
G01X28820Y136672D02*
X28846Y136641D01*
G01X37311Y130322D02*
X37278Y130315D01*
G01X37342Y130341D02*
X37311Y130322D01*
G01X37368Y130372D02*
X37342Y130341D01*
G01X36975Y130663D02*
X37008Y130669D01*
G01X36945Y130643D02*
X36975Y130663D01*
G01X36919Y130611D02*
X36945Y130643D01*
G01X37311Y133471D02*
X37278Y133465D01*
G01X37342Y133491D02*
X37311Y133471D01*
G01X37368Y133522D02*
X37342Y133491D01*
G01X36975Y133812D02*
X37008Y133819D01*
G01X36945Y133793D02*
X36975Y133812D01*
G01X36919Y133761D02*
X36945Y133793D01*
G01X37311Y136621D02*
X37278Y136614D01*
G01X37342Y136641D02*
X37311Y136621D01*
G01X37368Y136672D02*
X37342Y136641D01*
G01X36975Y136962D02*
X37008Y136969D01*
G01X36945Y136942D02*
X36975Y136962D01*
G01X36919Y136911D02*
X36945Y136942D01*
G01X37164Y140558D02*
X37131Y140551D01*
G01X37194Y140578D02*
X37164Y140558D01*
G01X37221Y140609D02*
X37194Y140578D01*
G01X36829Y141135D02*
X36861Y141142D01*
G01X36798Y141115D02*
X36829Y141135D01*
G01X36772Y141084D02*
X36798Y141115D01*
G01X29480Y138182D02*
X29513Y138189D01*
G01X29450Y138163D02*
X29480Y138182D01*
G01X29423Y138131D02*
X29450Y138163D01*
G01X28711Y137999D02*
X28678Y137992D01*
G01X28742Y138019D02*
X28711Y137999D01*
G01X28768Y138050D02*
X28742Y138019D01*
G01X32142Y143300D02*
X32174Y143307D01*
G01X32111Y143281D02*
X32142Y143300D01*
G01X32085Y143249D02*
X32111Y143281D01*
G01X30969Y142723D02*
X30936Y142717D01*
G01X30999Y142743D02*
X30969Y142723D01*
G01X31026Y142774D02*
X30999Y142743D01*
G01X23959Y135138D02*
G03X23582Y135059I-180J-79D01*
G01X23959Y131988D02*
G03X23582Y131909I-180J-79D01*
G01Y133248D02*
G03X23959Y133169I197J0D01*
G01X23582Y130098D02*
G03X23959Y130020I197J1D01*
G01Y128839D02*
G03X23582Y128760I-180J-79D01*
G01Y136398D02*
G03X23959Y136319I197J0D01*
G01Y141437D02*
G03X23582Y141358I-180J-79D01*
G01Y142697D02*
G03X23959Y142618I197J0D01*
G01Y144587D02*
G03X23582Y144508I-180J-79D01*
G01Y139547D02*
G03X23959Y139469I197J1D01*
G01Y138287D02*
G03X23582Y138209I-180J-79D01*
G01X25787Y138071D02*
G03X26164Y137992I197J0D01*
G01Y136811D02*
G03X25787Y136732I-180J-79D01*
G01X26164Y130512D02*
G03X25787Y130433I-180J-79D01*
G01Y131772D02*
G03X26164Y131693I197J0D01*
G01Y133661D02*
G03X25787Y133583I-180J-79D01*
G01Y134921D02*
G03X26164Y134843I197J0D01*
G01X28941Y142913D02*
G03X29138Y142717I197J1D01*
G01Y141142D02*
G03X28941Y140945I0J-197D01*
G01X31331Y143249D02*
X31026Y142774D01*
G01X31780D02*
X32085Y143249D01*
G01X28820Y138131D02*
X28768Y138050D01*
G01X29371D02*
X29423Y138131D01*
G01X28858Y135039D02*
X28731Y134843D01*
G01X29334D02*
X29461Y135039D01*
G01X26602Y144587D02*
X26681Y144744D01*
G01X27363D02*
X27284Y144587D01*
G01X26602Y141437D02*
X26681Y141595D01*
G01X27363D02*
X27284Y141437D01*
G01X26602Y138287D02*
X26681Y138445D01*
G01X27363D02*
X27284Y138287D01*
G01X26602Y135138D02*
X26681Y135295D01*
G01X27363D02*
X27284Y135138D01*
G01X26602Y131988D02*
X26681Y132146D01*
G01X27363D02*
X27284Y131988D01*
G01X26602Y128839D02*
X26681Y128996D01*
G01X27363D02*
X27284Y128839D01*
G01X28858Y131890D02*
X28731Y131693D01*
G01X29334D02*
X29461Y131890D01*
G01X36467Y140609D02*
X36772Y141084D01*
G01X37526D02*
X37221Y140609D01*
G01X36765Y136672D02*
X36919Y136911D01*
G01X37522D02*
X37368Y136672D01*
G01X36765Y133522D02*
X36919Y133761D01*
G01X37522D02*
X37368Y133522D01*
G01X36765Y130372D02*
X36919Y130611D01*
G01X37522D02*
X37368Y130372D01*
G01X23582Y131909D02*
Y131390D01*
G01Y133776D02*
Y133248D01*
G01Y135059D02*
Y134540D01*
G01Y136926D02*
Y136398D01*
G01Y138209D02*
Y137689D01*
G01Y141358D02*
Y140839D01*
G01Y143225D02*
Y142697D01*
G01Y144508D02*
Y143989D01*
G01Y139547D02*
Y140075D01*
G01Y130098D02*
Y130626D01*
G01X24190Y144587D02*
Y145768D01*
G01Y141437D02*
Y142618D01*
G01Y138287D02*
Y139469D01*
G01Y135138D02*
Y136319D01*
G01Y131988D02*
Y133169D01*
G01Y128839D02*
Y130020D01*
G01X25043D02*
Y128839D01*
G01Y133169D02*
Y131988D01*
G01Y136319D02*
Y135138D01*
G01Y139469D02*
Y138287D01*
G01Y142618D02*
Y141437D01*
G01Y145768D02*
Y144587D01*
G01X25724D02*
Y145768D01*
G01Y141437D02*
Y142618D01*
G01Y138287D02*
Y139469D01*
G01Y135138D02*
Y136319D01*
G01Y131988D02*
Y133169D01*
G01Y128839D02*
Y130020D01*
G01X25787Y130433D02*
Y129905D01*
G01Y132291D02*
Y131772D01*
G01Y133583D02*
Y133054D01*
G01Y136732D02*
Y136204D01*
G01Y135441D02*
Y134921D01*
G01Y138590D02*
Y138071D01*
G01X26968Y136811D02*
Y137992D01*
G01Y133661D02*
Y134843D01*
G01Y130512D02*
Y131693D01*
G01X27346Y144744D02*
Y145610D01*
G01Y141595D02*
Y142461D01*
G01Y138445D02*
Y139311D01*
G01Y135295D02*
Y136161D01*
G01Y132146D02*
Y133012D01*
G01Y128996D02*
Y129862D01*
G01X27722Y136811D02*
Y137992D01*
G01Y133661D02*
Y134843D01*
G01Y130512D02*
Y131693D01*
G01X28028Y129862D02*
Y128996D01*
G01Y133012D02*
Y132146D01*
G01Y136161D02*
Y135295D01*
G01Y139311D02*
Y138445D01*
G01Y142461D02*
Y141595D01*
G01Y145610D02*
Y144744D01*
G01X28189Y136496D02*
Y138307D01*
G01Y133346D02*
Y135158D01*
G01Y130197D02*
Y132008D01*
G01X28325Y137992D02*
Y136811D01*
G01Y133661D02*
Y134843D01*
G01Y130512D02*
Y131693D01*
G01X28881Y144744D02*
Y145610D01*
G01Y141595D02*
Y142461D01*
G01Y138445D02*
Y139311D01*
G01Y135295D02*
Y136161D01*
G01Y132146D02*
Y133012D01*
G01Y128996D02*
Y129862D01*
G01X28941Y140945D02*
Y139961D01*
G01Y143898D02*
Y142913D01*
G01Y145945D02*
Y144961D01*
G01X29728Y141142D02*
Y142717D01*
G01X30482Y141142D02*
Y142717D01*
G01X30573Y138534D02*
Y138976D01*
G01Y135385D02*
Y136269D01*
G01Y132235D02*
Y133119D01*
G01Y129085D02*
Y129969D01*
G01X30771Y135158D02*
Y133346D01*
G01Y136496D02*
Y138307D01*
G01Y130197D02*
Y132008D01*
G01X31165D02*
Y130197D01*
G01Y136496D02*
Y138307D01*
G01Y133346D02*
Y135158D01*
G01X31236Y142717D02*
Y141142D01*
G01X31637Y129862D02*
Y128996D01*
G01Y139311D02*
Y138445D01*
G01Y145610D02*
Y144744D01*
G01Y141595D02*
Y142461D01*
G01Y135295D02*
Y136161D01*
G01Y132146D02*
Y133012D01*
G01X37339Y142717D02*
Y141142D01*
G01X38093D02*
Y142717D01*
G01X38172Y131535D02*
Y130669D01*
G01Y134685D02*
Y133819D01*
G01Y137835D02*
Y136969D01*
G01X38776Y131535D02*
Y130669D01*
G01Y134685D02*
Y133819D01*
G01Y137835D02*
Y136969D01*
G01X38847Y141142D02*
Y142717D01*
G01X39530Y136969D02*
Y137835D01*
G01Y133819D02*
Y134685D01*
G01Y130669D02*
Y131535D01*
G01X26681Y129862D02*
X26602Y130020D01*
G01X27284D02*
X27363Y129862D01*
G01X26681Y133012D02*
X26602Y133169D01*
G01X27284D02*
X27363Y133012D01*
G01X26681Y136161D02*
X26602Y136319D01*
G01X27284D02*
X27363Y136161D01*
G01X26681Y139311D02*
X26602Y139469D01*
G01X27284D02*
X27363Y139311D01*
G01X30016Y138307D02*
X30573Y138534D01*
G01X30016Y135158D02*
X30573Y135385D01*
G01X30016Y132008D02*
X30573Y132235D01*
G01X30016Y128858D02*
X30573Y129085D01*
G01X26681Y142461D02*
X26602Y142618D01*
G01X27284D02*
X27363Y142461D01*
G01X28731Y130512D02*
X28858Y130315D01*
G01X29461D02*
X29334Y130512D01*
G01X28731Y133661D02*
X28858Y133465D01*
G01X29461D02*
X29334Y133661D01*
G01X28768Y136753D02*
X28820Y136672D01*
G01X29423D02*
X29371Y136753D01*
G01X36919Y131593D02*
X36765Y131832D01*
G01X31026Y141084D02*
X31331Y140609D01*
G01X37368Y131832D02*
X37522Y131593D01*
G01X32085Y140609D02*
X31780Y141084D01*
G01X36919Y134743D02*
X36765Y134982D01*
G01X37368D02*
X37522Y134743D01*
G01X36919Y137892D02*
X36765Y138131D01*
G01X37368D02*
X37522Y137892D01*
G01X36772Y142774D02*
X36467Y143249D01*
G01X37221D02*
X37526Y142774D01*
G01X30573Y129969D02*
X30016Y130197D01*
G01X30573Y133119D02*
X30016Y133346D01*
G01X30573Y136269D02*
X30016Y136496D01*
G01X27284Y128839D02*
X23959D01*
G01X31495Y128858D02*
X28189D01*
G01X31637Y128996D02*
X26681D01*
G01X31495Y129085D02*
X30573D01*
G01X25590Y129141D02*
X25787D01*
G01X26681Y129862D02*
X31637D01*
G01X25787Y129905D02*
X25590D01*
G01X30573Y129969D02*
X31495D01*
G01X27284Y130020D02*
X23959D01*
G01X28189Y130197D02*
X31495D01*
G01X37278Y130315D02*
X28858D01*
G01X37368Y130372D02*
X36765D01*
G01X29334Y130512D02*
X26164D01*
G01X36919Y130611D02*
X37522D01*
G01X23582Y130626D02*
X23385D01*
G01X41689Y130669D02*
X37008D01*
G01X23582Y131390D02*
X23385D01*
G01X37008Y131535D02*
X41688D01*
G01X37522Y131593D02*
X36919D01*
G01X29334Y131693D02*
X26164D01*
G01X36765Y131832D02*
X37368D01*
G01X37278Y131890D02*
X28858D01*
G01X27284Y131988D02*
X23959D01*
G01X31495Y132008D02*
X28189D01*
G01X31637Y132146D02*
X26681D01*
G01X30573Y132235D02*
X31495D01*
G01X25590Y132291D02*
X25787D01*
G01X26681Y133012D02*
X31637D01*
G01X25787Y133054D02*
X25590D01*
G01X31495Y133119D02*
X30573D01*
G01X27284Y133169D02*
X23959D01*
G01X28189Y133346D02*
X31495D01*
G01X37278Y133465D02*
X28858D01*
G01X37368Y133522D02*
X36765D01*
G01X29334Y133661D02*
X26164D01*
G01X36919Y133761D02*
X37522D01*
G01X23385Y133776D02*
X23582D01*
G01X41689Y133819D02*
X37008D01*
G01X23582Y134540D02*
X23385D01*
G01X37008Y134685D02*
X41688D01*
G01X37522Y134743D02*
X36919D01*
G01X29334Y134843D02*
X26164D01*
G01X36765Y134982D02*
X37368D01*
G01X37278Y135039D02*
X28858D01*
G01X27284Y135138D02*
X23959D01*
G01X31495Y135158D02*
X28189D01*
G01X31637Y135295D02*
X26681D01*
G01X30573Y135385D02*
X31495D01*
G01X25590Y135441D02*
X25787D01*
G01X26681Y136161D02*
X31637D01*
G01X25590Y136204D02*
X25787D01*
G01X31495Y136269D02*
X30573D01*
G01X27284Y136319D02*
X23959D01*
G01X28189Y136496D02*
X31495D01*
G01X37278Y136614D02*
X28910D01*
G01X37368Y136672D02*
X36765D01*
G01X28820D02*
X29423D01*
G01X29371Y136753D02*
X28768D01*
G01X29282Y136811D02*
X26164D01*
G01X36919Y136911D02*
X37522D01*
G01X23385Y136926D02*
X23582D01*
G01X41689Y136969D02*
X37008D01*
G01X23385Y137689D02*
X23582D01*
G01X37008Y137835D02*
X41688D01*
G01X37522Y137892D02*
X36919D01*
G01X29282Y137992D02*
X26164D01*
G01X28768Y138050D02*
X29371D01*
G01X29423Y138131D02*
X28820D01*
G01X36765D02*
X37368D01*
G01X37278Y138189D02*
X28910D01*
G01X27284Y138287D02*
X23959D01*
G01X31495Y138307D02*
X28189D01*
G01X31637Y138445D02*
X26681D01*
G01X31495Y138534D02*
X30573D01*
G01X25590Y138590D02*
X25787D01*
G01X25590Y138976D02*
X31495D01*
G01X26681Y139311D02*
X31637D01*
G01X27284Y139469D02*
X23959D01*
G01X28941Y139961D02*
X25590D01*
G01X23582Y140075D02*
X23385D01*
G01X37131Y140551D02*
X31421D01*
G01X36467Y140609D02*
X37221D01*
G01X31331D02*
X32085D01*
G01X23582Y140839D02*
X23385D01*
G01Y141083D02*
X23818D01*
G01X37526Y141084D02*
X36772D01*
G01X31026D02*
X31780D01*
G01X31690Y141142D02*
X29138D01*
G01X41603D02*
X36861D01*
G01X27284Y141437D02*
X23959D01*
G01X31637Y141595D02*
X26681D01*
G01Y142461D02*
X31637D01*
G01X27284Y142618D02*
X23959D01*
G01X31690Y142717D02*
X29138D01*
G01X41603D02*
X36861D01*
G01X37526Y142774D02*
X36772D01*
G01X31026D02*
X31780D01*
G01X23385Y143225D02*
X23582D01*
G01X32085Y143249D02*
X31331D01*
G01X36467D02*
X37221D01*
G01X31421Y143307D02*
X37131D01*
G01X28941Y143898D02*
X25590D01*
G01X23385Y143989D02*
X23582D01*
G01X27284Y144587D02*
X23959D01*
G01X31637Y144744D02*
X26681D01*
G01X28941Y144961D02*
X25590D01*
G01X37552Y161115D02*
X37526Y161084D01*
G01X37583Y161135D02*
X37552Y161115D01*
G01X37615Y161142D02*
X37583Y161135D01*
G01X36440Y160578D02*
X36467Y160609D01*
G01X36410Y160558D02*
X36440Y160578D01*
G01X36377Y160551D02*
X36410Y160558D01*
G01X31357Y158281D02*
X31331Y158249D01*
G01X31388Y158300D02*
X31357Y158281D01*
G01X31421Y158307D02*
X31388Y158300D01*
G01X31753Y157743D02*
X31780Y157774D01*
G01X31723Y157723D02*
X31753Y157743D01*
G01X31690Y157717D02*
X31723Y157723D01*
G01X37552Y156115D02*
X37526Y156084D01*
G01X37583Y156135D02*
X37552Y156115D01*
G01X37615Y156142D02*
X37583Y156135D01*
G01X36440Y155578D02*
X36467Y155609D01*
G01X36410Y155558D02*
X36440Y155578D01*
G01X36377Y155551D02*
X36410Y155558D01*
G01X31357Y153281D02*
X31331Y153249D01*
G01X31388Y153300D02*
X31357Y153281D01*
G01X31421Y153307D02*
X31388Y153300D01*
G01X31753Y152743D02*
X31780Y152774D01*
G01X31723Y152723D02*
X31753Y152743D01*
G01X31690Y152717D02*
X31723Y152723D01*
G01X37552Y151115D02*
X37526Y151084D01*
G01X37583Y151135D02*
X37552Y151115D01*
G01X37615Y151142D02*
X37583Y151135D01*
G01X36440Y150578D02*
X36467Y150609D01*
G01X36410Y150558D02*
X36440Y150578D01*
G01X36377Y150551D02*
X36410Y150558D01*
G01X31357Y148281D02*
X31331Y148249D01*
G01X31388Y148300D02*
X31357Y148281D01*
G01X31421Y148307D02*
X31388Y148300D01*
G01X31753Y147743D02*
X31780Y147774D01*
G01X31723Y147723D02*
X31753Y147743D01*
G01X31690Y147717D02*
X31723Y147723D01*
G01X37552Y146115D02*
X37526Y146084D01*
G01X37583Y146135D02*
X37552Y146115D01*
G01X37615Y146142D02*
X37583Y146135D01*
G01X36440Y145578D02*
X36467Y145609D01*
G01X36410Y145558D02*
X36440Y145578D01*
G01X36377Y145551D02*
X36410Y145558D01*
G01X30999Y161115D02*
X31026Y161084D01*
G01X30969Y161135D02*
X30999Y161115D01*
G01X30936Y161142D02*
X30969Y161135D01*
G01X32111Y160578D02*
X32085Y160609D01*
G01X32142Y160558D02*
X32111Y160578D01*
G01X32174Y160551D02*
X32142Y160558D01*
G01X37194Y158281D02*
X37221Y158249D01*
G01X37164Y158300D02*
X37194Y158281D01*
G01X37131Y158307D02*
X37164Y158300D01*
G01X36798Y157743D02*
X36772Y157774D01*
G01X36829Y157723D02*
X36798Y157743D01*
G01X36861Y157717D02*
X36829Y157723D01*
G01X30999Y156115D02*
X31026Y156084D01*
G01X30969Y156135D02*
X30999Y156115D01*
G01X30936Y156142D02*
X30969Y156135D01*
G01X32111Y155578D02*
X32085Y155609D01*
G01X32142Y155558D02*
X32111Y155578D01*
G01X32174Y155551D02*
X32142Y155558D01*
G01X37194Y153281D02*
X37221Y153249D01*
G01X37164Y153300D02*
X37194Y153281D01*
G01X37131Y153307D02*
X37164Y153300D01*
G01X36798Y152743D02*
X36772Y152774D01*
G01X36829Y152723D02*
X36798Y152743D01*
G01X36861Y152717D02*
X36829Y152723D01*
G01X30999Y151115D02*
X31026Y151084D01*
G01X30969Y151135D02*
X30999Y151115D01*
G01X30936Y151142D02*
X30969Y151135D01*
G01X32111Y150578D02*
X32085Y150609D01*
G01X32142Y150558D02*
X32111Y150578D01*
G01X32174Y150551D02*
X32142Y150558D01*
G01X37194Y148281D02*
X37221Y148249D01*
G01X37164Y148300D02*
X37194Y148281D01*
G01X37131Y148307D02*
X37164Y148300D01*
G01X36798Y147743D02*
X36772Y147774D01*
G01X36829Y147723D02*
X36798Y147743D01*
G01X36861Y147717D02*
X36829Y147723D01*
G01X30999Y146115D02*
X31026Y146084D01*
G01X30969Y146135D02*
X30999Y146115D01*
G01X30936Y146142D02*
X30969Y146135D01*
G01X32111Y145578D02*
X32085Y145609D01*
G01X32142Y145558D02*
X32111Y145578D01*
G01X32174Y145551D02*
X32142Y145558D01*
G01X37583Y157723D02*
X37615Y157717D01*
G01X37552Y157743D02*
X37583Y157723D01*
G01X37526Y157774D02*
X37552Y157743D01*
G01X36410Y158300D02*
X36377Y158307D01*
G01X36440Y158281D02*
X36410Y158300D01*
G01X36467Y158249D02*
X36440Y158281D01*
G01X31723Y161135D02*
X31690Y161142D01*
G01X31753Y161115D02*
X31723Y161135D01*
G01X31780Y161084D02*
X31753Y161115D01*
G01X31388Y160558D02*
X31421Y160551D01*
G01X31357Y160578D02*
X31388Y160558D01*
G01X31331Y160609D02*
X31357Y160578D01*
G01X37583Y152723D02*
X37615Y152717D01*
G01X37552Y152743D02*
X37583Y152723D01*
G01X37526Y152774D02*
X37552Y152743D01*
G01X36410Y153300D02*
X36377Y153307D01*
G01X36440Y153281D02*
X36410Y153300D01*
G01X36467Y153249D02*
X36440Y153281D01*
G01X31723Y156135D02*
X31690Y156142D01*
G01X31753Y156115D02*
X31723Y156135D01*
G01X31780Y156084D02*
X31753Y156115D01*
G01X31388Y155558D02*
X31421Y155551D01*
G01X31357Y155578D02*
X31388Y155558D01*
G01X31331Y155609D02*
X31357Y155578D01*
G01X37583Y147723D02*
X37615Y147717D01*
G01X37552Y147743D02*
X37583Y147723D01*
G01X37526Y147774D02*
X37552Y147743D01*
G01X36410Y148300D02*
X36377Y148307D01*
G01X36440Y148281D02*
X36410Y148300D01*
G01X36467Y148249D02*
X36440Y148281D01*
G01X31723Y151135D02*
X31690Y151142D01*
G01X31753Y151115D02*
X31723Y151135D01*
G01X31780Y151084D02*
X31753Y151115D01*
G01X31388Y150558D02*
X31421Y150551D01*
G01X31357Y150578D02*
X31388Y150558D01*
G01X31331Y150609D02*
X31357Y150578D01*
G01X31723Y146135D02*
X31690Y146142D01*
G01X31753Y146115D02*
X31723Y146135D01*
G01X31780Y146084D02*
X31753Y146115D01*
G01X31388Y145558D02*
X31421Y145551D01*
G01X31357Y145578D02*
X31388Y145558D01*
G01X31331Y145609D02*
X31357Y145578D01*
G01X37164Y145558D02*
X37131Y145551D01*
G01X37194Y145578D02*
X37164Y145558D01*
G01X37221Y145609D02*
X37194Y145578D01*
G01X36829Y146135D02*
X36861Y146142D01*
G01X36798Y146115D02*
X36829Y146135D01*
G01X36772Y146084D02*
X36798Y146115D01*
G01X37164Y150558D02*
X37131Y150551D01*
G01X37194Y150578D02*
X37164Y150558D01*
G01X37221Y150609D02*
X37194Y150578D01*
G01X36829Y151135D02*
X36861Y151142D01*
G01X36798Y151115D02*
X36829Y151135D01*
G01X36772Y151084D02*
X36798Y151115D01*
G01X32142Y148300D02*
X32174Y148307D01*
G01X32111Y148281D02*
X32142Y148300D01*
G01X32085Y148249D02*
X32111Y148281D01*
G01X30969Y147723D02*
X30936Y147717D01*
G01X30999Y147743D02*
X30969Y147723D01*
G01X31026Y147774D02*
X30999Y147743D01*
G01X37164Y155558D02*
X37131Y155551D01*
G01X37194Y155578D02*
X37164Y155558D01*
G01X37221Y155609D02*
X37194Y155578D01*
G01X36829Y156135D02*
X36861Y156142D01*
G01X36798Y156115D02*
X36829Y156135D01*
G01X36772Y156084D02*
X36798Y156115D01*
G01X32142Y153300D02*
X32174Y153307D01*
G01X32111Y153281D02*
X32142Y153300D01*
G01X32085Y153249D02*
X32111Y153281D01*
G01X30969Y152723D02*
X30936Y152717D01*
G01X30999Y152743D02*
X30969Y152723D01*
G01X31026Y152774D02*
X30999Y152743D01*
G01X37164Y160558D02*
X37131Y160551D01*
G01X37194Y160578D02*
X37164Y160558D01*
G01X37221Y160609D02*
X37194Y160578D01*
G01X36829Y161135D02*
X36861Y161142D01*
G01X36798Y161115D02*
X36829Y161135D01*
G01X36772Y161084D02*
X36798Y161115D01*
G01X32142Y158300D02*
X32174Y158307D01*
G01X32111Y158281D02*
X32142Y158300D01*
G01X32085Y158249D02*
X32111Y158281D01*
G01X30969Y157723D02*
X30936Y157717D01*
G01X30999Y157743D02*
X30969Y157723D01*
G01X31026Y157774D02*
X30999Y157743D01*
G01X23582Y145846D02*
G03X23959Y145768I197J1D01*
G01Y150886D02*
G03X23582Y150807I-180J-79D01*
G01Y152146D02*
G03X23959Y152067I197J0D01*
G01Y157185D02*
G03X23582Y157106I-180J-79D01*
G01X23959Y147736D02*
G03X23582Y147657I-180J-79D01*
G01Y148996D02*
G03X23959Y148917I197J0D01*
G01X23582Y155295D02*
G03X23959Y155217I197J1D01*
G01Y154035D02*
G03X23582Y153957I-180J-79D01*
G01X23959Y160335D02*
G03X23582Y160256I-180J-79D01*
G01Y161595D02*
G03X23959Y161516I197J0D01*
G01X23582Y158445D02*
G03X23959Y158366I197J0D01*
G01X28941Y147913D02*
G03X29138Y147717I197J1D01*
G01Y146142D02*
G03X28941Y145945I0J-197D01*
G01Y157913D02*
G03X29138Y157717I197J1D01*
G01Y156142D02*
G03X28941Y155945I0J-197D01*
G01Y152913D02*
G03X29138Y152717I197J1D01*
G01Y151142D02*
G03X28941Y150945I0J-197D01*
G01X29138Y161142D02*
G03X28941Y160945I0J-197D01*
G01X31331Y158249D02*
X31026Y157774D01*
G01X31780D02*
X32085Y158249D01*
G01X31331Y153249D02*
X31026Y152774D01*
G01X36467Y160609D02*
X36772Y161084D01*
G01X31780Y152774D02*
X32085Y153249D01*
G01X37526Y161084D02*
X37221Y160609D01*
G01X31331Y148249D02*
X31026Y147774D01*
G01X36467Y155609D02*
X36772Y156084D01*
G01X31780Y147774D02*
X32085Y148249D01*
G01X37526Y156084D02*
X37221Y155609D01*
G01X36467Y150609D02*
X36772Y151084D01*
G01X37526D02*
X37221Y150609D01*
G01X36467Y145609D02*
X36772Y146084D01*
G01X26602Y160335D02*
X26681Y160492D01*
G01X27363D02*
X27284Y160335D01*
G01X26602Y157185D02*
X26681Y157343D01*
G01X27363D02*
X27284Y157185D01*
G01X26602Y154035D02*
X26681Y154193D01*
G01X27363D02*
X27284Y154035D01*
G01X26602Y150886D02*
X26681Y151043D01*
G01X27363D02*
X27284Y150886D01*
G01X26602Y147736D02*
X26681Y147894D01*
G01X27363D02*
X27284Y147736D01*
G01X37526Y146084D02*
X37221Y145609D01*
G01X23582Y147657D02*
Y147138D01*
G01Y146374D02*
Y145846D01*
G01Y149524D02*
Y148996D01*
G01Y150807D02*
Y150288D01*
G01Y152674D02*
Y152146D01*
G01Y153957D02*
Y153437D01*
G01Y157106D02*
Y156587D01*
G01Y155823D02*
Y155295D01*
G01Y158973D02*
Y158445D01*
G01Y160256D02*
Y159737D01*
G01Y162122D02*
Y161595D01*
G01X24190Y160335D02*
Y161516D01*
G01Y157185D02*
Y158366D01*
G01Y154035D02*
Y155217D01*
G01Y150886D02*
Y152067D01*
G01Y147736D02*
Y148917D01*
G01X25043D02*
Y147736D01*
G01Y152067D02*
Y150886D01*
G01Y155217D02*
Y154035D01*
G01Y158366D02*
Y157185D01*
G01Y161516D02*
Y160335D01*
G01X25724D02*
Y161516D01*
G01Y157185D02*
Y158366D01*
G01Y154035D02*
Y155217D01*
G01Y150886D02*
Y152067D01*
G01Y147736D02*
Y148917D01*
G01X27346Y160492D02*
Y161358D01*
G01Y157343D02*
Y158209D01*
G01Y154193D02*
Y155059D01*
G01Y151043D02*
Y151909D01*
G01Y147894D02*
Y148760D01*
G01X28028D02*
Y147894D01*
G01Y151909D02*
Y151043D01*
G01Y155059D02*
Y154193D01*
G01Y158209D02*
Y157343D01*
G01Y161358D02*
Y160492D01*
G01X28881D02*
Y161358D01*
G01Y157343D02*
Y158209D01*
G01Y154193D02*
Y155059D01*
G01Y151043D02*
Y151909D01*
G01Y147894D02*
Y148760D01*
G01X28941Y148898D02*
Y147913D01*
G01Y153898D02*
Y152913D01*
G01Y155945D02*
Y154961D01*
G01Y160945D02*
Y159961D01*
G01Y157913D02*
Y158898D01*
G01Y149961D02*
Y150945D01*
G01X29728Y152717D02*
Y151142D01*
G01Y157717D02*
Y156142D01*
G01Y162717D02*
Y161142D01*
G01Y146142D02*
Y147717D01*
G01X30482Y161142D02*
Y162717D01*
G01Y156142D02*
Y157717D01*
G01Y151142D02*
Y152717D01*
G01Y146142D02*
Y147717D01*
G01X31236D02*
Y146142D01*
G01Y152717D02*
Y151142D01*
G01Y161142D02*
Y162717D01*
G01Y156142D02*
Y157717D01*
G01X31637Y155059D02*
Y154193D01*
G01Y160492D02*
Y161358D01*
G01Y157343D02*
Y158209D01*
G01Y151043D02*
Y151909D01*
G01Y147894D02*
Y148760D01*
G01X37339Y147717D02*
Y146142D01*
G01Y152717D02*
Y151142D01*
G01Y157717D02*
Y156142D01*
G01Y162717D02*
Y161142D01*
G01X38093D02*
Y162717D01*
G01Y156142D02*
Y157717D01*
G01Y151142D02*
Y152717D01*
G01Y146142D02*
Y147717D01*
G01X38847Y161142D02*
Y162717D01*
G01Y156142D02*
Y157717D01*
G01Y151142D02*
Y152717D01*
G01Y146142D02*
Y147717D01*
G01X26681Y145610D02*
X26602Y145768D01*
G01X27284D02*
X27363Y145610D01*
G01X26681Y148760D02*
X26602Y148917D01*
G01X27284D02*
X27363Y148760D01*
G01X26681Y151909D02*
X26602Y152067D01*
G01X27284D02*
X27363Y151909D01*
G01X26681Y155059D02*
X26602Y155217D01*
G01X27284D02*
X27363Y155059D01*
G01X26681Y158209D02*
X26602Y158366D01*
G01X27284D02*
X27363Y158209D01*
G01X26681Y161358D02*
X26602Y161516D01*
G01X27284D02*
X27363Y161358D01*
G01X31026Y146084D02*
X31331Y145609D01*
G01X32085D02*
X31780Y146084D01*
G01X31026Y151084D02*
X31331Y150609D01*
G01X32085D02*
X31780Y151084D01*
G01X31026Y156084D02*
X31331Y155609D01*
G01X36772Y147774D02*
X36467Y148249D01*
G01X32085Y155609D02*
X31780Y156084D01*
G01X37221Y148249D02*
X37526Y147774D01*
G01X31026Y161084D02*
X31331Y160609D01*
G01X36772Y152774D02*
X36467Y153249D01*
G01X32085Y160609D02*
X31780Y161084D01*
G01X37221Y153249D02*
X37526Y152774D01*
G01X36772Y157774D02*
X36467Y158249D01*
G01X37221D02*
X37526Y157774D01*
G01X37131Y145551D02*
X31421D01*
G01X32085Y145609D02*
X31637Y145610D01*
G01X36467Y145609D02*
X37221D01*
G01X26681Y145610D02*
X31637D01*
G01X27284Y145768D02*
X23959D01*
G01X36772Y146084D02*
X37526D01*
G01X31026D02*
X31780D01*
G01X31690Y146142D02*
X29138D01*
G01X41603D02*
X36861D01*
G01X23385Y146374D02*
X23582D01*
G01Y147138D02*
X23385D01*
G01X31690Y147717D02*
X29138D01*
G01X41603D02*
X36861D01*
G01X27284Y147736D02*
X23959D01*
G01X37526Y147774D02*
X36772D01*
G01X31026D02*
X31780D01*
G01X31637Y147894D02*
X26681D01*
G01X32085Y148249D02*
X31331D01*
G01X36467D02*
X37221D01*
G01X31421Y148307D02*
X37131D01*
G01X26681Y148760D02*
X31637D01*
G01X25590Y148898D02*
X28941D01*
G01X27284Y148917D02*
X23959D01*
G01X23385Y149524D02*
X23582D01*
G01X28941Y149961D02*
X25590D01*
G01X23582Y150288D02*
X23385D01*
G01X37131Y150551D02*
X31421D01*
G01X36467Y150609D02*
X37221D01*
G01X31331D02*
X32085D01*
G01X27284Y150886D02*
X23959D01*
G01X31637Y151043D02*
X26681D01*
G01X37526Y151084D02*
X36772D01*
G01X31026D02*
X31780D01*
G01X31690Y151142D02*
X29138D01*
G01X41603D02*
X36861D01*
G01X26681Y151909D02*
X31637D01*
G01X27284Y152067D02*
X23959D01*
G01X23385Y152674D02*
X23582D01*
G01X31690Y152717D02*
X29138D01*
G01X41603D02*
X36861D01*
G01X37526Y152774D02*
X36772D01*
G01X31026D02*
X31780D01*
G01X32085Y153249D02*
X31331D01*
G01X36467D02*
X37221D01*
G01X31421Y153307D02*
X37131D01*
G01X23385Y153437D02*
X23582D01*
G01X25590Y153898D02*
X28941D01*
G01X27284Y154035D02*
X23959D01*
G01X31637Y154193D02*
X26681D01*
G01X28941Y154961D02*
X25590D01*
G01X26681Y155059D02*
X31637D01*
G01X27284Y155217D02*
X23959D01*
G01X37131Y155551D02*
X31421D01*
G01X32085Y155609D02*
X31331D01*
G01X36467D02*
X37221D01*
G01X23385Y155823D02*
X23582D01*
G01X36772Y156084D02*
X37526D01*
G01X31026D02*
X31780D01*
G01X31690Y156142D02*
X29138D01*
G01X41603D02*
X36861D01*
G01X23582Y156587D02*
X23385D01*
G01X27284Y157185D02*
X23959D01*
G01X31637Y157343D02*
X26681D01*
G01X31690Y157717D02*
X29138D01*
G01X41603D02*
X36861D01*
G01X37526Y157774D02*
X36772D01*
G01X31026D02*
X31780D01*
G01X26681Y158209D02*
X31637D01*
G01X32085Y158249D02*
X31331D01*
G01X36467D02*
X37221D01*
G01X31421Y158307D02*
X37131D01*
G01X27284Y158366D02*
X23959D01*
G01X25590Y158898D02*
X28941D01*
G01X23385Y158973D02*
X23582D01*
G01Y159737D02*
X23385D01*
G01X28941Y159961D02*
X25590D01*
G01X27284Y160335D02*
X23959D01*
G01X31637Y160492D02*
X26681D01*
G01X37131Y160551D02*
X31421D01*
G01X32085Y160609D02*
X31331D01*
G01X36467D02*
X37221D01*
G01X36772Y161084D02*
X37526D01*
G01X31026D02*
X31780D01*
G01X31690Y161142D02*
X29138D01*
G01X41603D02*
X36861D01*
G01X26681Y161358D02*
X31637D01*
G01X27284Y161516D02*
X23959D01*
G01X31357Y178281D02*
X31331Y178249D01*
G01X31753Y177743D02*
X31780Y177774D01*
G01X31723Y177723D02*
X31753Y177743D01*
G01X31690Y177717D02*
X31723Y177723D01*
G01X37552Y176115D02*
X37526Y176084D01*
G01X37583Y176135D02*
X37552Y176115D01*
G01X37615Y176142D02*
X37583Y176135D01*
G01X36440Y175578D02*
X36467Y175609D01*
G01X36410Y175558D02*
X36440Y175578D01*
G01X36377Y175551D02*
X36410Y175558D01*
G01X31357Y173281D02*
X31331Y173249D01*
G01X31388Y173300D02*
X31357Y173281D01*
G01X31421Y173307D02*
X31388Y173300D01*
G01X31753Y172743D02*
X31780Y172774D01*
G01X31723Y172723D02*
X31753Y172743D01*
G01X31690Y172717D02*
X31723Y172723D01*
G01X37552Y171115D02*
X37526Y171084D01*
G01X37583Y171135D02*
X37552Y171115D01*
G01X37615Y171142D02*
X37583Y171135D01*
G01X36440Y170578D02*
X36467Y170609D01*
G01X36410Y170558D02*
X36440Y170578D01*
G01X36377Y170551D02*
X36410Y170558D01*
G01X31357Y168281D02*
X31331Y168249D01*
G01X31388Y168300D02*
X31357Y168281D01*
G01X31421Y168307D02*
X31388Y168300D01*
G01X31753Y167743D02*
X31780Y167774D01*
G01X31723Y167723D02*
X31753Y167743D01*
G01X31690Y167717D02*
X31723Y167723D01*
G01X37552Y166115D02*
X37526Y166084D01*
G01X37583Y166135D02*
X37552Y166115D01*
G01X37615Y166142D02*
X37583Y166135D01*
G01X36440Y165578D02*
X36467Y165609D01*
G01X36410Y165558D02*
X36440Y165578D01*
G01X36377Y165551D02*
X36410Y165558D01*
G01X31357Y163281D02*
X31331Y163249D01*
G01X31388Y163300D02*
X31357Y163281D01*
G01X31421Y163307D02*
X31388Y163300D01*
G01X31753Y162743D02*
X31780Y162774D01*
G01X31723Y162723D02*
X31753Y162743D01*
G01X31690Y162717D02*
X31723Y162723D01*
G01X37194Y178281D02*
X37221Y178249D01*
G01X36798Y177743D02*
X36772Y177774D01*
G01X36829Y177723D02*
X36798Y177743D01*
G01X36861Y177717D02*
X36829Y177723D01*
G01X30999Y176115D02*
X31026Y176084D01*
G01X30969Y176135D02*
X30999Y176115D01*
G01X30936Y176142D02*
X30969Y176135D01*
G01X32111Y175578D02*
X32085Y175609D01*
G01X32142Y175558D02*
X32111Y175578D01*
G01X32174Y175551D02*
X32142Y175558D01*
G01X37194Y173281D02*
X37221Y173249D01*
G01X37164Y173300D02*
X37194Y173281D01*
G01X37131Y173307D02*
X37164Y173300D01*
G01X36798Y172743D02*
X36772Y172774D01*
G01X36829Y172723D02*
X36798Y172743D01*
G01X36861Y172717D02*
X36829Y172723D01*
G01X30999Y171115D02*
X31026Y171084D01*
G01X30969Y171135D02*
X30999Y171115D01*
G01X30936Y171142D02*
X30969Y171135D01*
G01X32111Y170578D02*
X32085Y170609D01*
G01X32142Y170558D02*
X32111Y170578D01*
G01X32174Y170551D02*
X32142Y170558D01*
G01X37194Y168281D02*
X37221Y168249D01*
G01X37164Y168300D02*
X37194Y168281D01*
G01X37131Y168307D02*
X37164Y168300D01*
G01X36798Y167743D02*
X36772Y167774D01*
G01X36829Y167723D02*
X36798Y167743D01*
G01X36861Y167717D02*
X36829Y167723D01*
G01X30999Y166115D02*
X31026Y166084D01*
G01X30969Y166135D02*
X30999Y166115D01*
G01X30936Y166142D02*
X30969Y166135D01*
G01X32111Y165578D02*
X32085Y165609D01*
G01X32142Y165558D02*
X32111Y165578D01*
G01X32174Y165551D02*
X32142Y165558D01*
G01X37194Y163281D02*
X37221Y163249D01*
G01X37164Y163300D02*
X37194Y163281D01*
G01X37131Y163307D02*
X37164Y163300D01*
G01X36798Y162743D02*
X36772Y162774D01*
G01X36829Y162723D02*
X36798Y162743D01*
G01X36861Y162717D02*
X36829Y162723D01*
G01X37583Y177723D02*
X37615Y177717D01*
G01X37552Y177743D02*
X37583Y177723D01*
G01X37526Y177774D02*
X37552Y177743D01*
G01X36467Y178249D02*
X36440Y178281D01*
G01X37583Y172723D02*
X37615Y172717D01*
G01X37552Y172743D02*
X37583Y172723D01*
G01X37526Y172774D02*
X37552Y172743D01*
G01X36410Y173300D02*
X36377Y173307D01*
G01X36440Y173281D02*
X36410Y173300D01*
G01X36467Y173249D02*
X36440Y173281D01*
G01X31723Y176135D02*
X31690Y176142D01*
G01X31753Y176115D02*
X31723Y176135D01*
G01X31780Y176084D02*
X31753Y176115D01*
G01X31388Y175558D02*
X31421Y175551D01*
G01X31357Y175578D02*
X31388Y175558D01*
G01X31331Y175609D02*
X31357Y175578D01*
G01X37583Y167723D02*
X37615Y167717D01*
G01X37552Y167743D02*
X37583Y167723D01*
G01X37526Y167774D02*
X37552Y167743D01*
G01X36410Y168300D02*
X36377Y168307D01*
G01X36440Y168281D02*
X36410Y168300D01*
G01X36467Y168249D02*
X36440Y168281D01*
G01X31723Y171135D02*
X31690Y171142D01*
G01X31753Y171115D02*
X31723Y171135D01*
G01X31780Y171084D02*
X31753Y171115D01*
G01X31388Y170558D02*
X31421Y170551D01*
G01X31357Y170578D02*
X31388Y170558D01*
G01X31331Y170609D02*
X31357Y170578D01*
G01X37583Y162723D02*
X37615Y162717D01*
G01X37552Y162743D02*
X37583Y162723D01*
G01X37526Y162774D02*
X37552Y162743D01*
G01X36410Y163300D02*
X36377Y163307D01*
G01X36440Y163281D02*
X36410Y163300D01*
G01X36467Y163249D02*
X36440Y163281D01*
G01X31723Y166135D02*
X31690Y166142D01*
G01X31753Y166115D02*
X31723Y166135D01*
G01X31780Y166084D02*
X31753Y166115D01*
G01X31388Y165558D02*
X31421Y165551D01*
G01X31357Y165578D02*
X31388Y165558D01*
G01X31331Y165609D02*
X31357Y165578D01*
G01X37164Y165558D02*
X37131Y165551D01*
G01X37194Y165578D02*
X37164Y165558D01*
G01X37221Y165609D02*
X37194Y165578D01*
G01X36829Y166135D02*
X36861Y166142D01*
G01X36798Y166115D02*
X36829Y166135D01*
G01X36772Y166084D02*
X36798Y166115D01*
G01X32142Y163300D02*
X32174Y163307D01*
G01X32111Y163281D02*
X32142Y163300D01*
G01X32085Y163249D02*
X32111Y163281D01*
G01X30969Y162723D02*
X30936Y162717D01*
G01X30999Y162743D02*
X30969Y162723D01*
G01X31026Y162774D02*
X30999Y162743D01*
G01X37164Y170558D02*
X37131Y170551D01*
G01X37194Y170578D02*
X37164Y170558D01*
G01X37221Y170609D02*
X37194Y170578D01*
G01X36829Y171135D02*
X36861Y171142D01*
G01X36798Y171115D02*
X36829Y171135D01*
G01X36772Y171084D02*
X36798Y171115D01*
G01X32142Y168300D02*
X32174Y168307D01*
G01X32111Y168281D02*
X32142Y168300D01*
G01X32085Y168249D02*
X32111Y168281D01*
G01X30969Y167723D02*
X30936Y167717D01*
G01X30999Y167743D02*
X30969Y167723D01*
G01X31026Y167774D02*
X30999Y167743D01*
G01X37164Y175558D02*
X37131Y175551D01*
G01X37194Y175578D02*
X37164Y175558D01*
G01X37221Y175609D02*
X37194Y175578D01*
G01X36829Y176135D02*
X36861Y176142D01*
G01X36798Y176115D02*
X36829Y176135D01*
G01X36772Y176084D02*
X36798Y176115D01*
G01X32142Y173300D02*
X32174Y173307D01*
G01X32111Y173281D02*
X32142Y173300D01*
G01X32085Y173249D02*
X32111Y173281D01*
G01X30969Y172723D02*
X30936Y172717D01*
G01X30999Y172743D02*
X30969Y172723D01*
G01X31026Y172774D02*
X30999Y172743D01*
G01X32085Y178249D02*
X32111Y178281D01*
G01X30969Y177723D02*
X30936Y177717D01*
G01X30999Y177743D02*
X30969Y177723D01*
G01X31026Y177774D02*
X30999Y177743D01*
G01X23959Y166634D02*
G03X23582Y166555I-180J-79D01*
G01Y167894D02*
G03X23959Y167815I197J0D01*
G01X23582Y164744D02*
G03X23959Y164665I197J0D01*
G01Y163484D02*
G03X23582Y163406I-180J-79D01*
G01X28941Y167913D02*
G03X29138Y167717I197J1D01*
G01Y166142D02*
G03X28941Y165945I0J-197D01*
G01Y162913D02*
G03X29138Y162717I197J1D01*
G01X23959Y169783D02*
G03X23582Y169704I-180J-79D01*
G01Y171043D02*
G03X23959Y170965I197J1D01*
G01Y176083D02*
G03X23582Y176004I-180J-79D01*
G01Y177343D02*
G03X23959Y177264I197J0D01*
G01X23582Y174193D02*
G03X23959Y174114I197J0D01*
G01Y172933D02*
G03X23582Y172854I-180J-79D01*
G01X28941Y177913D02*
G03X29138Y177717I197J1D01*
G01Y176142D02*
G03X28941Y175945I0J-197D01*
G01Y172913D02*
G03X29138Y172717I197J1D01*
G01Y171142D02*
G03X28941Y170945I0J-197D01*
G01X31331Y178249D02*
X31026Y177774D01*
G01X31780D02*
X32085Y178249D01*
G01X31331Y173249D02*
X31026Y172774D01*
G01X31780D02*
X32085Y173249D01*
G01X26602Y176083D02*
X26681Y176240D01*
G01X27363D02*
X27284Y176083D01*
G01X26602Y172933D02*
X26681Y173091D01*
G01X27363D02*
X27284Y172933D01*
G01X26602Y169783D02*
X26681Y169941D01*
G01X27363D02*
X27284Y169783D01*
G01X26602Y166634D02*
X26681Y166791D01*
G01X27363D02*
X27284Y166634D01*
G01X26602Y163484D02*
X26681Y163642D01*
G01X27363D02*
X27284Y163484D01*
G01X31331Y168249D02*
X31026Y167774D01*
G01X36467Y175609D02*
X36772Y176084D01*
G01X31780Y167774D02*
X32085Y168249D01*
G01X37526Y176084D02*
X37221Y175609D01*
G01X31331Y163249D02*
X31026Y162774D01*
G01X36467Y170609D02*
X36772Y171084D01*
G01X31780Y162774D02*
X32085Y163249D01*
G01X37526Y171084D02*
X37221Y170609D01*
G01X36467Y165609D02*
X36772Y166084D01*
G01X37526D02*
X37221Y165609D01*
G01X23582Y163406D02*
Y162886D01*
G01Y166555D02*
Y166036D01*
G01Y165272D02*
Y164744D01*
G01Y168422D02*
Y167894D01*
G01Y169704D02*
Y169185D01*
G01Y171571D02*
Y171043D01*
G01Y172854D02*
Y172335D01*
G01Y176004D02*
Y175485D01*
G01Y174721D02*
Y174193D01*
G01Y177870D02*
Y177343D01*
G01X24190Y176083D02*
Y177264D01*
G01Y172933D02*
Y174114D01*
G01Y169783D02*
Y170965D01*
G01Y166634D02*
Y167815D01*
G01Y163484D02*
Y164665D01*
G01X25043D02*
Y163484D01*
G01Y167815D02*
Y166634D01*
G01Y170965D02*
Y169783D01*
G01Y174114D02*
Y172933D01*
G01Y177264D02*
Y176083D01*
G01X25724D02*
Y177264D01*
G01Y172933D02*
Y174114D01*
G01Y169783D02*
Y170965D01*
G01Y166634D02*
Y167815D01*
G01Y163484D02*
Y164665D01*
G01X27346Y176240D02*
Y177106D01*
G01Y173091D02*
Y173957D01*
G01Y169941D02*
Y170807D01*
G01Y166791D02*
Y167658D01*
G01Y163642D02*
Y164508D01*
G01X28028D02*
Y163642D01*
G01Y167658D02*
Y166791D01*
G01Y170807D02*
Y169941D01*
G01Y173957D02*
Y173091D01*
G01Y177106D02*
Y176240D01*
G01X28881D02*
Y177106D01*
G01Y173091D02*
Y173957D01*
G01Y169941D02*
Y170807D01*
G01Y166791D02*
Y167658D01*
G01Y163642D02*
Y164508D01*
G01X28941Y165945D02*
Y164961D01*
G01Y173898D02*
Y172913D01*
G01Y175945D02*
Y174961D01*
G01Y178898D02*
Y177913D01*
G01Y169961D02*
Y170945D01*
G01Y167913D02*
Y168898D01*
G01Y162913D02*
Y163898D01*
G01X29728Y167717D02*
Y166142D01*
G01Y172717D02*
Y171142D01*
G01Y176142D02*
Y177717D01*
G01X30482Y176142D02*
Y177717D01*
G01Y171142D02*
Y172717D01*
G01Y166142D02*
Y167717D01*
G01X31236Y172717D02*
Y171142D01*
G01Y177717D02*
Y176142D01*
G01Y166142D02*
Y167717D01*
G01X31637Y164508D02*
Y163642D01*
G01Y173957D02*
Y173091D01*
G01Y176240D02*
Y177106D01*
G01Y169941D02*
Y170807D01*
G01Y166791D02*
Y167658D01*
G01X37339Y167717D02*
Y166142D01*
G01Y172717D02*
Y171142D01*
G01Y177717D02*
Y176142D01*
G01X38093D02*
Y177717D01*
G01Y171142D02*
Y172717D01*
G01Y166142D02*
Y167717D01*
G01X38847Y176142D02*
Y177717D01*
G01Y171142D02*
Y172717D01*
G01Y166142D02*
Y167717D01*
G01X26681Y164508D02*
X26602Y164665D01*
G01X27284D02*
X27363Y164508D01*
G01X26681Y167658D02*
X26602Y167815D01*
G01X27284D02*
X27363Y167658D01*
G01X26681Y170807D02*
X26602Y170965D01*
G01X27284D02*
X27363Y170807D01*
G01X26681Y173957D02*
X26602Y174114D01*
G01X27284D02*
X27363Y173957D01*
G01X26681Y177106D02*
X26602Y177264D01*
G01X27284D02*
X27363Y177106D01*
G01X31026Y166084D02*
X31331Y165609D01*
G01X32085D02*
X31780Y166084D01*
G01X31026Y171084D02*
X31331Y170609D01*
G01X36772Y162774D02*
X36467Y163249D01*
G01X32085Y170609D02*
X31780Y171084D01*
G01X37221Y163249D02*
X37526Y162774D01*
G01X31026Y176084D02*
X31331Y175609D01*
G01X36772Y167774D02*
X36467Y168249D01*
G01X32085Y175609D02*
X31780Y176084D01*
G01X37221Y168249D02*
X37526Y167774D01*
G01X36772Y172774D02*
X36467Y173249D01*
G01X37221D02*
X37526Y172774D01*
G01X36772Y177774D02*
X36467Y178249D01*
G01X37221D02*
X37526Y177774D01*
G01X23385Y162122D02*
X23582D01*
G01X31690Y162717D02*
X29138D01*
G01X41603D02*
X36861D01*
G01X37526Y162774D02*
X36772D01*
G01X31026D02*
X31780D01*
G01X23385Y162886D02*
X23582D01*
G01X32085Y163249D02*
X31331D01*
G01X36467D02*
X37221D01*
G01X31421Y163307D02*
X37131D01*
G01X27284Y163484D02*
X23959D01*
G01X31637Y163642D02*
X26681D01*
G01X25590Y163898D02*
X28941D01*
G01X26681Y164508D02*
X31637D01*
G01X27284Y164665D02*
X23959D01*
G01X28941Y164961D02*
X25590D01*
G01X23385Y165272D02*
X23582D01*
G01X37131Y165551D02*
X31421D01*
G01X32085Y165609D02*
X31331D01*
G01X36467D02*
X37221D01*
G01X23582Y166036D02*
X23385D01*
G01X36772Y166084D02*
X37526D01*
G01X31026D02*
X31780D01*
G01X31690Y166142D02*
X29138D01*
G01X41603D02*
X36861D01*
G01X27284Y166634D02*
X23959D01*
G01X31637Y166791D02*
X26681D01*
G01Y167658D02*
X31637D01*
G01X31690Y167717D02*
X29138D01*
G01X41603D02*
X36861D01*
G01X37526Y167774D02*
X36772D01*
G01X31026D02*
X31780D01*
G01X27284Y167815D02*
X23959D01*
G01X32085Y168249D02*
X31331D01*
G01X36467D02*
X37221D01*
G01X31421Y168307D02*
X37131D01*
G01X23385Y168422D02*
X23582D01*
G01X25590Y168898D02*
X28941D01*
G01X23582Y169185D02*
X23385D01*
G01X27284Y169783D02*
X23959D01*
G01X31637Y169941D02*
X26681D01*
G01X28941Y169961D02*
X25590D01*
G01X37131Y170551D02*
X31421D01*
G01X36467Y170609D02*
X37221D01*
G01X31331D02*
X32085D01*
G01X26681Y170807D02*
X31637D01*
G01X27284Y170965D02*
X23959D01*
G01X37526Y171084D02*
X36772D01*
G01X31026D02*
X31780D01*
G01X31690Y171142D02*
X29138D01*
G01X41603D02*
X36861D01*
G01X23385Y171571D02*
X23582D01*
G01X23385Y172335D02*
X23582D01*
G01X31690Y172717D02*
X29138D01*
G01X41603D02*
X36861D01*
G01X37526Y172774D02*
X36772D01*
G01X31026D02*
X31780D01*
G01X27284Y172933D02*
X23959D01*
G01X31637Y173091D02*
X26681D01*
G01X32085Y173249D02*
X31331D01*
G01X36467D02*
X37221D01*
G01X31421Y173307D02*
X37131D01*
G01X25590Y173898D02*
X28941D01*
G01X26681Y173957D02*
X31637D01*
G01X27284Y174114D02*
X23959D01*
G01X23385Y174721D02*
X23582D01*
G01X28941Y174961D02*
X25590D01*
G01X23582Y175485D02*
X23385D01*
G01X37131Y175551D02*
X31421D01*
G01X32085Y175609D02*
X31331D01*
G01X36467D02*
X37221D01*
G01X27284Y176083D02*
X23959D01*
G01X36772Y176084D02*
X37526D01*
G01X31026D02*
X31780D01*
G01X31690Y176142D02*
X29138D01*
G01X41603D02*
X36861D01*
G01X31637Y176240D02*
X26681D01*
G01Y177106D02*
X31637D01*
G01X27284Y177264D02*
X23959D01*
G01X31690Y177717D02*
X29138D01*
G01X41603D02*
X36861D01*
G01X37526Y177774D02*
X36772D01*
G01X31026D02*
X31780D01*
G01X23385Y177870D02*
X23582D01*
G01X32085Y178249D02*
X31331D01*
G01X36467D02*
X37221D01*
G01X31357Y193281D02*
X31331Y193249D01*
G01X31388Y193300D02*
X31357Y193281D01*
G01X31421Y193307D02*
X31388Y193300D01*
G01X31753Y192743D02*
X31780Y192774D01*
G01X31723Y192723D02*
X31753Y192743D01*
G01X31690Y192717D02*
X31723Y192723D01*
G01X37552Y191115D02*
X37526Y191084D01*
G01X37583Y191135D02*
X37552Y191115D01*
G01X37615Y191142D02*
X37583Y191135D01*
G01X36440Y190578D02*
X36467Y190609D01*
G01X36410Y190558D02*
X36440Y190578D01*
G01X36377Y190551D02*
X36410Y190558D01*
G01X31357Y188281D02*
X31331Y188249D01*
G01X31388Y188300D02*
X31357Y188281D01*
G01X31421Y188307D02*
X31388Y188300D01*
G01X31753Y187743D02*
X31780Y187774D01*
G01X31723Y187723D02*
X31753Y187743D01*
G01X31690Y187717D02*
X31723Y187723D01*
G01X37552Y186115D02*
X37526Y186084D01*
G01X37583Y186135D02*
X37552Y186115D01*
G01X37615Y186142D02*
X37583Y186135D01*
G01X36440Y185578D02*
X36467Y185609D01*
G01X36410Y185558D02*
X36440Y185578D01*
G01X36377Y185551D02*
X36410Y185558D01*
G01X31357Y183281D02*
X31331Y183249D01*
G01X31388Y183300D02*
X31357Y183281D01*
G01X31421Y183307D02*
X31388Y183300D01*
G01X31753Y182743D02*
X31780Y182774D01*
G01X31723Y182723D02*
X31753Y182743D01*
G01X31690Y182717D02*
X31723Y182723D01*
G01X37552Y181115D02*
X37526Y181084D01*
G01X37583Y181135D02*
X37552Y181115D01*
G01X37615Y181142D02*
X37583Y181135D01*
G01X36440Y180578D02*
X36467Y180609D01*
G01X36410Y180558D02*
X36440Y180578D01*
G01X36377Y180551D02*
X36410Y180558D01*
G01X31388Y178300D02*
X31357Y178281D01*
G01X31421Y178307D02*
X31388Y178300D01*
G01X37194Y193281D02*
X37221Y193249D01*
G01X37164Y193300D02*
X37194Y193281D01*
G01X37131Y193307D02*
X37164Y193300D01*
G01X36798Y192743D02*
X36772Y192774D01*
G01X36829Y192723D02*
X36798Y192743D01*
G01X36861Y192717D02*
X36829Y192723D01*
G01X30999Y191115D02*
X31026Y191084D01*
G01X30969Y191135D02*
X30999Y191115D01*
G01X30936Y191142D02*
X30969Y191135D01*
G01X32111Y190578D02*
X32085Y190609D01*
G01X32142Y190558D02*
X32111Y190578D01*
G01X32174Y190551D02*
X32142Y190558D01*
G01X37194Y188281D02*
X37221Y188249D01*
G01X37164Y188300D02*
X37194Y188281D01*
G01X37131Y188307D02*
X37164Y188300D01*
G01X36798Y187743D02*
X36772Y187774D01*
G01X36829Y187723D02*
X36798Y187743D01*
G01X36861Y187717D02*
X36829Y187723D01*
G01X30999Y186115D02*
X31026Y186084D01*
G01X30969Y186135D02*
X30999Y186115D01*
G01X30936Y186142D02*
X30969Y186135D01*
G01X32111Y185578D02*
X32085Y185609D01*
G01X32142Y185558D02*
X32111Y185578D01*
G01X32174Y185551D02*
X32142Y185558D01*
G01X37194Y183281D02*
X37221Y183249D01*
G01X37164Y183300D02*
X37194Y183281D01*
G01X37131Y183307D02*
X37164Y183300D01*
G01X36798Y182743D02*
X36772Y182774D01*
G01X36829Y182723D02*
X36798Y182743D01*
G01X36861Y182717D02*
X36829Y182723D01*
G01X30999Y181115D02*
X31026Y181084D01*
G01X30969Y181135D02*
X30999Y181115D01*
G01X30936Y181142D02*
X30969Y181135D01*
G01X32111Y180578D02*
X32085Y180609D01*
G01X32142Y180558D02*
X32111Y180578D01*
G01X32174Y180551D02*
X32142Y180558D01*
G01X37164Y178300D02*
X37194Y178281D01*
G01X37131Y178307D02*
X37164Y178300D01*
G01X37583Y192723D02*
X37615Y192717D01*
G01X37552Y192743D02*
X37583Y192723D01*
G01X37526Y192774D02*
X37552Y192743D01*
G01X36410Y193300D02*
X36377Y193307D01*
G01X36440Y193281D02*
X36410Y193300D01*
G01X36467Y193249D02*
X36440Y193281D01*
G01X37583Y187723D02*
X37615Y187717D01*
G01X37552Y187743D02*
X37583Y187723D01*
G01X37526Y187774D02*
X37552Y187743D01*
G01X36410Y188300D02*
X36377Y188307D01*
G01X36440Y188281D02*
X36410Y188300D01*
G01X36467Y188249D02*
X36440Y188281D01*
G01X31723Y191135D02*
X31690Y191142D01*
G01X31753Y191115D02*
X31723Y191135D01*
G01X31780Y191084D02*
X31753Y191115D01*
G01X31388Y190558D02*
X31421Y190551D01*
G01X31357Y190578D02*
X31388Y190558D01*
G01X31331Y190609D02*
X31357Y190578D01*
G01X37583Y182723D02*
X37615Y182717D01*
G01X37552Y182743D02*
X37583Y182723D01*
G01X37526Y182774D02*
X37552Y182743D01*
G01X36410Y183300D02*
X36377Y183307D01*
G01X36440Y183281D02*
X36410Y183300D01*
G01X36467Y183249D02*
X36440Y183281D01*
G01X31723Y186135D02*
X31690Y186142D01*
G01X31753Y186115D02*
X31723Y186135D01*
G01X31780Y186084D02*
X31753Y186115D01*
G01X31388Y185558D02*
X31421Y185551D01*
G01X31357Y185578D02*
X31388Y185558D01*
G01X31331Y185609D02*
X31357Y185578D01*
G01X36410Y178300D02*
X36377Y178307D01*
G01X36440Y178281D02*
X36410Y178300D01*
G01X31723Y181135D02*
X31690Y181142D01*
G01X31753Y181115D02*
X31723Y181135D01*
G01X31780Y181084D02*
X31753Y181115D01*
G01X31388Y180558D02*
X31421Y180551D01*
G01X31357Y180578D02*
X31388Y180558D01*
G01X31331Y180609D02*
X31357Y180578D01*
G01X37164Y180558D02*
X37131Y180551D01*
G01X37194Y180578D02*
X37164Y180558D01*
G01X37221Y180609D02*
X37194Y180578D01*
G01X36829Y181135D02*
X36861Y181142D01*
G01X36798Y181115D02*
X36829Y181135D01*
G01X36772Y181084D02*
X36798Y181115D01*
G01X32142Y178300D02*
X32174Y178307D01*
G01X32111Y178281D02*
X32142Y178300D01*
G01X37164Y185558D02*
X37131Y185551D01*
G01X37194Y185578D02*
X37164Y185558D01*
G01X37221Y185609D02*
X37194Y185578D01*
G01X36829Y186135D02*
X36861Y186142D01*
G01X36798Y186115D02*
X36829Y186135D01*
G01X36772Y186084D02*
X36798Y186115D01*
G01X32142Y183300D02*
X32174Y183307D01*
G01X32111Y183281D02*
X32142Y183300D01*
G01X32085Y183249D02*
X32111Y183281D01*
G01X30969Y182723D02*
X30936Y182717D01*
G01X30999Y182743D02*
X30969Y182723D01*
G01X31026Y182774D02*
X30999Y182743D01*
G01X37164Y190558D02*
X37131Y190551D01*
G01X37194Y190578D02*
X37164Y190558D01*
G01X37221Y190609D02*
X37194Y190578D01*
G01X36829Y191135D02*
X36861Y191142D01*
G01X36798Y191115D02*
X36829Y191135D01*
G01X36772Y191084D02*
X36798Y191115D01*
G01X32142Y188300D02*
X32174Y188307D01*
G01X32111Y188281D02*
X32142Y188300D01*
G01X32085Y188249D02*
X32111Y188281D01*
G01X30969Y187723D02*
X30936Y187717D01*
G01X30999Y187743D02*
X30969Y187723D01*
G01X31026Y187774D02*
X30999Y187743D01*
G01X32142Y193300D02*
X32174Y193307D01*
G01X32111Y193281D02*
X32142Y193300D01*
G01X32085Y193249D02*
X32111Y193281D01*
G01X30969Y192723D02*
X30936Y192717D01*
G01X30999Y192743D02*
X30969Y192723D01*
G01X31026Y192774D02*
X30999Y192743D01*
G01X23959Y179232D02*
G03X23582Y179153I-180J-79D01*
G01X23959Y188681D02*
G03X23582Y188602I-180J-79D01*
G01Y189941D02*
G03X23959Y189862I197J0D01*
G01X23582Y180492D02*
G03X23959Y180413I197J0D01*
G01Y185532D02*
G03X23582Y185452I-180J-79D01*
G01Y186791D02*
G03X23959Y186713I197J1D01*
G01X23582Y183642D02*
G03X23959Y183563I197J0D01*
G01Y182382D02*
G03X23582Y182303I-180J-79D01*
G01X28941Y182913D02*
G03X29138Y182717I197J1D01*
G01Y181142D02*
G03X28941Y180945I0J-197D01*
G01Y187913D02*
G03X29138Y187717I197J1D01*
G01Y186142D02*
G03X28941Y185945I0J-197D01*
G01X23582Y193091D02*
G03X23959Y193012I197J0D01*
G01Y191831D02*
G03X23582Y191752I-180J-79D01*
G01X28941Y192913D02*
G03X29138Y192717I197J1D01*
G01Y191142D02*
G03X28941Y190945I0J-197D01*
G01X31331Y193249D02*
X31026Y192774D01*
G01X31780D02*
X32085Y193249D01*
G01X31331Y188249D02*
X31026Y187774D01*
G01X31780D02*
X32085Y188249D01*
G01X31331Y183249D02*
X31026Y182774D01*
G01X36467Y190609D02*
X36772Y191084D01*
G01X31780Y182774D02*
X32085Y183249D01*
G01X37526Y191084D02*
X37221Y190609D01*
G01X36467Y185609D02*
X36772Y186084D01*
G01X37526D02*
X37221Y185609D01*
G01X36467Y180609D02*
X36772Y181084D01*
G01X37526D02*
X37221Y180609D01*
G01X26602Y191831D02*
X26681Y191988D01*
G01X27363D02*
X27284Y191831D01*
G01X26602Y188681D02*
X26681Y188839D01*
G01X27363D02*
X27284Y188681D01*
G01X26602Y185532D02*
X26681Y185689D01*
G01X27363D02*
X27284Y185532D01*
G01X26602Y182382D02*
X26681Y182539D01*
G01X27363D02*
X27284Y182382D01*
G01X26602Y179232D02*
X26681Y179390D01*
G01X27363D02*
X27284Y179232D01*
G01X23582Y179153D02*
Y178634D01*
G01Y181020D02*
Y180492D01*
G01Y182303D02*
Y181784D01*
G01Y185452D02*
Y184933D01*
G01Y184170D02*
Y183642D01*
G01Y187319D02*
Y186791D01*
G01Y188602D02*
Y188083D01*
G01Y190469D02*
Y189941D01*
G01Y191752D02*
Y191233D01*
G01Y194901D02*
Y194382D01*
G01Y193091D02*
Y193619D01*
G01X24190Y191831D02*
Y193012D01*
G01Y188681D02*
Y189862D01*
G01Y185532D02*
Y186713D01*
G01Y182382D02*
Y183563D01*
G01Y179232D02*
Y180413D01*
G01X25043D02*
Y179232D01*
G01Y183563D02*
Y182382D01*
G01Y186713D02*
Y185532D01*
G01Y189862D02*
Y188681D01*
G01Y193012D02*
Y191831D01*
G01X25570Y183393D02*
Y181307D01*
G01X25724Y191831D02*
Y193012D01*
G01Y188681D02*
Y189862D01*
G01Y185532D02*
Y186713D01*
G01Y182382D02*
Y183563D01*
G01Y179232D02*
Y180413D01*
G01X27346Y191988D02*
Y192854D01*
G01Y188839D02*
Y189705D01*
G01Y185689D02*
Y186555D01*
G01Y182539D02*
Y183406D01*
G01Y179390D02*
Y180256D01*
G01X28028D02*
Y179390D01*
G01Y183406D02*
Y182539D01*
G01Y186555D02*
Y185689D01*
G01Y189705D02*
Y188839D01*
G01Y192854D02*
Y191988D01*
G01X28881D02*
Y192854D01*
G01Y188839D02*
Y189705D01*
G01Y185689D02*
Y186555D01*
G01Y182539D02*
Y183406D01*
G01Y179390D02*
Y180256D01*
G01X28941Y180945D02*
Y179961D01*
G01Y183898D02*
Y182913D01*
G01Y185945D02*
Y184961D01*
G01Y190945D02*
Y189961D01*
G01Y193898D02*
Y192913D01*
G01Y187913D02*
Y188898D01*
G01X29728Y187717D02*
Y186142D01*
G01Y191142D02*
Y192717D01*
G01Y181142D02*
Y182717D01*
G01X30482Y191142D02*
Y192717D01*
G01Y186142D02*
Y187717D01*
G01Y181142D02*
Y182717D01*
G01X31236D02*
Y181142D01*
G01Y192717D02*
Y191142D01*
G01Y186142D02*
Y187717D01*
G01X31637Y183406D02*
Y182539D01*
G01Y192854D02*
Y191988D01*
G01Y188839D02*
Y189705D01*
G01Y185689D02*
Y186555D01*
G01Y179390D02*
Y180256D01*
G01X37339Y182717D02*
Y181142D01*
G01Y187717D02*
Y186142D01*
G01Y192717D02*
Y191142D01*
G01X38093D02*
Y192717D01*
G01Y186142D02*
Y187717D01*
G01Y181142D02*
Y182717D01*
G01X38847Y191142D02*
Y192717D01*
G01Y186142D02*
Y187717D01*
G01Y181142D02*
Y182717D01*
G01X26681Y180256D02*
X26602Y180413D01*
G01X27284D02*
X27363Y180256D01*
G01X26681Y183406D02*
X26602Y183563D01*
G01X27284D02*
X27363Y183406D01*
G01X26681Y186555D02*
X26602Y186713D01*
G01X27284D02*
X27363Y186555D01*
G01X26681Y189705D02*
X26602Y189862D01*
G01X27284D02*
X27363Y189705D01*
G01X26681Y192854D02*
X26602Y193012D01*
G01X27284D02*
X27363Y192854D01*
G01X31026Y181084D02*
X31331Y180609D01*
G01X32085D02*
X31780Y181084D01*
G01X31026Y186084D02*
X31331Y185609D01*
G01X32085D02*
X31780Y186084D01*
G01X31026Y191084D02*
X31331Y190609D01*
G01X36772Y182774D02*
X36467Y183249D01*
G01X32085Y190609D02*
X31780Y191084D01*
G01X37221Y183249D02*
X37526Y182774D01*
G01X36772Y187774D02*
X36467Y188249D01*
G01X37221D02*
X37526Y187774D01*
G01X36772Y192774D02*
X36467Y193249D01*
G01X37221D02*
X37526Y192774D01*
G01X31421Y178307D02*
X37131D01*
G01X23582Y178634D02*
X23385D01*
G01X25590Y178898D02*
X28941D01*
G01X27284Y179232D02*
X23959D01*
G01X31637Y179390D02*
X26681D01*
G01X28941Y179961D02*
X25590D01*
G01X26681Y180256D02*
X31637D01*
G01X27284Y180413D02*
X23959D01*
G01X37131Y180551D02*
X31421D01*
G01X32085Y180609D02*
X31331D01*
G01X36467D02*
X37221D01*
G01X23385Y181020D02*
X23582D01*
G01X36772Y181084D02*
X37526D01*
G01X31026D02*
X31780D01*
G01X31690Y181142D02*
X29138D01*
G01X41603D02*
X36861D01*
G01X23385Y181784D02*
X23582D01*
G01X27284Y182382D02*
X23959D01*
G01X31637Y182539D02*
X26681D01*
G01X31690Y182717D02*
X29138D01*
G01X41603D02*
X36861D01*
G01X37526Y182774D02*
X36772D01*
G01X31026D02*
X31780D01*
G01X32085Y183249D02*
X31331D01*
G01X36467D02*
X37221D01*
G01X31421Y183307D02*
X37131D01*
G01X26681Y183406D02*
X31637D01*
G01X27284Y183563D02*
X23959D01*
G01X25590Y183898D02*
X28941D01*
G01X23385Y184170D02*
X23582D01*
G01Y184933D02*
X23385D01*
G01X28941Y184961D02*
X25590D01*
G01X27284Y185532D02*
X23959D01*
G01X37131Y185551D02*
X31421D01*
G01X32085Y185609D02*
X31331D01*
G01X36467D02*
X37221D01*
G01X31637Y185689D02*
X26681D01*
G01X36772Y186084D02*
X37526D01*
G01X31026D02*
X31780D01*
G01X31690Y186142D02*
X29138D01*
G01X41603D02*
X36861D01*
G01X26681Y186555D02*
X31637D01*
G01X27284Y186713D02*
X23959D01*
G01X23385Y187319D02*
X23582D01*
G01X31690Y187717D02*
X29138D01*
G01X41603D02*
X36861D01*
G01X37526Y187774D02*
X36772D01*
G01X31026D02*
X31780D01*
G01X23582Y188083D02*
X23385D01*
G01X32085Y188249D02*
X31331D01*
G01X36467D02*
X37221D01*
G01X31421Y188307D02*
X37131D01*
G01X27284Y188681D02*
X23959D01*
G01X31637Y188839D02*
X26681D01*
G01X25590Y188898D02*
X28941D01*
G01X26681Y189705D02*
X31637D01*
G01X27284Y189862D02*
X23959D01*
G01X28941Y189961D02*
X25590D01*
G01X23385Y190469D02*
X23582D01*
G01X37131Y190551D02*
X31421D01*
G01X32085Y190609D02*
X31331D01*
G01X36467D02*
X37221D01*
G01X36772Y191084D02*
X37526D01*
G01X31026D02*
X31780D01*
G01X31690Y191142D02*
X29138D01*
G01X41603D02*
X36861D01*
G01X23385Y191233D02*
X23582D01*
G01X27284Y191831D02*
X23959D01*
G01X31637Y191988D02*
X26681D01*
G01X31690Y192717D02*
X29138D01*
G01X41603D02*
X36861D01*
G01X37526Y192774D02*
X36772D01*
G01X31026D02*
X31780D01*
G01X26681Y192854D02*
X31637D01*
G01X27284Y193012D02*
X23959D01*
G01X32085Y193249D02*
X31331D01*
G01X36467D02*
X37221D01*
G01X31421Y193307D02*
X37131D01*
G01X23582Y193619D02*
X23385D01*
G01X25590Y193898D02*
X28941D01*
G01X23582Y194382D02*
X23385D01*
G01X37552Y211115D02*
X37526Y211084D01*
G01X37583Y211135D02*
X37552Y211115D01*
G01X37615Y211142D02*
X37583Y211135D01*
G01X36440Y210578D02*
X36467Y210609D01*
G01X36410Y210558D02*
X36440Y210578D01*
G01X36377Y210551D02*
X36410Y210558D01*
G01X31357Y208281D02*
X31331Y208249D01*
G01X31388Y208300D02*
X31357Y208281D01*
G01X31421Y208307D02*
X31388Y208300D01*
G01X31753Y207743D02*
X31780Y207774D01*
G01X31723Y207723D02*
X31753Y207743D01*
G01X31690Y207717D02*
X31723Y207723D01*
G01X37552Y206115D02*
X37526Y206084D01*
G01X37583Y206135D02*
X37552Y206115D01*
G01X37615Y206142D02*
X37583Y206135D01*
G01X36440Y205578D02*
X36467Y205609D01*
G01X36410Y205558D02*
X36440Y205578D01*
G01X36377Y205551D02*
X36410Y205558D01*
G01X31357Y203281D02*
X31331Y203249D01*
G01X31388Y203300D02*
X31357Y203281D01*
G01X31421Y203307D02*
X31388Y203300D01*
G01X31753Y202743D02*
X31780Y202774D01*
G01X31723Y202723D02*
X31753Y202743D01*
G01X31690Y202717D02*
X31723Y202723D01*
G01X37552Y201115D02*
X37526Y201084D01*
G01X37583Y201135D02*
X37552Y201115D01*
G01X37615Y201142D02*
X37583Y201135D01*
G01X36440Y200578D02*
X36467Y200609D01*
G01X36410Y200558D02*
X36440Y200578D01*
G01X36377Y200551D02*
X36410Y200558D01*
G01X31357Y198281D02*
X31331Y198249D01*
G01X31388Y198300D02*
X31357Y198281D01*
G01X31421Y198307D02*
X31388Y198300D01*
G01X31753Y197743D02*
X31780Y197774D01*
G01X31723Y197723D02*
X31753Y197743D01*
G01X31690Y197717D02*
X31723Y197723D01*
G01X37552Y196115D02*
X37526Y196084D01*
G01X37583Y196135D02*
X37552Y196115D01*
G01X37615Y196142D02*
X37583Y196135D01*
G01X36440Y195578D02*
X36467Y195609D01*
G01X36410Y195558D02*
X36440Y195578D01*
G01X36377Y195551D02*
X36410Y195558D01*
G01X30999Y211115D02*
X31026Y211084D01*
G01X30969Y211135D02*
X30999Y211115D01*
G01X30936Y211142D02*
X30969Y211135D01*
G01X32111Y210578D02*
X32085Y210609D01*
G01X32142Y210558D02*
X32111Y210578D01*
G01X32174Y210551D02*
X32142Y210558D01*
G01X37194Y208281D02*
X37221Y208249D01*
G01X37164Y208300D02*
X37194Y208281D01*
G01X37131Y208307D02*
X37164Y208300D01*
G01X36798Y207743D02*
X36772Y207774D01*
G01X36829Y207723D02*
X36798Y207743D01*
G01X36861Y207717D02*
X36829Y207723D01*
G01X30999Y206115D02*
X31026Y206084D01*
G01X30969Y206135D02*
X30999Y206115D01*
G01X30936Y206142D02*
X30969Y206135D01*
G01X32111Y205578D02*
X32085Y205609D01*
G01X32142Y205558D02*
X32111Y205578D01*
G01X32174Y205551D02*
X32142Y205558D01*
G01X37194Y203281D02*
X37221Y203249D01*
G01X37164Y203300D02*
X37194Y203281D01*
G01X37131Y203307D02*
X37164Y203300D01*
G01X36798Y202743D02*
X36772Y202774D01*
G01X36829Y202723D02*
X36798Y202743D01*
G01X36861Y202717D02*
X36829Y202723D01*
G01X30999Y201115D02*
X31026Y201084D01*
G01X30969Y201135D02*
X30999Y201115D01*
G01X30936Y201142D02*
X30969Y201135D01*
G01X32111Y200578D02*
X32085Y200609D01*
G01X32142Y200558D02*
X32111Y200578D01*
G01X32174Y200551D02*
X32142Y200558D01*
G01X37194Y198281D02*
X37221Y198249D01*
G01X37164Y198300D02*
X37194Y198281D01*
G01X37131Y198307D02*
X37164Y198300D01*
G01X36798Y197743D02*
X36772Y197774D01*
G01X36829Y197723D02*
X36798Y197743D01*
G01X36861Y197717D02*
X36829Y197723D01*
G01X30999Y196115D02*
X31026Y196084D01*
G01X30969Y196135D02*
X30999Y196115D01*
G01X30936Y196142D02*
X30969Y196135D01*
G01X32111Y195578D02*
X32085Y195609D01*
G01X32142Y195558D02*
X32111Y195578D01*
G01X32174Y195551D02*
X32142Y195558D01*
G01X37583Y207723D02*
X37615Y207717D01*
G01X37552Y207743D02*
X37583Y207723D01*
G01X37526Y207774D02*
X37552Y207743D01*
G01X36410Y208300D02*
X36377Y208307D01*
G01X36440Y208281D02*
X36410Y208300D01*
G01X36467Y208249D02*
X36440Y208281D01*
G01X31723Y211135D02*
X31690Y211142D01*
G01X31753Y211115D02*
X31723Y211135D01*
G01X31780Y211084D02*
X31753Y211115D01*
G01X31388Y210558D02*
X31421Y210551D01*
G01X31357Y210578D02*
X31388Y210558D01*
G01X31331Y210609D02*
X31357Y210578D01*
G01X37583Y202723D02*
X37615Y202717D01*
G01X37552Y202743D02*
X37583Y202723D01*
G01X37526Y202774D02*
X37552Y202743D01*
G01X36410Y203300D02*
X36377Y203307D01*
G01X36440Y203281D02*
X36410Y203300D01*
G01X36467Y203249D02*
X36440Y203281D01*
G01X31723Y206135D02*
X31690Y206142D01*
G01X31753Y206115D02*
X31723Y206135D01*
G01X31780Y206084D02*
X31753Y206115D01*
G01X31388Y205558D02*
X31421Y205551D01*
G01X31357Y205578D02*
X31388Y205558D01*
G01X31331Y205609D02*
X31357Y205578D01*
G01X37583Y197723D02*
X37615Y197717D01*
G01X37552Y197743D02*
X37583Y197723D01*
G01X37526Y197774D02*
X37552Y197743D01*
G01X36410Y198300D02*
X36377Y198307D01*
G01X36440Y198281D02*
X36410Y198300D01*
G01X36467Y198249D02*
X36440Y198281D01*
G01X31723Y201135D02*
X31690Y201142D01*
G01X31753Y201115D02*
X31723Y201135D01*
G01X31780Y201084D02*
X31753Y201115D01*
G01X31388Y200558D02*
X31421Y200551D01*
G01X31357Y200578D02*
X31388Y200558D01*
G01X31331Y200609D02*
X31357Y200578D01*
G01X31723Y196135D02*
X31690Y196142D01*
G01X31753Y196115D02*
X31723Y196135D01*
G01X31780Y196084D02*
X31753Y196115D01*
G01X31388Y195558D02*
X31421Y195551D01*
G01X31357Y195578D02*
X31388Y195558D01*
G01X31331Y195609D02*
X31357Y195578D01*
G01X37164Y195558D02*
X37131Y195551D01*
G01X37194Y195578D02*
X37164Y195558D01*
G01X37221Y195609D02*
X37194Y195578D01*
G01X36829Y196135D02*
X36861Y196142D01*
G01X36798Y196115D02*
X36829Y196135D01*
G01X36772Y196084D02*
X36798Y196115D01*
G01X37164Y200558D02*
X37131Y200551D01*
G01X37194Y200578D02*
X37164Y200558D01*
G01X37221Y200609D02*
X37194Y200578D01*
G01X36829Y201135D02*
X36861Y201142D01*
G01X36798Y201115D02*
X36829Y201135D01*
G01X36772Y201084D02*
X36798Y201115D01*
G01X32142Y198300D02*
X32174Y198307D01*
G01X32111Y198281D02*
X32142Y198300D01*
G01X32085Y198249D02*
X32111Y198281D01*
G01X30969Y197723D02*
X30936Y197717D01*
G01X30999Y197743D02*
X30969Y197723D01*
G01X31026Y197774D02*
X30999Y197743D01*
G01X37164Y205558D02*
X37131Y205551D01*
G01X37194Y205578D02*
X37164Y205558D01*
G01X37221Y205609D02*
X37194Y205578D01*
G01X36829Y206135D02*
X36861Y206142D01*
G01X36798Y206115D02*
X36829Y206135D01*
G01X36772Y206084D02*
X36798Y206115D01*
G01X32142Y203300D02*
X32174Y203307D01*
G01X32111Y203281D02*
X32142Y203300D01*
G01X32085Y203249D02*
X32111Y203281D01*
G01X30969Y202723D02*
X30936Y202717D01*
G01X30999Y202743D02*
X30969Y202723D01*
G01X31026Y202774D02*
X30999Y202743D01*
G01X37164Y210558D02*
X37131Y210551D01*
G01X37194Y210578D02*
X37164Y210558D01*
G01X37221Y210609D02*
X37194Y210578D01*
G01X36829Y211135D02*
X36861Y211142D01*
G01X36798Y211115D02*
X36829Y211135D01*
G01X36772Y211084D02*
X36798Y211115D01*
G01X32142Y208300D02*
X32174Y208307D01*
G01X32111Y208281D02*
X32142Y208300D01*
G01X32085Y208249D02*
X32111Y208281D01*
G01X30969Y207723D02*
X30936Y207717D01*
G01X30999Y207743D02*
X30969Y207723D01*
G01X31026Y207774D02*
X30999Y207743D01*
G01X23959Y198130D02*
G03X23582Y198051I-180J-79D01*
G01Y199390D02*
G03X23959Y199311I197J0D01*
G01Y194980D02*
G03X23582Y194901I-180J-79D01*
G01Y196240D02*
G03X23959Y196161I197J0D01*
G01Y201280D02*
G03X23582Y201201I-180J-79D01*
G01X29138Y201142D02*
G03X28941Y200945I0J-197D01*
G01Y197913D02*
G03X29138Y197717I197J1D01*
G01Y196142D02*
G03X28941Y195945I0J-197D01*
G01X23959Y207579D02*
G03X23582Y207500I-180J-79D01*
G01Y208839D02*
G03X23959Y208760I197J0D01*
G01Y204429D02*
G03X23582Y204350I-180J-79D01*
G01Y205689D02*
G03X23959Y205610I197J0D01*
G01X23582Y202539D02*
G03X23959Y202461I197J1D01*
G01Y210728D02*
G03X23582Y210650I-180J-79D01*
G01X29138Y211142D02*
G03X28941Y210945I0J-197D01*
G01Y207913D02*
G03X29138Y207717I197J1D01*
G01Y206142D02*
G03X28941Y205945I0J-197D01*
G01Y202913D02*
G03X29138Y202717I197J1D01*
G01X31331Y208249D02*
X31026Y207774D01*
G01X31780D02*
X32085Y208249D01*
G01X31331Y203249D02*
X31026Y202774D01*
G01X36467Y210609D02*
X36772Y211084D01*
G01X31780Y202774D02*
X32085Y203249D01*
G01X37526Y211084D02*
X37221Y210609D01*
G01X26602Y210728D02*
X26681Y210886D01*
G01X27363D02*
X27284Y210728D01*
G01X26602Y207579D02*
X26681Y207736D01*
G01X27363D02*
X27284Y207579D01*
G01X26602Y204429D02*
X26681Y204587D01*
G01X27363D02*
X27284Y204429D01*
G01X26602Y201280D02*
X26681Y201437D01*
G01X27363D02*
X27284Y201280D01*
G01X31331Y198249D02*
X31026Y197774D01*
G01X36467Y205609D02*
X36772Y206084D01*
G01X31780Y197774D02*
X32085Y198249D01*
G01X37526Y206084D02*
X37221Y205609D01*
G01X36467Y200609D02*
X36772Y201084D01*
G01X37526D02*
X37221Y200609D01*
G01X36467Y195609D02*
X36772Y196084D01*
G01X37526D02*
X37221Y195609D01*
G01X26602Y198130D02*
X26681Y198287D01*
G01X27363D02*
X27284Y198130D01*
G01X26602Y194980D02*
X26681Y195138D01*
G01X27363D02*
X27284Y194980D01*
G01X23582Y196768D02*
Y196240D01*
G01Y198051D02*
Y197532D01*
G01Y199918D02*
Y199390D01*
G01Y201201D02*
Y200682D01*
G01Y204350D02*
Y203831D01*
G01Y206217D02*
Y205689D01*
G01Y207500D02*
Y206981D01*
G01Y209367D02*
Y208839D01*
G01Y210650D02*
Y210130D01*
G01Y202539D02*
Y203067D01*
G01X24190Y210728D02*
Y211909D01*
G01Y207579D02*
Y208760D01*
G01Y204429D02*
Y205610D01*
G01Y201280D02*
Y202461D01*
G01Y198130D02*
Y199311D01*
G01Y194980D02*
Y196161D01*
G01X25043D02*
Y194980D01*
G01Y199311D02*
Y198130D01*
G01Y202461D02*
Y201280D01*
G01Y205610D02*
Y204429D01*
G01Y208760D02*
Y207579D01*
G01Y211909D02*
Y210728D01*
G01X25570Y196969D02*
Y194882D01*
G01Y199803D02*
Y197598D01*
G01Y203701D02*
Y201496D01*
G01Y205039D02*
Y204764D01*
G01Y205630D02*
Y205236D01*
G01Y206929D02*
Y206102D01*
G01X25724Y210728D02*
Y211909D01*
G01Y207579D02*
Y208760D01*
G01Y204429D02*
Y205610D01*
G01Y201280D02*
Y202461D01*
G01Y198130D02*
Y199311D01*
G01Y194980D02*
Y196161D01*
G01X27346Y210886D02*
Y211752D01*
G01Y207736D02*
Y208602D01*
G01Y204587D02*
Y205453D01*
G01Y201437D02*
Y202303D01*
G01Y198287D02*
Y199154D01*
G01Y195138D02*
Y196004D01*
G01X28028D02*
Y195138D01*
G01Y199154D02*
Y198287D01*
G01Y202303D02*
Y201437D01*
G01Y205453D02*
Y204587D01*
G01Y208602D02*
Y207736D01*
G01Y211752D02*
Y210886D01*
G01X28881D02*
Y211752D01*
G01Y207736D02*
Y208602D01*
G01Y204587D02*
Y205453D01*
G01Y201437D02*
Y202303D01*
G01Y198287D02*
Y199154D01*
G01Y195138D02*
Y196004D01*
G01X28941Y195945D02*
Y194961D01*
G01Y200945D02*
Y199961D01*
G01Y205945D02*
Y204961D01*
G01Y208898D02*
Y207913D01*
G01Y210945D02*
Y209961D01*
G01Y202913D02*
Y203898D01*
G01Y197913D02*
Y198898D01*
G01X29728Y197717D02*
Y196142D01*
G01Y202717D02*
Y201142D01*
G01Y211142D02*
Y212717D01*
G01Y206142D02*
Y207717D01*
G01X30482Y211142D02*
Y212717D01*
G01Y206142D02*
Y207717D01*
G01Y201142D02*
Y202717D01*
G01Y196142D02*
Y197717D01*
G01X31236Y207717D02*
Y206142D01*
G01Y212717D02*
Y211142D01*
G01Y201142D02*
Y202717D01*
G01Y196142D02*
Y197717D01*
G01X31637Y202303D02*
Y201437D01*
G01Y211752D02*
Y210886D01*
G01Y207736D02*
Y208602D01*
G01Y204587D02*
Y205453D01*
G01Y198287D02*
Y199154D01*
G01Y195138D02*
Y196004D01*
G01X37339Y197717D02*
Y196142D01*
G01Y202717D02*
Y201142D01*
G01Y207717D02*
Y206142D01*
G01Y212717D02*
Y211142D01*
G01X38093D02*
Y212717D01*
G01Y206142D02*
Y207717D01*
G01Y201142D02*
Y202717D01*
G01Y196142D02*
Y197717D01*
G01X38847Y211142D02*
Y212717D01*
G01Y206142D02*
Y207717D01*
G01Y201142D02*
Y202717D01*
G01Y196142D02*
Y197717D01*
G01X26681Y196004D02*
X26602Y196161D01*
G01X27284D02*
X27363Y196004D01*
G01X26681Y199154D02*
X26602Y199311D01*
G01X27284D02*
X27363Y199154D01*
G01X26681Y202303D02*
X26602Y202461D01*
G01X27284D02*
X27363Y202303D01*
G01X26681Y205453D02*
X26602Y205610D01*
G01X27284D02*
X27363Y205453D01*
G01X26681Y208602D02*
X26602Y208760D01*
G01X27284D02*
X27363Y208602D01*
G01X31026Y196084D02*
X31331Y195609D01*
G01X32085D02*
X31780Y196084D01*
G01X31026Y201084D02*
X31331Y200609D01*
G01X32085D02*
X31780Y201084D01*
G01X31026Y206084D02*
X31331Y205609D01*
G01X36772Y197774D02*
X36467Y198249D01*
G01X32085Y205609D02*
X31780Y206084D01*
G01X37221Y198249D02*
X37526Y197774D01*
G01X31026Y211084D02*
X31331Y210609D01*
G01X36772Y202774D02*
X36467Y203249D01*
G01X32085Y210609D02*
X31780Y211084D01*
G01X37221Y203249D02*
X37526Y202774D01*
G01X36772Y207774D02*
X36467Y208249D01*
G01X37221D02*
X37526Y207774D01*
G01X28941Y194961D02*
X25590D01*
G01X27284Y194980D02*
X23959D01*
G01X31637Y195138D02*
X26681D01*
G01X37131Y195551D02*
X31421D01*
G01X32085Y195609D02*
X31331D01*
G01X36467D02*
X37221D01*
G01X26681Y196004D02*
X31637D01*
G01X36772Y196084D02*
X37526D01*
G01X31026D02*
X31780D01*
G01X31690Y196142D02*
X29138D01*
G01X41603D02*
X36861D01*
G01X27284Y196161D02*
X23959D01*
G01X23385Y196768D02*
X23582D01*
G01Y197532D02*
X23385D01*
G01X31690Y197717D02*
X29138D01*
G01X41603D02*
X36861D01*
G01X37526Y197774D02*
X36772D01*
G01X31026D02*
X31780D01*
G01X27284Y198130D02*
X23959D01*
G01X32085Y198249D02*
X31331D01*
G01X36467D02*
X37221D01*
G01X31637Y198287D02*
X26681D01*
G01X31421Y198307D02*
X37131D01*
G01X25590Y198898D02*
X28941D01*
G01X26681Y199154D02*
X31637D01*
G01X27284Y199311D02*
X23959D01*
G01X23385Y199918D02*
X23582D01*
G01X28941Y199961D02*
X25590D01*
G01X37131Y200551D02*
X31421D01*
G01X32085Y200609D02*
X31331D01*
G01X36467D02*
X37221D01*
G01X23385Y200682D02*
X23582D01*
G01X36772Y201084D02*
X37526D01*
G01X31026D02*
X31780D01*
G01X31690Y201142D02*
X29138D01*
G01X41603D02*
X36861D01*
G01X27284Y201280D02*
X23959D01*
G01X31637Y201437D02*
X26681D01*
G01Y202303D02*
X31637D01*
G01X27284Y202461D02*
X23959D01*
G01X31690Y202717D02*
X29138D01*
G01X41603D02*
X36861D01*
G01X37526Y202774D02*
X36772D01*
G01X31026D02*
X31780D01*
G01X23582Y203067D02*
X23385D01*
G01X32085Y203249D02*
X31331D01*
G01X36467D02*
X37221D01*
G01X31421Y203307D02*
X37131D01*
G01X23582Y203831D02*
X23385D01*
G01X25590Y203898D02*
X28941D01*
G01X27284Y204429D02*
X23959D01*
G01X31637Y204587D02*
X26681D01*
G01X28941Y204961D02*
X25590D01*
G01X26681Y205453D02*
X31637D01*
G01X37131Y205551D02*
X31421D01*
G01X36467Y205609D02*
X37221D01*
G01X31331D02*
X32085D01*
G01X27284Y205610D02*
X23959D01*
G01X37526Y206084D02*
X36772D01*
G01X31026D02*
X31780D01*
G01X31690Y206142D02*
X29138D01*
G01X41603D02*
X36861D01*
G01X23385Y206217D02*
X23582D01*
G01Y206981D02*
X23385D01*
G01X27284Y207579D02*
X23959D01*
G01X31690Y207717D02*
X29138D01*
G01X41603D02*
X36861D01*
G01X31637Y207736D02*
X26681D01*
G01X37526Y207774D02*
X36772D01*
G01X31026D02*
X31780D01*
G01X32085Y208249D02*
X31331D01*
G01X36467D02*
X37221D01*
G01X31421Y208307D02*
X37131D01*
G01X26681Y208602D02*
X31637D01*
G01X27284Y208760D02*
X23959D01*
G01X28941Y208898D02*
X25590D01*
G01X23385Y209367D02*
X23582D01*
G01X28941Y209961D02*
X25590D01*
G01X23385Y210130D02*
X23582D01*
G01X37131Y210551D02*
X31421D01*
G01X36467Y210609D02*
X37221D01*
G01X31331D02*
X32085D01*
G01X27284Y210728D02*
X23959D01*
G01X31637Y210886D02*
X26681D01*
G01X37526Y211084D02*
X36772D01*
G01X31026D02*
X31780D01*
G01X31690Y211142D02*
X29138D01*
G01X41603D02*
X36861D01*
G01X133464Y200197D02*
X30314D01*
G01X31357Y213281D02*
X31331Y213249D01*
G01X31388Y213300D02*
X31357Y213281D01*
G01X31421Y213307D02*
X31388Y213300D01*
G01X31753Y212743D02*
X31780Y212774D01*
G01X31723Y212723D02*
X31753Y212743D01*
G01X31690Y212717D02*
X31723Y212723D01*
G01X37194Y213281D02*
X37221Y213249D01*
G01X37164Y213300D02*
X37194Y213281D01*
G01X37131Y213307D02*
X37164Y213300D01*
G01X36798Y212743D02*
X36772Y212774D01*
G01X36829Y212723D02*
X36798Y212743D01*
G01X36861Y212717D02*
X36829Y212723D01*
G01X37583D02*
X37615Y212717D01*
G01X37552Y212743D02*
X37583Y212723D01*
G01X37526Y212774D02*
X37552Y212743D01*
G01X36410Y213300D02*
X36377Y213307D01*
G01X36440Y213281D02*
X36410Y213300D01*
G01X36467Y213249D02*
X36440Y213281D01*
G01X32142Y213300D02*
X32174Y213307D01*
G01X32111Y213281D02*
X32142Y213300D01*
G01X32085Y213249D02*
X32111Y213281D01*
G01X30969Y212723D02*
X30936Y212717D01*
G01X30999Y212743D02*
X30969Y212723D01*
G01X31026Y212774D02*
X30999Y212743D01*
G01X23582Y211988D02*
G03X23959Y211909I197J0D01*
G01X28941Y212913D02*
G03X29138Y212717I197J1D01*
G01X28346Y214035D02*
G03X30314Y216004I0J1968D01*
G01X28772Y214120D02*
G03X29133Y215256I-1607J1136D01*
G01X28346Y214035D02*
G03X30314Y216004I0J1968D01*
G01X27165Y213287D02*
G03X28772Y214120I-1J1968D01*
G01X36810Y227579D02*
G03Y224823I0J-1378D01*
G01X38779D02*
G03Y227579I0J1378D01*
G01Y224429D02*
G03Y227972I0J1772D01*
G01X36810D02*
G03Y224429I0J-1771D01*
G01X38779Y223642D02*
G03Y228760I0J2559D01*
G01X36810D02*
G03Y223642I0J-2559D01*
G01X28346Y214035D02*
G03X30314Y216004I0J1968D01*
G01X28346Y214035D02*
G03X30314Y216004I0J1968D01*
G01X26377Y215236D02*
X29133Y217992D01*
G01X31331Y213249D02*
X31026Y212774D01*
G01X31780D02*
X32085Y213249D01*
G01X23385Y215236D02*
Y214035D01*
G01X23582Y212516D02*
Y211988D01*
G01X25590Y214035D02*
Y215236D01*
G01X26771Y219012D02*
Y230394D01*
G01X28941Y213898D02*
Y212913D01*
G01X29133Y217992D02*
Y230787D01*
G01X29921Y233543D02*
Y215236D01*
G01X30314Y232736D02*
Y216004D01*
G01Y232736D02*
Y216004D01*
G01X31889Y215236D02*
Y233543D01*
G01X32283Y230945D02*
Y221496D01*
G01X36810Y228760D02*
Y227579D01*
G01Y223642D02*
Y224823D01*
G01X38779D02*
Y223642D01*
G01Y228760D02*
Y227579D01*
G01X26681Y211752D02*
X26602Y211909D01*
G01X27284D02*
X27363Y211752D01*
G01X36772Y212774D02*
X36467Y213249D01*
G01X37221D02*
X37526Y212774D01*
G01X26681Y211752D02*
X31637D01*
G01X27284Y211909D02*
X23959D01*
G01X23385Y212516D02*
X23582D01*
G01X31690Y212717D02*
X29138D01*
G01X41603D02*
X36861D01*
G01X37526Y212774D02*
X36772D01*
G01X31026D02*
X31780D01*
G01X32085Y213249D02*
X31331D01*
G01X36467D02*
X37221D01*
G01X31421Y213307D02*
X37131D01*
G01X28941Y213898D02*
X25590D01*
G01X23228Y214035D02*
X28346D01*
G01X23228D02*
X28346D01*
G01X46062Y215236D02*
X30155D01*
G01X32283Y221496D02*
X41732D01*
G01X38779Y223642D02*
X36810D01*
G01Y224429D02*
X38779D01*
G01Y224823D02*
X36810D01*
G01Y227579D02*
X38779D01*
G01X30314Y232736D02*
Y216004D01*
G01X23228Y214035D02*
X28346D01*
G01X23228D02*
X28346D01*
G01Y214036D02*
X23228D01*
G01X28346D02*
G03X30315Y216004I0J1969D01*
G01Y232736D02*
Y216004D01*
G01X30314Y232736D02*
G03X28346Y234705I-1969J0D01*
G01X30314Y232736D02*
G03X28346Y234705I-1969J0D01*
G01X30314Y232736D02*
G03X28346Y234705I-1969J0D01*
G01X30314Y232736D02*
G03X28346Y234705I-1969J0D01*
G01X23464Y240039D02*
Y238858D01*
G01X24015Y234705D02*
Y244370D01*
G01Y233543D02*
Y234705D01*
G01X24054Y240039D02*
Y238858D01*
G01X29921Y233854D02*
Y233543D01*
G01Y244370D02*
Y233854D01*
G01X37209Y235236D02*
Y258071D01*
G01X29133Y230787D02*
X26377Y233543D01*
G01X38779Y227972D02*
X36810D01*
G01Y228760D02*
X38779D01*
G01X26771Y229606D02*
X29921D01*
G01X32283Y230945D02*
X41732D01*
G01X46062Y233543D02*
X30128D01*
G01X45870Y235236D02*
X37209D01*
G01X30315Y232736D02*
G03X28346Y234705I-1969J0D01*
G01X38787Y265945D02*
G03Y258071I1J-3937D01*
G01X25591Y309193D02*
G03Y323169I0J6988D01*
G01X38787Y371299D02*
G03Y363425I1J-3937D01*
G01X237000Y371299D02*
X38787D01*
G01X68995Y-87638D02*
G03X55019I-6988J0D01*
G03X68995I6988J0D01*
G01D02*
G03X55019I-6988J0D01*
G03X68995I6988J0D01*
G01X77755D02*
G03X46259I-15748J0D01*
G03X77755I15748J0D01*
G01X68995D02*
G03X55019I-6988J0D01*
G03X68995I6988J0D01*
G01X77755D02*
G03X46259I-15748J0D01*
G03X77755I15748J0D01*
G01X62007Y-80649D02*
G03Y-94626I0J-6988D01*
G01X46062Y65315D02*
G03X47243Y66496I0J1181D01*
G01X41732Y77382D02*
Y67933D01*
G01X42519Y82835D02*
Y78898D01*
G01X46456D02*
Y82835D01*
G01X47243Y82441D02*
Y66496D01*
G01X41014Y72658D02*
X40354D01*
G01X42519Y78898D02*
X46456D01*
G01X47243Y82441D02*
G03X46062Y83622I-1181J0D01*
G01X41069Y87244D02*
X41088Y87163D01*
G01X40970Y87143D02*
X40950Y87204D01*
G01X41128Y86620D02*
X41069Y86520D01*
G01X40616Y87204D02*
X40596Y87163D01*
G01X40419Y86761D02*
X40458Y86841D01*
G01X40478Y87163D02*
X40498Y87224D01*
G01X40950Y87043D02*
X40970Y87103D01*
G01X41009Y86641D02*
X41029Y86701D01*
G01X41088Y87083D02*
X41069Y87002D01*
G01X41147Y86701D02*
X41128Y86620D01*
G01X40025Y87384D02*
Y86439D01*
G01X40143D02*
Y87224D01*
G01X40261Y87083D02*
Y87244D01*
G01X40419Y86661D02*
Y86761D01*
G01X40537Y86741D02*
Y86681D01*
G01X40970Y87103D02*
Y87143D01*
G01X41088Y87163D02*
Y87083D01*
G01X41603Y91142D02*
Y92717D01*
G01Y86142D02*
Y87717D01*
G01X40458Y86580D02*
X40419Y86661D01*
G01X40537Y86681D02*
X40576Y86620D01*
G01X40655Y87244D02*
X40616Y87204D01*
G01X40458Y86841D02*
X40537Y86922D01*
G01X40498Y87224D02*
X40557Y87304D01*
G01X40576Y86801D02*
X40537Y86741D01*
G01X40143Y87224D02*
X40261Y87083D01*
G01Y87244D02*
X40143Y87384D01*
G01X40537Y86500D02*
X40458Y86580D01*
G01X40990Y87324D02*
X41069Y87244D01*
G01X40557Y87304D02*
X40635Y87364D01*
G01X41069Y87002D02*
X40990Y86922D01*
G01X40950Y86580D02*
X41009Y86641D01*
G01X40537Y86922D02*
X40616Y86962D01*
G01X40990Y86922D02*
X40911Y86882D01*
G01X41069Y86520D02*
X40970Y86459D01*
G01X40635Y86841D02*
X40576Y86801D01*
G01X40891Y87002D02*
X40950Y87043D01*
G01X40576Y86620D02*
X40635Y86580D01*
G01X40950Y87204D02*
X40891Y87244D01*
G01X40714Y87264D02*
X40655Y87244D01*
G01X40832Y86982D02*
X40891Y87002D01*
G01X40616Y86459D02*
X40537Y86500D01*
G01X40911Y87364D02*
X40990Y87324D01*
G01X40891Y87244D02*
X40832Y87264D01*
G01X40635Y86580D02*
X40714Y86560D01*
G01X40832Y87384D02*
X40911Y87364D01*
G01X40714Y86439D02*
X40616Y86459D01*
G01X46456Y82835D02*
X42519D01*
G01X40872Y86439D02*
X40714D01*
G01X40025D02*
X40143D01*
G01X40714Y86560D02*
X40872D01*
G01X41029Y86701D02*
X41147D01*
G01X40832Y86862D02*
X40714D01*
G01Y86982D02*
X40832D01*
G01X40596Y87163D02*
X40478D01*
G01X40832Y87264D02*
X40714D01*
G01X40143Y87384D02*
X40025D01*
G01X40734D02*
X40832D01*
G01X40970Y86459D02*
X40872Y86439D01*
G01X40616Y86962D02*
X40714Y86982D01*
G01X40635Y87364D02*
X40734Y87384D01*
G01X40872Y86560D02*
X40950Y86580D01*
G01X40911Y86882D02*
X40832Y86862D01*
G01X40714D02*
X40635Y86841D01*
G01X41603Y111142D02*
Y112717D01*
G01Y106142D02*
Y107717D01*
G01Y101142D02*
Y102717D01*
G01Y96142D02*
Y97717D01*
G01X40767Y121914D02*
Y121402D01*
G01X40831D02*
Y121827D01*
G01X40895Y121750D02*
Y121838D01*
G01X40980Y121914D02*
Y121848D01*
G01Y121467D02*
Y121402D01*
G01X41022Y121707D02*
Y121642D01*
G01X41300D02*
Y121467D01*
G01Y121848D02*
Y121707D01*
G01X41364Y121402D02*
Y121914D01*
G01X41603Y116142D02*
Y117717D01*
G01X41689Y122087D02*
Y121220D01*
G01Y125236D02*
Y124370D01*
G01Y128386D02*
Y127520D01*
G01X40831Y121827D02*
X40895Y121750D01*
G01Y121838D02*
X40831Y121914D01*
G01X40980Y121402D02*
X41364D01*
G01X40767D02*
X40831D01*
G01X41300Y121467D02*
X40980D01*
G01X41022Y121642D02*
X41300D01*
G01Y121707D02*
X41022D01*
G01X40980Y121848D02*
X41300D01*
G01X41364Y121914D02*
X40980D01*
G01X40831D02*
X40767D01*
G01X40399Y142154D02*
X40438Y142195D01*
G01X40340Y142235D02*
X40281Y142154D01*
G01D02*
X40261Y142094D01*
G01X40379D02*
X40399Y142154D01*
G01X40419Y142295D02*
X40340Y142235D01*
G01X39867Y142315D02*
Y141370D01*
G01X39985D02*
Y142154D01*
G01X40104Y142014D02*
Y142174D01*
G01X40261Y142094D02*
Y142014D01*
G01X40379Y142034D02*
Y142094D01*
G01X40871Y142215D02*
Y141913D01*
G01Y141793D02*
Y141370D01*
G01X40989D02*
Y142315D01*
G01X41603Y141142D02*
Y142717D01*
G01X41689Y131535D02*
Y130669D01*
G01Y134685D02*
Y133819D01*
G01Y137835D02*
Y136969D01*
G01X40261Y142014D02*
X40281Y141953D01*
G01X40399Y141974D02*
X40379Y142034D01*
G01X40438Y142195D02*
X40497Y142215D01*
G01X40281Y141953D02*
X40340Y141873D01*
G01X39985Y142154D02*
X40104Y142014D01*
G01Y142174D02*
X39985Y142315D01*
G01X40438Y141933D02*
X40399Y141974D01*
G01X40340Y141873D02*
X40419Y141813D01*
G01X40497Y141913D02*
X40438Y141933D01*
G01X40419Y141813D02*
X40517Y141793D01*
G01X39867Y141370D02*
X39985D01*
G01X40871D02*
X40989D01*
G01X40517Y141793D02*
X40871D01*
G01Y141913D02*
X40497D01*
G01Y142215D02*
X40871D01*
G01X39985Y142315D02*
X39867D01*
G01X40989D02*
X40517D01*
G01D02*
X40419Y142295D01*
G01X41603Y161142D02*
Y162717D01*
G01Y156142D02*
Y157717D01*
G01Y151142D02*
Y152717D01*
G01Y146142D02*
Y147717D01*
G01Y176142D02*
Y177717D01*
G01Y171142D02*
Y172717D01*
G01Y166142D02*
Y167717D01*
G01Y191142D02*
Y192717D01*
G01Y186142D02*
Y187717D01*
G01Y181142D02*
Y182717D01*
G01Y211142D02*
Y212717D01*
G01Y206142D02*
Y207717D01*
G01Y201142D02*
Y202717D01*
G01Y196142D02*
Y197717D01*
G01X46062Y215236D02*
G03X47243Y216417I0J1181D01*
G01X47114Y235236D02*
G03X62007Y224606I14893J5118D01*
G01X41732Y221496D02*
Y230945D01*
G01X42519Y222333D02*
Y218396D01*
G01X46456D02*
Y222333D01*
G01X47243Y216417D02*
Y232362D01*
G01X46456Y218396D02*
X42519D01*
G01X46456Y222333D02*
X42519D01*
G01X47243Y232362D02*
G03X46062Y233543I-1181J0D01*
G01X55118Y363425D02*
Y265945D01*
G01X62007Y-94626D02*
G03Y-80649I0J6988D01*
G01X61220Y-7874D02*
Y984D01*
G01X341535Y-7874D02*
X61220D01*
G01X63108Y13228D02*
G03X62911Y13032I0J-197D01*
G01Y12638D02*
G03X63108Y12441I197J0D01*
G01Y11260D02*
G03X62911Y11063I0J-197D01*
G01Y10669D02*
G03X63108Y10472I197J0D01*
G01Y9291D02*
G03X62911Y9095I0J-197D01*
G01Y8701D02*
G03X63108Y8504I197J0D01*
G01X69409Y7244D02*
G03X70196Y6457I787J0D01*
G01X61417Y2795D02*
G03X62204Y2008I787J0D01*
G01X71745Y12309D02*
X71812Y12178D01*
G01X71544Y11128D02*
X71477Y11325D01*
G01X71745D02*
X71812Y11128D01*
G01X71544Y12178D02*
X71477Y12375D01*
G01X71678Y10997D02*
X71544Y11128D01*
G01X71812D02*
X71946Y10997D01*
G01X71745Y11982D02*
X71544Y12178D01*
G01X71812D02*
X71879Y12113D01*
G01X61417Y6929D02*
Y2795D01*
G01X62911Y12638D02*
Y13032D01*
G01Y10669D02*
Y11063D01*
G01Y8701D02*
Y9095D01*
G01X64369Y5158D02*
Y85472D01*
G01X66732Y5158D02*
Y85472D01*
G01X69409Y26890D02*
Y7244D01*
G01X70472Y8569D02*
Y9095D01*
G01X71477Y12375D02*
Y12638D01*
G01Y11325D02*
Y11588D01*
G01Y10669D02*
Y10997D01*
G01X71879Y12113D02*
X72013Y12047D01*
G01X73621Y7520D02*
X70472Y8569D01*
G01X70740Y8832D02*
X72549Y8241D01*
G01X71745Y11457D02*
Y11325D01*
G01Y12506D02*
Y12309D01*
G01X72549Y8241D02*
Y9422D01*
G01X93503Y2008D02*
X62204D01*
G01X61417Y5158D02*
X66732D01*
G01X61417Y6339D02*
X64369D01*
G01X70196Y6457D02*
X79054D01*
G01X71477Y12638D02*
X71544Y12835D01*
G01X71477Y11588D02*
X71544Y11785D01*
G01X64369Y6929D02*
X61417D01*
G01X64369Y8504D02*
X63108D01*
G01X64369Y9291D02*
X63108D01*
G01X64369Y10472D02*
X63108D01*
G01X73621Y10669D02*
X71477D01*
G01X71946Y10997D02*
X73621D01*
G01X71477D02*
X71678D01*
G01X64369Y11260D02*
X63108D01*
G01X73621Y11719D02*
X72013D01*
G01Y12047D02*
X73621D01*
G01X64369Y12441D02*
X63108D01*
G01X73621Y12769D02*
X72013D01*
G01Y13097D02*
X73621D01*
G01X64369Y13228D02*
X63108D01*
G01X71812Y12638D02*
X71745Y12506D01*
G01X71812Y11588D02*
X71745Y11457D01*
G01X71544Y12835D02*
X71678Y12966D01*
G01X71879Y12703D02*
X71812Y12638D01*
G01X71544Y11785D02*
X71745Y11982D01*
G01X71879Y11654D02*
X71812Y11588D01*
G01X72013Y12769D02*
X71879Y12703D01*
G01X72013Y11719D02*
X71879Y11654D01*
G01X70472Y9095D02*
X73621Y10144D01*
G01X71678Y12966D02*
X72013Y13097D01*
G01X72549Y9422D02*
X70740Y8832D01*
G01X63108Y28976D02*
G03X62911Y28780I0J-197D01*
G01Y28386D02*
G03X63108Y28189I197J0D01*
G01Y27008D02*
G03X62911Y26811I0J-197D01*
G01Y26417D02*
G03X63108Y26220I197J0D01*
G01Y25039D02*
G03X62911Y24843I0J-197D01*
G01Y24449D02*
G03X63108Y24252I197J0D01*
G01Y23071D02*
G03X62911Y22874I0J-197D01*
G01Y22480D02*
G03X63108Y22283I197J0D01*
G01Y21102D02*
G03X62911Y20906I0J-197D01*
G01Y20512D02*
G03X63108Y20315I197J0D01*
G01Y19134D02*
G03X62911Y18937I0J-197D01*
G01Y18543D02*
G03X63108Y18346I197J0D01*
G01Y17165D02*
G03X62911Y16969I0J-197D01*
G01Y16575D02*
G03X63108Y16378I197J0D01*
G01Y15197D02*
G03X62911Y15000I0J-197D01*
G01Y14606D02*
G03X63108Y14409I197J0D01*
G01X70196Y27677D02*
G03X69409Y26890I0J-787D01*
G01X71611Y14147D02*
X71544Y14278D01*
G01X71879D02*
X72013Y14081D01*
G01X71544Y19331D02*
X71477Y19724D01*
G01X71544Y14278D02*
X71477Y14541D01*
G01X71812D02*
X71879Y14278D01*
G01X71544Y16903D02*
X71477Y17165D01*
G01X71745D02*
X71812Y16903D01*
G01X71745Y19659D02*
X71812Y19396D01*
G01X71544Y21890D02*
X71477Y22152D01*
G01X71745D02*
X71812Y21890D01*
G01X71544Y24120D02*
X71477Y24383D01*
G01X71745Y24514D02*
X71812Y24252D01*
G01X71611Y19134D02*
X71544Y19331D01*
G01X71812Y19396D02*
X71879Y19265D01*
G01X71611Y23989D02*
X71544Y24120D01*
G01X71678Y16706D02*
X71544Y16903D01*
G01X71812D02*
X71946Y16706D01*
G01X71745Y18937D02*
X71611Y19134D01*
G01X71678Y21693D02*
X71544Y21890D01*
G01X71812D02*
X71946Y21693D01*
G01X71745Y14016D02*
X71611Y14147D01*
G01X71812Y16575D02*
X71678Y16706D01*
G01X71946D02*
X72080Y16575D01*
G01X71879Y18806D02*
X71745Y18937D01*
G01X71879Y19265D02*
X72080Y19068D01*
G01X71812Y21561D02*
X71678Y21693D01*
G01X71946D02*
X72080Y21561D01*
G01X71745Y23858D02*
X71611Y23989D01*
G01X71812Y24252D02*
X71946Y24120D01*
G01X72013Y14081D02*
X72214Y13950D01*
G01X62911Y28386D02*
Y28780D01*
G01Y26417D02*
Y26811D01*
G01Y24449D02*
Y24843D01*
G01Y22480D02*
Y22874D01*
G01Y20512D02*
Y20906D01*
G01Y18543D02*
Y18937D01*
G01Y16575D02*
Y16969D01*
G01Y14606D02*
Y15000D01*
G01X70472Y26220D02*
Y26548D01*
G01Y16246D02*
Y16575D01*
G01X71477Y24383D02*
Y24908D01*
G01Y22152D02*
Y22415D01*
G01Y21233D02*
Y21561D01*
G01Y17165D02*
Y17428D01*
G01Y14541D02*
Y14934D01*
G01Y13622D02*
Y13950D01*
G01X71946Y23727D02*
X71745Y23858D01*
G01X71946Y24120D02*
X72147Y23989D01*
G01X71879Y13950D02*
X71745Y14016D01*
G01X72147Y18674D02*
X71879Y18806D01*
G01X72080Y19068D02*
X72214Y19002D01*
G01X71477Y24908D02*
X71544Y25170D01*
G01X71812Y25039D02*
X71745Y24777D01*
G01X71812Y22415D02*
X71745Y22152D01*
G01X71477Y19724D02*
X71544Y20118D01*
G01X71812Y20052D02*
X71745Y19659D01*
G01Y24777D02*
Y24514D01*
G01X71812Y14934D02*
Y14541D01*
G01X72281Y19002D02*
Y20380D01*
G01X72549Y20709D02*
Y18937D01*
G01X72147Y23661D02*
X71946Y23727D01*
G01X72415Y23596D02*
X72147Y23661D01*
G01Y23989D02*
X72415Y23924D01*
G01X72549Y18609D02*
X72147Y18674D01*
G01X71477Y22415D02*
X71544Y22611D01*
G01X71477Y17428D02*
X71544Y17624D01*
G01X71812Y17428D02*
X71745Y17165D01*
G01X71477Y14934D02*
X71544Y15197D01*
G01X74693Y13622D02*
X71477D01*
G01X72214Y13950D02*
X72884D01*
G01X71477D02*
X71879D01*
G01X64369Y14409D02*
X63108D01*
G01X64369Y15197D02*
X63108D01*
G01X72750Y15394D02*
X72348D01*
G01X72281Y15722D02*
X72817D01*
G01X73621Y16246D02*
X70472D01*
G01X64369Y16378D02*
X63108D01*
G01X72080Y16575D02*
X73621D01*
G01X70472D02*
X71812D01*
G01X64369Y17165D02*
X63108D01*
G01X73621Y17756D02*
X72281D01*
G01Y18084D02*
X73621D01*
G01X64369Y18346D02*
X63108D01*
G01X72549Y18937D02*
X72683D01*
G01X72214Y19002D02*
X72281D01*
G01X64369Y19134D02*
X63108D01*
G01X64369Y20315D02*
X63108D01*
G01X72281Y20380D02*
X72147D01*
G01X72281Y20709D02*
X72549D01*
G01X64369Y21102D02*
X63108D01*
G01X73621Y21233D02*
X71477D01*
G01X72080Y21561D02*
X73621D01*
G01X71477D02*
X71812D01*
G01X64369Y22283D02*
X63108D01*
G01X73621Y22743D02*
X72348D01*
G01X64369Y23071D02*
X63108D01*
G01X72348D02*
X73621D01*
G01X72683Y23596D02*
X72415D01*
G01X71544Y22611D02*
X71678Y22808D01*
G01X71946Y20249D02*
X71812Y20052D01*
G01X71544Y20118D02*
X71745Y20446D01*
G01X71544Y25170D02*
X71611Y25302D01*
G01X71879Y22546D02*
X71812Y22415D01*
G01X71879Y17559D02*
X71812Y17428D01*
G01X71946Y15197D02*
X71812Y14934D01*
G01X72415Y23924D02*
X72683D01*
G01X64369Y24252D02*
X63108D01*
G01X64369Y25039D02*
X63108D01*
G01X72683Y25367D02*
X72415D01*
G01Y25695D02*
X72683D01*
G01X64369Y26220D02*
X63108D01*
G01X73621D02*
X70472D01*
G01Y26548D02*
X73621D01*
G01X64369Y27008D02*
X63108D01*
G01X79054Y27677D02*
X70196D01*
G01X64369Y28189D02*
X63108D01*
G01X64369Y28976D02*
X63108D01*
G01X72951Y18674D02*
X72549Y18609D01*
G01X71946Y18018D02*
X72281Y18084D01*
G01X71544Y17624D02*
X71678Y17821D01*
G01X71544Y15197D02*
X71678Y15394D01*
G01X72348Y22743D02*
X72013Y22677D01*
G01Y23005D02*
X72348Y23071D01*
G01X72013Y15656D02*
X72281Y15722D01*
G01Y17756D02*
X72013Y17690D01*
G01Y20643D02*
X72281Y20709D01*
G01X72415Y25367D02*
X72147Y25302D01*
G01Y25630D02*
X72415Y25695D01*
G01X71611Y25302D02*
X71745Y25433D01*
G01X71946Y25170D02*
X71812Y25039D01*
G01X71678Y22808D02*
X71812Y22939D01*
G01X72013Y22677D02*
X71879Y22546D01*
G01X71678Y17821D02*
X71812Y17953D01*
G01X72013Y17690D02*
X71879Y17559D01*
G01X71678Y15394D02*
X71879Y15591D01*
G01X71745Y25433D02*
X71946Y25564D01*
G01X72147Y25302D02*
X71946Y25170D01*
G01X72147Y20380D02*
X71946Y20249D01*
G01X72147Y15328D02*
X71946Y15197D01*
G01X71745Y20446D02*
X72013Y20643D01*
G01X71812Y17953D02*
X71946Y18018D01*
G01X71879Y15591D02*
X72013Y15656D01*
G01X71946Y25564D02*
X72147Y25630D01*
G01X71812Y22939D02*
X72013Y23005D01*
G01X72348Y15394D02*
X72147Y15328D01*
G01X63108Y36850D02*
G03X62911Y36654I0J-197D01*
G01Y36260D02*
G03X63108Y36063I197J0D01*
G01Y34882D02*
G03X62911Y34685I0J-197D01*
G01Y34291D02*
G03X63108Y34095I197J1D01*
G01Y32913D02*
G03X62911Y32717I0J-197D01*
G01Y32323D02*
G03X63108Y32126I197J0D01*
G01Y30945D02*
G03X62911Y30748I0J-197D01*
G01Y30354D02*
G03X63108Y30158I197J1D01*
G01X62911Y40197D02*
G03X63108Y40000I197J0D01*
G01Y38819D02*
G03X62911Y38622I0J-197D01*
G01Y38228D02*
G03X63108Y38032I197J1D01*
G01X62911Y46102D02*
G03X63108Y45906I197J1D01*
G01Y44724D02*
G03X62911Y44528I0J-197D01*
G01Y44134D02*
G03X63108Y43937I197J0D01*
G01Y42756D02*
G03X62911Y42559I0J-197D01*
G01Y42165D02*
G03X63108Y41969I197J1D01*
G01Y40787D02*
G03X62911Y40591I0J-197D01*
G01Y46102D02*
Y46496D01*
G01Y44134D02*
Y44528D01*
G01Y42165D02*
Y42559D01*
G01Y40197D02*
Y40591D01*
G01Y36260D02*
Y36654D01*
G01Y38228D02*
Y38622D01*
G01Y34291D02*
Y34685D01*
G01Y32323D02*
Y32717D01*
G01Y30354D02*
Y30748D01*
G01X64369Y30158D02*
X63108D01*
G01X64369Y30945D02*
X63108D01*
G01X64369Y32126D02*
X63108D01*
G01X64369Y32913D02*
X63108D01*
G01X64369Y34095D02*
X63108D01*
G01X64369Y34882D02*
X63108D01*
G01X64369Y36063D02*
X63108D01*
G01X64369Y36850D02*
X63108D01*
G01X64369Y38032D02*
X63108D01*
G01X64369Y38819D02*
X63108D01*
G01X64369Y40000D02*
X63108D01*
G01X64369Y40787D02*
X63108D01*
G01X64369Y41969D02*
X63108D01*
G01X64369Y42756D02*
X63108D01*
G01X64369Y43937D02*
X63108D01*
G01X64369Y44724D02*
X63108D01*
G01X64369Y45906D02*
X63108D01*
G01Y62441D02*
G03X62911Y62244I0J-197D01*
G01Y61850D02*
G03X63108Y61654I197J1D01*
G01Y60472D02*
G03X62911Y60276I0J-197D01*
G01Y59882D02*
G03X63108Y59685I197J0D01*
G01Y58504D02*
G03X62911Y58307I0J-197D01*
G01Y57913D02*
G03X63108Y57717I197J1D01*
G01Y56535D02*
G03X62911Y56339I0J-197D01*
G01Y55945D02*
G03X63108Y55748I197J0D01*
G01Y54567D02*
G03X62911Y54370I0J-197D01*
G01Y53976D02*
G03X63108Y53780I197J1D01*
G01Y52598D02*
G03X62911Y52402I0J-197D01*
G01Y52008D02*
G03X63108Y51811I197J0D01*
G01Y50630D02*
G03X62911Y50433I0J-197D01*
G01Y50039D02*
G03X63108Y49843I197J1D01*
G01Y48661D02*
G03X62911Y48465I0J-197D01*
G01Y48071D02*
G03X63108Y47874I197J0D01*
G01Y46693D02*
G03X62911Y46496I0J-197D01*
G01Y61850D02*
Y62244D01*
G01Y59882D02*
Y60276D01*
G01Y57913D02*
Y58307D01*
G01Y55945D02*
Y56339D01*
G01Y53976D02*
Y54370D01*
G01Y52008D02*
Y52402D01*
G01Y50039D02*
Y50433D01*
G01Y48071D02*
Y48465D01*
G01X64369Y46693D02*
X63108D01*
G01X64369Y47874D02*
X63108D01*
G01X64369Y48661D02*
X63108D01*
G01X64369Y49843D02*
X63108D01*
G01X64369Y50630D02*
X63108D01*
G01X64369Y51811D02*
X63108D01*
G01X64369Y52598D02*
X63108D01*
G01X64369Y53780D02*
X63108D01*
G01X64369Y54567D02*
X63108D01*
G01X64369Y55748D02*
X63108D01*
G01X64369Y56535D02*
X63108D01*
G01X64369Y57717D02*
X63108D01*
G01X64369Y58504D02*
X63108D01*
G01X64369Y59685D02*
X63108D01*
G01X64369Y60472D02*
X63108D01*
G01X64369Y61654D02*
X63108D01*
G01X64369Y62441D02*
X63108D01*
G01Y78189D02*
G03X62911Y77992I0J-197D01*
G01Y77598D02*
G03X63108Y77402I197J1D01*
G01Y76220D02*
G03X62911Y76024I0J-197D01*
G01Y75630D02*
G03X63108Y75433I197J0D01*
G01Y74252D02*
G03X62911Y74055I0J-197D01*
G01Y73661D02*
G03X63108Y73465I197J1D01*
G01Y64409D02*
G03X62911Y64213I0J-197D01*
G01Y63819D02*
G03X63108Y63622I197J0D01*
G01X62911Y77598D02*
Y77992D01*
G01Y75630D02*
Y76024D01*
G01Y73661D02*
Y74055D01*
G01Y63819D02*
Y64213D01*
G01X64369Y63622D02*
X63108D01*
G01X64369Y64409D02*
X63108D01*
G01X64369Y73465D02*
X63108D01*
G01X64369Y74252D02*
X63108D01*
G01X64369Y75433D02*
X63108D01*
G01X64369Y76220D02*
X63108D01*
G01X64369Y77402D02*
X63108D01*
G01X64369Y78189D02*
X63108D01*
G01Y82126D02*
G03X62911Y81929I0J-197D01*
G01Y81535D02*
G03X63108Y81339I197J1D01*
G01Y80158D02*
G03X62911Y79961I0J-197D01*
G01Y79567D02*
G03X63108Y79370I197J0D01*
G01X62204Y88622D02*
G03X61417Y87835I0J-787D01*
G01D02*
Y83701D01*
G01X62911Y81535D02*
Y81929D01*
G01Y79567D02*
Y79961D01*
G01X64369Y79370D02*
X63108D01*
G01X64369Y80158D02*
X63108D01*
G01X64369Y81339D02*
X63108D01*
G01X64369Y82126D02*
X63108D01*
G01X64369Y83701D02*
X61417D01*
G01X64369Y84291D02*
X61417D01*
G01X66732Y85472D02*
X61417D01*
G01X93503Y88622D02*
X62204D01*
G01X61417Y111457D02*
G03X62204Y110669I787J-1D01*
G01X61417Y115591D02*
Y111457D01*
G01X93503Y110669D02*
X62204D01*
G01X62911Y123268D02*
G03X63108Y123071I197J0D01*
G01Y121890D02*
G03X62911Y121693I0J-197D01*
G01Y121299D02*
G03X63108Y121102I197J0D01*
G01Y119921D02*
G03X62911Y119724I0J-197D01*
G01Y119331D02*
G03X63108Y119134I197J0D01*
G01Y117953D02*
G03X62911Y117756I0J-197D01*
G01Y117362D02*
G03X63108Y117165I197J0D01*
G01Y127795D02*
G03X62911Y127598I0J-197D01*
G01Y127205D02*
G03X63108Y127008I197J0D01*
G01Y125827D02*
G03X62911Y125630I0J-197D01*
G01Y125236D02*
G03X63108Y125039I197J0D01*
G01Y123858D02*
G03X62911Y123661I0J-197D01*
G01X69409Y115906D02*
G03X70196Y115118I787J-1D01*
G01X71678Y126483D02*
X71812Y126614D01*
G01X72013Y126352D02*
X71879Y126220D01*
G01X71678Y124055D02*
X71879Y124252D01*
G01X71544Y121496D02*
X71678Y121627D01*
G01X71879Y121365D02*
X71812Y121299D01*
G01X71544Y120446D02*
X71745Y120643D01*
G01X71879Y120315D02*
X71812Y120249D01*
G01X71946Y128911D02*
X71812Y128714D01*
G01X71544Y126286D02*
X71678Y126483D01*
G01X71544Y123858D02*
X71678Y124055D01*
G01X71879Y126220D02*
X71812Y126089D01*
G01X71946Y123858D02*
X71812Y123596D01*
G01Y121299D02*
X71745Y121168D01*
G01X71812Y120249D02*
X71745Y120118D01*
G01X71477Y126089D02*
X71544Y126286D01*
G01X71477Y121299D02*
X71544Y121496D01*
G01X71477Y120249D02*
X71544Y120446D01*
G01X71812Y126089D02*
X71745Y125827D01*
G01X71477Y123596D02*
X71544Y123858D01*
G01X71477Y128386D02*
X71544Y128780D01*
G01X71812Y128714D02*
X71745Y128320D01*
G01X62911Y127205D02*
Y127598D01*
G01Y125236D02*
Y125630D01*
G01Y123268D02*
Y123661D01*
G01Y121299D02*
Y121693D01*
G01Y119331D02*
Y119724D01*
G01Y117362D02*
Y117756D01*
G01X64369Y113819D02*
Y194134D01*
G01X66732Y113819D02*
Y194134D01*
G01X69409Y135551D02*
Y115906D01*
G01X70472Y124908D02*
Y125236D01*
G01Y117231D02*
Y117756D01*
G01X71477Y125827D02*
Y126089D01*
G01Y123202D02*
Y123596D01*
G01Y122283D02*
Y122611D01*
G01Y121037D02*
Y121299D01*
G01Y119987D02*
Y120249D01*
G01Y119331D02*
Y119659D01*
G01X71544Y127992D02*
X71477Y128386D01*
G01X71544Y122939D02*
X71477Y123202D01*
G01X71812D02*
X71879Y122939D01*
G01X71544Y125564D02*
X71477Y125827D01*
G01X71745D02*
X71812Y125564D01*
G01X71745Y128320D02*
X71812Y128058D01*
G01Y126614D02*
X71946Y126680D01*
G01X71879Y124252D02*
X72013Y124317D01*
G01X72147Y123989D02*
X71946Y123858D01*
G01X71745Y120118D02*
Y119987D01*
G01Y121168D02*
Y120971D01*
G01X71812Y123596D02*
Y123202D01*
G01X72281Y127664D02*
Y129042D01*
G01X72549Y129370D02*
Y127598D01*
G01Y116903D02*
Y118084D01*
G01X71544Y119790D02*
X71477Y119987D01*
G01X71745D02*
X71812Y119790D01*
G01X71544Y120840D02*
X71477Y121037D01*
G01X71611Y127795D02*
X71544Y127992D01*
G01X71745Y120971D02*
X71812Y120840D01*
G01X71611Y122808D02*
X71544Y122939D01*
G01X72348Y124055D02*
X72147Y123989D01*
G01X72549Y118084D02*
X70740Y117493D01*
G01X70472Y117756D02*
X73621Y118806D01*
G01X71678Y121627D02*
X72013Y121758D01*
G01Y121430D02*
X71879Y121365D01*
G01X72013Y120380D02*
X71879Y120315D01*
G01X71812Y128058D02*
X71879Y127926D01*
G01Y122939D02*
X72013Y122743D01*
G01X71678Y125367D02*
X71544Y125564D01*
G01X71812D02*
X71946Y125367D01*
G01X71745Y127598D02*
X71611Y127795D01*
G01X71678Y119659D02*
X71544Y119790D01*
G01X71812D02*
X71946Y119659D01*
G01X71745Y120643D02*
X71544Y120840D01*
G01X71812D02*
X71879Y120774D01*
G01X71745Y122677D02*
X71611Y122808D01*
G01X71812Y125236D02*
X71678Y125367D01*
G01X71946D02*
X72080Y125236D01*
G01X71879Y127467D02*
X71745Y127598D01*
G01X71879Y127926D02*
X72080Y127730D01*
G01X72013Y122743D02*
X72214Y122611D01*
G01X71879Y120774D02*
X72013Y120709D01*
G01X71879Y122611D02*
X71745Y122677D01*
G01X72147Y127336D02*
X71879Y127467D01*
G01X72080Y127730D02*
X72214Y127664D01*
G01X73621Y116181D02*
X70472Y117231D01*
G01X70740Y117493D02*
X72549Y116903D01*
G01Y127270D02*
X72147Y127336D01*
G01X61417Y113819D02*
X66732D01*
G01X61417Y115000D02*
X64369D01*
G01X70196Y115118D02*
X79054D01*
G01X64369Y115591D02*
X61417D01*
G01X64369Y117165D02*
X63108D01*
G01X64369Y117953D02*
X63108D01*
G01X64369Y119134D02*
X63108D01*
G01X73621Y119331D02*
X71477D01*
G01X71946Y119659D02*
X73621D01*
G01X71477D02*
X71678D01*
G01X64369Y119921D02*
X63108D01*
G01X73621Y120380D02*
X72013D01*
G01Y120709D02*
X73621D01*
G01X64369Y121102D02*
X63108D01*
G01X73621Y121430D02*
X72013D01*
G01Y121758D02*
X73621D01*
G01X64369Y121890D02*
X63108D01*
G01X74693Y122283D02*
X71477D01*
G01X72214Y122611D02*
X72884D01*
G01X71477D02*
X71879D01*
G01X64369Y123071D02*
X63108D01*
G01X64369Y123858D02*
X63108D01*
G01X72750Y124055D02*
X72348D01*
G01X72281Y124383D02*
X72817D01*
G01X73621Y124908D02*
X70472D01*
G01X64369Y125039D02*
X63108D01*
G01X72080Y125236D02*
X73621D01*
G01X70472D02*
X71812D01*
G01X64369Y125827D02*
X63108D01*
G01X73621Y126417D02*
X72281D01*
G01Y126745D02*
X73621D01*
G01X64369Y127008D02*
X63108D01*
G01X72549Y127598D02*
X72683D01*
G01X72214Y127664D02*
X72281D01*
G01X64369Y127795D02*
X63108D01*
G01X72951Y127336D02*
X72549Y127270D01*
G01X71946Y126680D02*
X72281Y126745D01*
G01X72013Y124317D02*
X72281Y124383D01*
G01Y126417D02*
X72013Y126352D01*
G01X62911Y144921D02*
G03X63108Y144724I197J0D01*
G01Y143543D02*
G03X62911Y143346I0J-197D01*
G01Y142953D02*
G03X63108Y142756I197J0D01*
G01Y141575D02*
G03X62911Y141378I0J-197D01*
G01Y140984D02*
G03X63108Y140787I197J0D01*
G01Y139606D02*
G03X62911Y139409I0J-197D01*
G01Y139016D02*
G03X63108Y138819I197J0D01*
G01Y137638D02*
G03X62911Y137441I0J-197D01*
G01Y137047D02*
G03X63108Y136850I197J0D01*
G01Y135669D02*
G03X62911Y135472I0J-197D01*
G01Y135079D02*
G03X63108Y134882I197J0D01*
G01Y133701D02*
G03X62911Y133504I0J-197D01*
G01Y133110D02*
G03X63108Y132913I197J0D01*
G01Y131732D02*
G03X62911Y131535I0J-197D01*
G01Y131142D02*
G03X63108Y130945I197J0D01*
G01Y129764D02*
G03X62911Y129567I0J-197D01*
G01Y129173D02*
G03X63108Y128976I197J0D01*
G01X70196Y136339D02*
G03X69409Y135551I1J-788D01*
G01X71745Y134095D02*
X71946Y134226D01*
G01X72147Y133963D02*
X71946Y133832D01*
G01X71745Y129108D02*
X72013Y129304D01*
G01X71611Y133963D02*
X71745Y134095D01*
G01X71946Y133832D02*
X71812Y133701D01*
G01X71678Y131470D02*
X71812Y131601D01*
G01X72013Y131339D02*
X71879Y131207D01*
G01X71544Y131273D02*
X71678Y131470D01*
G01X71544Y128780D02*
X71745Y129108D01*
G01X71544Y133832D02*
X71611Y133963D01*
G01X71879Y131207D02*
X71812Y131076D01*
G01X71477D02*
X71544Y131273D01*
G01X71477Y133569D02*
X71544Y133832D01*
G01X71812Y133701D02*
X71745Y133438D01*
G01X71812Y131076D02*
X71745Y130813D01*
G01X62911Y144921D02*
Y145315D01*
G01Y142953D02*
Y143346D01*
G01Y140984D02*
Y141378D01*
G01Y139016D02*
Y139409D01*
G01Y137047D02*
Y137441D01*
G01Y135079D02*
Y135472D01*
G01Y133110D02*
Y133504D01*
G01Y131142D02*
Y131535D01*
G01Y129173D02*
Y129567D01*
G01X70472Y134882D02*
Y135210D01*
G01X71477Y133045D02*
Y133569D01*
G01Y130813D02*
Y131076D01*
G01Y129895D02*
Y130223D01*
G01X71544Y130551D02*
X71477Y130813D01*
G01X71745D02*
X71812Y130551D01*
G01X71946Y134226D02*
X72147Y134291D01*
G01Y129042D02*
X71946Y128911D01*
G01X71745Y133438D02*
Y133176D01*
G01X71544Y132782D02*
X71477Y133045D01*
G01X71745Y133176D02*
X71812Y132913D01*
G01Y131601D02*
X72013Y131667D01*
G01X71611Y132651D02*
X71544Y132782D01*
G01X71678Y130354D02*
X71544Y130551D01*
G01X71812D02*
X71946Y130354D01*
G01X71812Y130223D02*
X71678Y130354D01*
G01X71946D02*
X72080Y130223D01*
G01X71745Y132520D02*
X71611Y132651D01*
G01X71812Y132913D02*
X71946Y132782D01*
G01Y132388D02*
X71745Y132520D01*
G01X71946Y132782D02*
X72147Y132651D01*
G01Y132323D02*
X71946Y132388D01*
G01X72415Y132257D02*
X72147Y132323D01*
G01Y132651D02*
X72415Y132585D01*
G01X64369Y128976D02*
X63108D01*
G01X72281Y129042D02*
X72147D01*
G01X72281Y129370D02*
X72549D01*
G01X64369Y129764D02*
X63108D01*
G01X73621Y129895D02*
X71477D01*
G01X72080Y130223D02*
X73621D01*
G01X71477D02*
X71812D01*
G01X64369Y130945D02*
X63108D01*
G01X73621Y131404D02*
X72348D01*
G01X64369Y131732D02*
X63108D01*
G01X72348D02*
X73621D01*
G01X72683Y132257D02*
X72415D01*
G01Y132585D02*
X72683D01*
G01X64369Y132913D02*
X63108D01*
G01X64369Y133701D02*
X63108D01*
G01X72683Y134029D02*
X72415D01*
G01Y134357D02*
X72683D01*
G01X64369Y134882D02*
X63108D01*
G01X73621D02*
X70472D01*
G01Y135210D02*
X73621D01*
G01X64369Y135669D02*
X63108D01*
G01X79054Y136339D02*
X70196D01*
G01X64369Y136850D02*
X63108D01*
G01X64369Y137638D02*
X63108D01*
G01X64369Y138819D02*
X63108D01*
G01X64369Y139606D02*
X63108D01*
G01X64369Y140787D02*
X63108D01*
G01X64369Y141575D02*
X63108D01*
G01X64369Y142756D02*
X63108D01*
G01X64369Y143543D02*
X63108D01*
G01X64369Y144724D02*
X63108D01*
G01X72348Y131404D02*
X72013Y131339D01*
G01Y131667D02*
X72348Y131732D01*
G01X72013Y129304D02*
X72281Y129370D01*
G01X72415Y134029D02*
X72147Y133963D01*
G01Y134291D02*
X72415Y134357D01*
G01X63108Y145512D02*
G03X62911Y145315I0J-197D01*
G01X63108Y161260D02*
G03X62911Y161063I0J-197D01*
G01Y160669D02*
G03X63108Y160472I197J0D01*
G01Y159291D02*
G03X62911Y159095I0J-197D01*
G01Y158701D02*
G03X63108Y158504I197J0D01*
G01Y157323D02*
G03X62911Y157126I0J-197D01*
G01Y156732D02*
G03X63108Y156535I197J0D01*
G01Y155354D02*
G03X62911Y155158I0J-197D01*
G01Y154764D02*
G03X63108Y154567I197J0D01*
G01Y153386D02*
G03X62911Y153189I0J-197D01*
G01Y152795D02*
G03X63108Y152598I197J0D01*
G01Y151417D02*
G03X62911Y151220I0J-197D01*
G01Y150827D02*
G03X63108Y150630I197J0D01*
G01Y149449D02*
G03X62911Y149252I0J-197D01*
G01Y148858D02*
G03X63108Y148661I197J0D01*
G01Y147480D02*
G03X62911Y147283I0J-197D01*
G01Y146890D02*
G03X63108Y146693I197J0D01*
G01X62911Y160669D02*
Y161063D01*
G01Y158701D02*
Y159095D01*
G01Y156732D02*
Y157126D01*
G01Y154764D02*
Y155158D01*
G01Y152795D02*
Y153189D01*
G01Y150827D02*
Y151220D01*
G01Y148858D02*
Y149252D01*
G01Y146890D02*
Y147283D01*
G01X64369Y145512D02*
X63108D01*
G01X64369Y146693D02*
X63108D01*
G01X64369Y147480D02*
X63108D01*
G01X64369Y148661D02*
X63108D01*
G01X64369Y149449D02*
X63108D01*
G01X64369Y150630D02*
X63108D01*
G01X64369Y151417D02*
X63108D01*
G01X64369Y152598D02*
X63108D01*
G01X64369Y153386D02*
X63108D01*
G01X64369Y154567D02*
X63108D01*
G01X64369Y155354D02*
X63108D01*
G01X64369Y156535D02*
X63108D01*
G01X64369Y157323D02*
X63108D01*
G01X64369Y158504D02*
X63108D01*
G01X64369Y159291D02*
X63108D01*
G01X64369Y160472D02*
X63108D01*
G01X64369Y161260D02*
X63108D01*
G01Y167165D02*
G03X62911Y166969I0J-197D01*
G01Y166575D02*
G03X63108Y166378I197J0D01*
G01Y165197D02*
G03X62911Y165000I0J-197D01*
G01Y164606D02*
G03X63108Y164409I197J0D01*
G01Y163228D02*
G03X62911Y163032I0J-197D01*
G01Y162638D02*
G03X63108Y162441I197J0D01*
G01Y173071D02*
G03X62911Y172874I0J-197D01*
G01Y172480D02*
G03X63108Y172283I197J0D01*
G01Y171102D02*
G03X62911Y170906I0J-197D01*
G01Y170512D02*
G03X63108Y170315I197J0D01*
G01Y169134D02*
G03X62911Y168937I0J-197D01*
G01Y168543D02*
G03X63108Y168346I197J0D01*
G01X62911Y172480D02*
Y172874D01*
G01Y170512D02*
Y170906D01*
G01Y168543D02*
Y168937D01*
G01Y166575D02*
Y166969D01*
G01Y164606D02*
Y165000D01*
G01Y162638D02*
Y163032D01*
G01X64369Y162441D02*
X63108D01*
G01X64369Y163228D02*
X63108D01*
G01X64369Y164409D02*
X63108D01*
G01X64369Y165197D02*
X63108D01*
G01X64369Y166378D02*
X63108D01*
G01X64369Y167165D02*
X63108D01*
G01X64369Y168346D02*
X63108D01*
G01X64369Y169134D02*
X63108D01*
G01X64369Y170315D02*
X63108D01*
G01X64369Y171102D02*
X63108D01*
G01X64369Y172283D02*
X63108D01*
G01X64369Y173071D02*
X63108D01*
G01Y190787D02*
G03X62911Y190591I0J-197D01*
G01Y190197D02*
G03X63108Y190000I197J0D01*
G01Y188819D02*
G03X62911Y188622I0J-197D01*
G01Y188228D02*
G03X63108Y188032I197J1D01*
G01Y186850D02*
G03X62911Y186654I0J-197D01*
G01Y186260D02*
G03X63108Y186063I197J0D01*
G01Y184882D02*
G03X62911Y184685I0J-197D01*
G01Y184291D02*
G03X63108Y184095I197J1D01*
G01Y182913D02*
G03X62911Y182717I0J-197D01*
G01Y182323D02*
G03X63108Y182126I197J0D01*
G01X61417Y196496D02*
Y192362D01*
G01X62911Y190197D02*
Y190591D01*
G01Y188228D02*
Y188622D01*
G01Y186260D02*
Y186654D01*
G01Y184291D02*
Y184685D01*
G01Y182323D02*
Y182717D01*
G01X64369Y182126D02*
X63108D01*
G01X64369Y182913D02*
X63108D01*
G01X64369Y184095D02*
X63108D01*
G01X64369Y184882D02*
X63108D01*
G01X64369Y186063D02*
X63108D01*
G01X64369Y186850D02*
X63108D01*
G01X64369Y188032D02*
X63108D01*
G01X64369Y188819D02*
X63108D01*
G01X64369Y190000D02*
X63108D01*
G01X64369Y190787D02*
X63108D01*
G01X64369Y192362D02*
X61417D01*
G01X64369Y192953D02*
X61417D01*
G01X66732Y194134D02*
X61417D01*
G01X62204Y197283D02*
G03X61417Y196496I0J-787D01*
G01X93503Y197283D02*
X62204D01*
G01X62007Y223425D02*
Y217520D01*
G01D02*
X133464D01*
G01X85039Y-62047D02*
Y-105354D01*
G01X79054Y6457D02*
G03X79842Y7244I1J787D01*
G01X87991Y4469D02*
G03X86810Y5650I-1181J0D01*
G01X72817Y8176D02*
X73621Y7913D01*
G01X72817Y9488D02*
Y8176D01*
G01X73621Y7913D02*
Y7520D01*
G01Y10144D02*
Y9750D01*
G01Y12047D02*
Y11719D01*
G01Y13097D02*
Y12769D01*
G01Y10997D02*
Y10669D01*
G01X79842Y7244D02*
Y26890D01*
G01X82873Y-984D02*
Y2008D01*
G01X84054Y86161D02*
Y4469D01*
G01Y2008D02*
Y4469D01*
G01X84999Y10236D02*
Y9528D01*
G01Y12205D02*
Y11496D01*
G01X87991Y2008D02*
Y4469D01*
G01X133464Y-984D02*
X82873D01*
G01X87991Y4469D02*
X84054D01*
G01Y5650D02*
X86810D01*
G01X84054Y9528D02*
X84999D01*
G01Y10236D02*
X84054D01*
G01Y11496D02*
X84999D01*
G01Y12205D02*
X84054D01*
G01X73621Y9750D02*
X72817Y9488D01*
G01X79842Y26890D02*
G03X79054Y27677I-787J0D01*
G01X73353Y19659D02*
X73286Y20118D01*
G01X73554Y20183D02*
X73621Y19724D01*
G01X73286Y14803D02*
X73219Y15065D01*
G01X73554Y15197D02*
X73621Y14934D01*
G01X73353Y24777D02*
X73286Y25039D01*
G01X73554Y25170D02*
X73621Y24908D01*
G01X73420Y20446D02*
X73554Y20183D01*
G01X73487Y25302D02*
X73554Y25170D01*
G01X73219Y15065D02*
X73085Y15262D01*
G01X73420Y15394D02*
X73554Y15197D01*
G01X73286Y20118D02*
X73152Y20315D01*
G01X73219Y20643D02*
X73420Y20446D01*
G01X73286Y25039D02*
X73152Y25170D01*
G01X73353Y25433D02*
X73487Y25302D01*
G01X73085Y15656D02*
X73420Y15394D01*
G01X73152Y25170D02*
X72951Y25302D01*
G01X73152Y25564D02*
X73353Y25433D01*
G01X73085Y15262D02*
X72951Y15328D01*
G01X76378Y18150D02*
X78858Y17231D01*
G01X78522Y16969D02*
X75708Y17953D01*
G01X72951Y15328D02*
X72750Y15394D01*
G01X73621Y19724D02*
X73554Y19331D01*
G01X72951Y20380D02*
Y20709D01*
G01X73286Y14541D02*
Y14803D01*
G01X73353Y24514D02*
Y24777D01*
G01X73621Y14934D02*
Y14541D01*
G01Y16575D02*
Y16246D01*
G01Y18084D02*
Y17756D01*
G01Y21561D02*
Y21233D01*
G01Y24908D02*
Y24383D01*
G01Y23071D02*
Y22743D01*
G01Y26548D02*
Y26220D01*
G01X74693Y13950D02*
Y13622D01*
G01X75708Y17953D02*
Y18543D01*
G01Y15394D02*
Y15984D01*
G01X78858Y15787D02*
Y15394D01*
G01Y17231D02*
Y16706D01*
G01Y18543D02*
Y18150D01*
G01X84999Y14173D02*
Y13465D01*
G01Y16142D02*
Y15433D01*
G01Y18110D02*
Y17402D01*
G01Y20079D02*
Y19370D01*
G01Y22047D02*
Y21339D01*
G01Y24016D02*
Y23307D01*
G01Y25984D02*
Y25276D01*
G01Y27953D02*
Y27244D01*
G01Y29921D02*
Y29213D01*
G01X73152Y20315D02*
X72951Y20380D01*
G01X72683Y25695D02*
X73152Y25564D01*
G01X72817Y15722D02*
X73085Y15656D01*
G01X72951Y20709D02*
X73219Y20643D01*
G01X72951Y25302D02*
X72683Y25367D01*
G01X73554Y19331D02*
X73487Y19134D01*
G01X73286Y24252D02*
X73353Y24514D01*
G01X73621Y24383D02*
X73554Y24120D01*
G01X73286Y19396D02*
X73353Y19659D01*
G01X73219Y14278D02*
X73286Y14541D01*
G01X73621D02*
X73554Y14278D01*
G01X84054Y13465D02*
X84999D01*
G01X73219Y13950D02*
X74693D01*
G01X84999Y14173D02*
X84054D01*
G01X78858Y15394D02*
X75708D01*
G01X84054Y15433D02*
X84999D01*
G01X76378Y15787D02*
X78858D01*
G01X84999Y16142D02*
X84054D01*
G01Y17402D02*
X84999D01*
G01Y18110D02*
X84054D01*
G01X78858Y18150D02*
X76378D01*
G01X75708Y18543D02*
X78858D01*
G01X84054Y19370D02*
X84999D01*
G01Y20079D02*
X84054D01*
G01Y21339D02*
X84999D01*
G01Y22047D02*
X84054D01*
G01Y23307D02*
X84999D01*
G01X73554Y24120D02*
X73487Y23989D01*
G01X73219Y19265D02*
X73286Y19396D01*
G01X73554Y14278D02*
X73487Y14147D01*
G01X84999Y24016D02*
X84054D01*
G01Y25276D02*
X84999D01*
G01Y25984D02*
X84054D01*
G01Y27244D02*
X84999D01*
G01Y27953D02*
X84054D01*
G01Y29213D02*
X84999D01*
G01X73487Y19134D02*
X73353Y18937D01*
G01X73085Y14081D02*
X73219Y14278D01*
G01X72683Y23924D02*
X72951Y23989D01*
G01X73152Y23727D02*
X72683Y23596D01*
G01X73152Y24120D02*
X73286Y24252D01*
G01X73487Y23989D02*
X73353Y23858D01*
G01X73018Y19068D02*
X73219Y19265D01*
G01X73353Y18937D02*
X73219Y18806D01*
G01X73487Y14147D02*
X73353Y14016D01*
G01X72951Y23989D02*
X73152Y24120D01*
G01X73353Y23858D02*
X73152Y23727D01*
G01X72884Y13950D02*
X73085Y14081D01*
G01X72884Y19002D02*
X73018Y19068D01*
G01X73219Y18806D02*
X72951Y18674D01*
G01X73353Y14016D02*
X73219Y13950D01*
G01X72683Y18937D02*
X72884Y19002D01*
G01X75708Y15984D02*
X78522Y16969D01*
G01X78858Y16706D02*
X76378Y15787D01*
G01X84999Y31890D02*
Y31181D01*
G01Y33858D02*
Y33150D01*
G01Y35827D02*
Y35118D01*
G01Y37795D02*
Y37087D01*
G01Y39764D02*
Y39055D01*
G01Y43701D02*
Y42992D01*
G01Y41732D02*
Y41024D01*
G01Y45669D02*
Y44961D01*
G01Y29921D02*
X84054D01*
G01Y31181D02*
X84999D01*
G01Y31890D02*
X84054D01*
G01Y33150D02*
X84999D01*
G01Y33858D02*
X84054D01*
G01Y35118D02*
X84999D01*
G01Y35827D02*
X84054D01*
G01Y37087D02*
X84999D01*
G01Y37795D02*
X84054D01*
G01Y39055D02*
X84999D01*
G01Y39764D02*
X84054D01*
G01Y41024D02*
X84999D01*
G01Y41732D02*
X84054D01*
G01Y42992D02*
X84999D01*
G01Y43701D02*
X84054D01*
G01Y44961D02*
X84999D01*
G01Y45669D02*
X84054D01*
G01X84999Y47638D02*
Y46929D01*
G01Y49606D02*
Y48898D01*
G01Y51575D02*
Y50866D01*
G01Y53543D02*
Y52835D01*
G01Y55512D02*
Y54803D01*
G01Y57480D02*
Y56772D01*
G01Y59449D02*
Y58740D01*
G01Y61417D02*
Y60709D01*
G01Y63386D02*
Y62677D01*
G01X84054Y46929D02*
X84999D01*
G01Y47638D02*
X84054D01*
G01Y48898D02*
X84999D01*
G01Y49606D02*
X84054D01*
G01Y50866D02*
X84999D01*
G01Y51575D02*
X84054D01*
G01Y52835D02*
X84999D01*
G01Y53543D02*
X84054D01*
G01Y54803D02*
X84999D01*
G01Y55512D02*
X84054D01*
G01Y56772D02*
X84999D01*
G01Y57480D02*
X84054D01*
G01Y58740D02*
X84999D01*
G01Y59449D02*
X84054D01*
G01Y60709D02*
X84999D01*
G01Y61417D02*
X84054D01*
G01Y62677D02*
X84999D01*
G01X85826Y67264D02*
G03Y71595I0J2165D01*
G01X84999Y65354D02*
Y64646D01*
G01Y75197D02*
Y74488D01*
G01Y77165D02*
Y76457D01*
G01Y79134D02*
Y78425D01*
G01Y63386D02*
X84054D01*
G01Y64646D02*
X84999D01*
G01Y65354D02*
X84054D01*
G01Y67264D02*
X85826D01*
G01Y71595D02*
X84054D01*
G01Y74488D02*
X84999D01*
G01Y75197D02*
X84054D01*
G01Y76457D02*
X84999D01*
G01Y77165D02*
X84054D01*
G01Y78425D02*
X84999D01*
G01Y79134D02*
X84054D01*
G01X86810Y84980D02*
G03X87991Y86161I0J1181D01*
G01X82873Y88622D02*
Y91535D01*
G01X84054Y86161D02*
Y88622D01*
G01X84999Y81102D02*
Y80394D01*
G01X87991Y86161D02*
Y88622D01*
G01X84054Y80394D02*
X84999D01*
G01Y81102D02*
X84054D01*
G01Y84980D02*
X86810D01*
G01X84054Y86161D02*
X87991D01*
G01X133464Y91535D02*
X82873D01*
G01Y107677D02*
Y110669D01*
G01X84054D02*
Y113130D01*
G01X87991Y110669D02*
Y113130D01*
G01X82873Y107677D02*
X133464D01*
G01X79054Y115118D02*
G03X79842Y115906I1J787D01*
G01X87991Y113130D02*
G03X86810Y114311I-1181J0D01*
G01X73018Y127730D02*
X73219Y127926D01*
G01X73353Y127598D02*
X73219Y127467D01*
G01X73487Y122808D02*
X73353Y122677D01*
G01X73487Y127795D02*
X73353Y127598D01*
G01X73085Y122743D02*
X73219Y122939D01*
G01Y127926D02*
X73286Y128058D01*
G01X73554Y122939D02*
X73487Y122808D01*
G01X73554Y127992D02*
X73487Y127795D01*
G01X73286Y128058D02*
X73353Y128320D01*
G01X73219Y122939D02*
X73286Y123202D01*
G01X73621D02*
X73554Y122939D01*
G01X73621Y128386D02*
X73554Y127992D01*
G01X73353Y128320D02*
X73286Y128780D01*
G01X73554Y128845D02*
X73621Y128386D01*
G01X73286Y123465D02*
X73219Y123727D01*
G01X72884Y127664D02*
X73018Y127730D01*
G01X73219Y127467D02*
X72951Y127336D01*
G01X72884Y122611D02*
X73085Y122743D01*
G01X72817Y118150D02*
Y116837D01*
G01X73286Y123202D02*
Y123465D01*
G01X73621Y116575D02*
Y116181D01*
G01Y120709D02*
Y120380D01*
G01Y119659D02*
Y119331D01*
G01Y118806D02*
Y118412D01*
G01Y121758D02*
Y121430D01*
G01Y125236D02*
Y124908D01*
G01Y123596D02*
Y123202D01*
G01Y126745D02*
Y126417D01*
G01X74693Y122611D02*
Y122283D01*
G01X75708Y126614D02*
Y127205D01*
G01Y124055D02*
Y124646D01*
G01X78858Y124449D02*
Y124055D01*
G01Y127205D02*
Y126811D01*
G01Y125892D02*
Y125367D01*
G01X79842Y115906D02*
Y135551D01*
G01X84054Y194823D02*
Y113130D01*
G01X84999Y120866D02*
Y120158D01*
G01Y118898D02*
Y118189D01*
G01Y122835D02*
Y122126D01*
G01Y124803D02*
Y124095D01*
G01Y126772D02*
Y126063D01*
G01Y128740D02*
Y128032D01*
G01X73554Y123858D02*
X73621Y123596D01*
G01X72683Y127598D02*
X72884Y127664D01*
G01X73621Y118412D02*
X72817Y118150D01*
G01X75708Y124646D02*
X78522Y125630D01*
G01X78858Y125367D02*
X76378Y124449D01*
G01X73353Y122677D02*
X73219Y122611D01*
G01Y123727D02*
X73085Y123924D01*
G01X73420Y124055D02*
X73554Y123858D01*
G01X73085Y124317D02*
X73420Y124055D01*
G01X73085Y123924D02*
X72951Y123989D01*
G01X76378Y126811D02*
X78858Y125892D01*
G01X72817Y116837D02*
X73621Y116575D01*
G01X72951Y123989D02*
X72750Y124055D01*
G01X78522Y125630D02*
X75708Y126614D01*
G01X72817Y124383D02*
X73085Y124317D01*
G01X87991Y113130D02*
X84054D01*
G01Y114311D02*
X86810D01*
G01X84054Y118189D02*
X84999D01*
G01Y118898D02*
X84054D01*
G01Y120158D02*
X84999D01*
G01Y120866D02*
X84054D01*
G01Y122126D02*
X84999D01*
G01X73219Y122611D02*
X74693D01*
G01X84999Y122835D02*
X84054D01*
G01X78858Y124055D02*
X75708D01*
G01X84054Y124095D02*
X84999D01*
G01X76378Y124449D02*
X78858D01*
G01X84999Y124803D02*
X84054D01*
G01Y126063D02*
X84999D01*
G01Y126772D02*
X84054D01*
G01X78858Y126811D02*
X76378D01*
G01X75708Y127205D02*
X78858D01*
G01X84054Y128032D02*
X84999D01*
G01Y128740D02*
X84054D01*
G01X79842Y135551D02*
G03X79054Y136339I-788J0D01*
G01X73152Y132782D02*
X73286Y132913D01*
G01X73487Y132651D02*
X73353Y132520D01*
G01X73554Y132782D02*
X73487Y132651D01*
G01X73286Y132913D02*
X73353Y133176D01*
G01X73621Y133045D02*
X73554Y132782D01*
G01X72951Y132651D02*
X73152Y132782D01*
G01X73353Y132520D02*
X73152Y132388D01*
G01X72951Y129042D02*
Y129370D01*
G01X73353Y133176D02*
Y133438D01*
G01X73621Y131732D02*
Y131404D01*
G01Y130223D02*
Y129895D01*
G01Y133569D02*
Y133045D01*
G01Y135210D02*
Y134882D01*
G01X84999Y130709D02*
Y130000D01*
G01Y132677D02*
Y131969D01*
G01Y134646D02*
Y133937D01*
G01Y136614D02*
Y135906D01*
G01Y138583D02*
Y137874D01*
G01Y140551D02*
Y139843D01*
G01Y142520D02*
Y141811D01*
G01Y144488D02*
Y143780D01*
G01X73353Y133438D02*
X73286Y133701D01*
G01X73554Y133832D02*
X73621Y133569D01*
G01X73420Y129108D02*
X73554Y128845D01*
G01X73487Y133963D02*
X73554Y133832D01*
G01X73286Y128780D02*
X73152Y128976D01*
G01X73219Y129304D02*
X73420Y129108D01*
G01X73286Y133701D02*
X73152Y133832D01*
G01X73353Y134095D02*
X73487Y133963D01*
G01X73152Y133832D02*
X72951Y133963D01*
G01X73152Y134226D02*
X73353Y134095D01*
G01X73152Y128976D02*
X72951Y129042D01*
G01X72683Y134357D02*
X73152Y134226D01*
G01X72951Y129370D02*
X73219Y129304D01*
G01X72951Y133963D02*
X72683Y134029D01*
G01X84054Y130000D02*
X84999D01*
G01Y130709D02*
X84054D01*
G01Y131969D02*
X84999D01*
G01Y132677D02*
X84054D01*
G01Y133937D02*
X84999D01*
G01Y134646D02*
X84054D01*
G01Y135906D02*
X84999D01*
G01Y136614D02*
X84054D01*
G01Y137874D02*
X84999D01*
G01Y138583D02*
X84054D01*
G01Y139843D02*
X84999D01*
G01Y140551D02*
X84054D01*
G01Y141811D02*
X84999D01*
G01Y142520D02*
X84054D01*
G01Y143780D02*
X84999D01*
G01Y144488D02*
X84054D01*
G01X72683Y132585D02*
X72951Y132651D01*
G01X73152Y132388D02*
X72683Y132257D01*
G01X84999Y146457D02*
Y145748D01*
G01Y148425D02*
Y147717D01*
G01Y150394D02*
Y149685D01*
G01Y152362D02*
Y151654D01*
G01Y154331D02*
Y153622D01*
G01Y156299D02*
Y155591D01*
G01Y158268D02*
Y157559D01*
G01Y160236D02*
Y159528D01*
G01Y162205D02*
Y161496D01*
G01X84054Y145748D02*
X84999D01*
G01Y146457D02*
X84054D01*
G01Y147717D02*
X84999D01*
G01Y148425D02*
X84054D01*
G01Y149685D02*
X84999D01*
G01Y150394D02*
X84054D01*
G01Y151654D02*
X84999D01*
G01Y152362D02*
X84054D01*
G01Y153622D02*
X84999D01*
G01Y154331D02*
X84054D01*
G01Y155591D02*
X84999D01*
G01Y156299D02*
X84054D01*
G01Y157559D02*
X84999D01*
G01Y158268D02*
X84054D01*
G01Y159528D02*
X84999D01*
G01Y160236D02*
X84054D01*
G01Y161496D02*
X84999D01*
G01X85826Y175925D02*
G03Y180256I0J2165D01*
G01X84999Y164173D02*
Y163465D01*
G01Y166142D02*
Y165433D01*
G01Y170079D02*
Y169370D01*
G01Y168110D02*
Y167402D01*
G01Y172047D02*
Y171339D01*
G01Y174016D02*
Y173307D01*
G01Y162205D02*
X84054D01*
G01Y163465D02*
X84999D01*
G01Y164173D02*
X84054D01*
G01Y165433D02*
X84999D01*
G01Y166142D02*
X84054D01*
G01Y167402D02*
X84999D01*
G01Y168110D02*
X84054D01*
G01Y169370D02*
X84999D01*
G01Y170079D02*
X84054D01*
G01Y171339D02*
X84999D01*
G01Y172047D02*
X84054D01*
G01Y173307D02*
X84999D01*
G01Y174016D02*
X84054D01*
G01Y175925D02*
X85826D01*
G01X86810Y193642D02*
G03X87991Y194823I0J1181D01*
G01X84999Y183858D02*
Y183150D01*
G01Y185827D02*
Y185118D01*
G01Y187795D02*
Y187087D01*
G01Y189764D02*
Y189055D01*
G01X85826Y180256D02*
X84054D01*
G01Y183150D02*
X84999D01*
G01Y183858D02*
X84054D01*
G01Y185118D02*
X84999D01*
G01Y185827D02*
X84054D01*
G01Y187087D02*
X84999D01*
G01Y187795D02*
X84054D01*
G01Y189055D02*
X84999D01*
G01Y189764D02*
X84054D01*
G01Y193642D02*
X86810D01*
G01X82873Y197283D02*
Y200197D01*
G01X84054Y194823D02*
Y197283D01*
G01X87991Y194823D02*
Y197283D01*
G01X84054Y194823D02*
X87991D01*
G01X91268Y-740940D02*
Y-758263D01*
G01X94684Y11457D02*
G03X94881Y11654I0J197D01*
G01Y12047D02*
G03X94684Y12244I-197J0D01*
G01Y9488D02*
G03X94881Y9685I0J197D01*
G01Y10079D02*
G03X94684Y10276I-197J0D01*
G01X93503Y2008D02*
Y88622D01*
G01X94881Y11654D02*
Y12047D01*
G01Y9685D02*
Y10079D01*
G01X93503Y9488D02*
X94684D01*
G01Y10276D02*
X93503D01*
G01Y11457D02*
X94684D01*
G01Y12244D02*
X93503D01*
G01X94684Y29173D02*
G03X94881Y29370I0J197D01*
G01X94684Y27205D02*
G03X94881Y27402I0J197D01*
G01Y27795D02*
G03X94684Y27992I-197J0D01*
G01Y25236D02*
G03X94881Y25433I0J197D01*
G01Y25827D02*
G03X94684Y26024I-197J0D01*
G01Y23268D02*
G03X94881Y23465I0J197D01*
G01Y23858D02*
G03X94684Y24055I-197J0D01*
G01Y21299D02*
G03X94881Y21496I0J197D01*
G01Y21890D02*
G03X94684Y22087I-197J0D01*
G01Y19331D02*
G03X94881Y19528I0J197D01*
G01Y19921D02*
G03X94684Y20118I-197J0D01*
G01Y17362D02*
G03X94881Y17559I0J197D01*
G01Y17953D02*
G03X94684Y18150I-197J0D01*
G01Y15394D02*
G03X94881Y15591I0J197D01*
G01Y15984D02*
G03X94684Y16181I-197J0D01*
G01Y13425D02*
G03X94881Y13622I0J197D01*
G01Y14016D02*
G03X94684Y14213I-197J0D01*
G01X94881Y29370D02*
Y29764D01*
G01Y27402D02*
Y27795D01*
G01Y25433D02*
Y25827D01*
G01Y23465D02*
Y23858D01*
G01Y21496D02*
Y21890D01*
G01Y19528D02*
Y19921D01*
G01Y17559D02*
Y17953D01*
G01Y15591D02*
Y15984D01*
G01Y13622D02*
Y14016D01*
G01X93503Y13425D02*
X94684D01*
G01Y14213D02*
X93503D01*
G01Y15394D02*
X94684D01*
G01Y16181D02*
X93503D01*
G01Y17362D02*
X94684D01*
G01Y18150D02*
X93503D01*
G01Y19331D02*
X94684D01*
G01Y20118D02*
X93503D01*
G01Y21299D02*
X94684D01*
G01Y22087D02*
X93503D01*
G01Y23268D02*
X94684D01*
G01Y24055D02*
X93503D01*
G01Y25236D02*
X94684D01*
G01Y26024D02*
X93503D01*
G01Y27205D02*
X94684D01*
G01Y27992D02*
X93503D01*
G01Y29173D02*
X94684D01*
G01Y39016D02*
G03X94881Y39213I0J197D01*
G01X94684Y37047D02*
G03X94881Y37244I0J197D01*
G01Y37638D02*
G03X94684Y37835I-197J0D01*
G01Y35079D02*
G03X94881Y35276I0J197D01*
G01Y35669D02*
G03X94684Y35866I-197J0D01*
G01Y33110D02*
G03X94881Y33307I0J197D01*
G01Y33701D02*
G03X94684Y33898I-197J0D01*
G01Y31142D02*
G03X94881Y31339I0J197D01*
G01Y31732D02*
G03X94684Y31929I-197J0D01*
G01X94881Y29764D02*
G03X94684Y29961I-197J0D01*
G01Y44921D02*
G03X94881Y45118I0J197D01*
G01Y45512D02*
G03X94684Y45709I-197J0D01*
G01Y42953D02*
G03X94881Y43150I0J197D01*
G01Y43543D02*
G03X94684Y43740I-197J0D01*
G01Y40984D02*
G03X94881Y41181I0J197D01*
G01Y41575D02*
G03X94684Y41772I-197J0D01*
G01X94881Y39606D02*
G03X94684Y39803I-197J0D01*
G01X94881Y45118D02*
Y45512D01*
G01Y43150D02*
Y43543D01*
G01Y41181D02*
Y41575D01*
G01Y39213D02*
Y39606D01*
G01Y37244D02*
Y37638D01*
G01Y35276D02*
Y35669D01*
G01Y33307D02*
Y33701D01*
G01Y31339D02*
Y31732D01*
G01X93582Y38966D02*
X93503Y38993D01*
G01X94684Y29961D02*
X93503D01*
G01Y31142D02*
X94684D01*
G01Y31929D02*
X93503D01*
G01Y33110D02*
X94684D01*
G01Y33898D02*
X93503D01*
G01Y35079D02*
X94684D01*
G01Y35866D02*
X93503D01*
G01Y37047D02*
X94684D01*
G01Y37835D02*
X93503D01*
G01X94566Y38966D02*
X93582D01*
G01X94684Y39803D02*
X93503D01*
G01Y40984D02*
X94684D01*
G01Y41772D02*
X93503D01*
G01Y42953D02*
X94684D01*
G01Y43740D02*
X93503D01*
G01Y44921D02*
X94684D01*
G01Y45709D02*
X93503D01*
G01X94687Y39008D02*
X94566Y38966D01*
G01X94684Y62638D02*
G03X94881Y62835I0J197D01*
G01X94684Y60669D02*
G03X94881Y60866I0J197D01*
G01Y61260D02*
G03X94684Y61457I-197J0D01*
G01Y58701D02*
G03X94881Y58898I0J197D01*
G01Y59291D02*
G03X94684Y59488I-197J0D01*
G01Y56732D02*
G03X94881Y56929I0J197D01*
G01Y57323D02*
G03X94684Y57520I-197J0D01*
G01Y54764D02*
G03X94881Y54961I0J197D01*
G01Y55354D02*
G03X94684Y55551I-197J0D01*
G01Y52795D02*
G03X94881Y52992I0J197D01*
G01Y53386D02*
G03X94684Y53583I-197J0D01*
G01Y50827D02*
G03X94881Y51024I0J197D01*
G01Y51417D02*
G03X94684Y51614I-197J0D01*
G01Y48858D02*
G03X94881Y49055I0J197D01*
G01Y49449D02*
G03X94684Y49646I-197J0D01*
G01Y46890D02*
G03X94881Y47087I0J197D01*
G01Y47480D02*
G03X94684Y47677I-197J0D01*
G01X94881Y60866D02*
Y61260D01*
G01Y58898D02*
Y59291D01*
G01Y56929D02*
Y57323D01*
G01Y54961D02*
Y55354D01*
G01Y52992D02*
Y53386D01*
G01Y51024D02*
Y51417D01*
G01Y49055D02*
Y49449D01*
G01Y47087D02*
Y47480D01*
G01X93503Y46890D02*
X94684D01*
G01Y47677D02*
X93503D01*
G01Y48858D02*
X94684D01*
G01Y49646D02*
X93503D01*
G01Y50827D02*
X94684D01*
G01Y51614D02*
X93503D01*
G01Y52795D02*
X94684D01*
G01Y53583D02*
X93503D01*
G01Y54764D02*
X94684D01*
G01Y55551D02*
X93503D01*
G01Y56732D02*
X94684D01*
G01Y57520D02*
X93503D01*
G01Y58701D02*
X94684D01*
G01Y59488D02*
X93503D01*
G01Y60669D02*
X94684D01*
G01Y61457D02*
X93503D01*
G01Y62638D02*
X94684D01*
G01Y78386D02*
G03X94881Y78583I0J197D01*
G01Y78976D02*
G03X94684Y79173I-197J0D01*
G01Y76417D02*
G03X94881Y76614I0J197D01*
G01Y77008D02*
G03X94684Y77205I-197J0D01*
G01Y74449D02*
G03X94881Y74646I0J197D01*
G01Y75039D02*
G03X94684Y75236I-197J0D01*
G01Y64606D02*
G03X94881Y64803I0J197D01*
G01Y65197D02*
G03X94684Y65394I-197J0D01*
G01X94881Y63228D02*
G03X94684Y63425I-197J0D01*
G01X94881Y78583D02*
Y78976D01*
G01Y76614D02*
Y77008D01*
G01Y74646D02*
Y75039D01*
G01Y64803D02*
Y65197D01*
G01Y62835D02*
Y63228D01*
G01X94684Y63425D02*
X93503D01*
G01Y64606D02*
X94684D01*
G01Y65394D02*
X93503D01*
G01Y74449D02*
X94684D01*
G01Y75236D02*
X93503D01*
G01Y76417D02*
X94684D01*
G01Y77205D02*
X93503D01*
G01Y78386D02*
X94684D01*
G01Y79173D02*
X93503D01*
G01X94684Y80354D02*
G03X94881Y80551I0J197D01*
G01Y80945D02*
G03X94684Y81142I-197J0D01*
G01X94881Y80551D02*
Y80945D01*
G01X93503Y80354D02*
X94684D01*
G01Y81142D02*
X93503D01*
G01Y110669D02*
Y197283D01*
G01X94684Y122087D02*
G03X94881Y122283I0J197D01*
G01Y122677D02*
G03X94684Y122874I-197J0D01*
G01Y120118D02*
G03X94881Y120315I0J197D01*
G01Y120709D02*
G03X94684Y120906I-197J0D01*
G01Y118150D02*
G03X94881Y118346I0J197D01*
G01Y118740D02*
G03X94684Y118937I-197J0D01*
G01Y127992D02*
G03X94881Y128189I0J197D01*
G01Y128583D02*
G03X94684Y128780I-197J0D01*
G01Y126024D02*
G03X94881Y126220I0J197D01*
G01Y126614D02*
G03X94684Y126811I-197J0D01*
G01Y124055D02*
G03X94881Y124252I0J197D01*
G01Y124646D02*
G03X94684Y124843I-197J0D01*
G01X94881Y128189D02*
Y128583D01*
G01Y126220D02*
Y126614D01*
G01Y124252D02*
Y124646D01*
G01Y122283D02*
Y122677D01*
G01Y120315D02*
Y120709D01*
G01Y118346D02*
Y118740D01*
G01X93503Y118150D02*
X94684D01*
G01Y118937D02*
X93503D01*
G01Y120118D02*
X94684D01*
G01Y120906D02*
X93503D01*
G01Y122087D02*
X94684D01*
G01Y122874D02*
X93503D01*
G01Y124055D02*
X94684D01*
G01Y124843D02*
X93503D01*
G01Y126024D02*
X94684D01*
G01Y126811D02*
X93503D01*
G01Y127992D02*
X94684D01*
G01Y143740D02*
G03X94881Y143937I0J197D01*
G01Y144331D02*
G03X94684Y144528I-197J0D01*
G01Y141772D02*
G03X94881Y141969I0J197D01*
G01Y142362D02*
G03X94684Y142559I-197J0D01*
G01Y139803D02*
G03X94881Y140000I0J197D01*
G01Y140394D02*
G03X94684Y140591I-197J0D01*
G01Y137835D02*
G03X94881Y138032I0J197D01*
G01Y138425D02*
G03X94684Y138622I-197J0D01*
G01Y135866D02*
G03X94881Y136063I0J197D01*
G01Y136457D02*
G03X94684Y136654I-197J0D01*
G01Y133898D02*
G03X94881Y134095I0J197D01*
G01Y134488D02*
G03X94684Y134685I-197J0D01*
G01Y131929D02*
G03X94881Y132126I0J197D01*
G01Y132520D02*
G03X94684Y132717I-197J0D01*
G01Y129961D02*
G03X94881Y130158I0J197D01*
G01Y130551D02*
G03X94684Y130748I-197J0D01*
G01X94881Y143937D02*
Y144331D01*
G01Y141969D02*
Y142362D01*
G01Y140000D02*
Y140394D01*
G01Y138032D02*
Y138425D01*
G01Y136063D02*
Y136457D01*
G01Y134095D02*
Y134488D01*
G01Y132126D02*
Y132520D01*
G01Y130158D02*
Y130551D01*
G01X94684Y128780D02*
X93503D01*
G01Y129961D02*
X94684D01*
G01Y130748D02*
X93503D01*
G01Y131929D02*
X94684D01*
G01Y132717D02*
X93503D01*
G01Y133898D02*
X94684D01*
G01Y134685D02*
X93503D01*
G01Y135866D02*
X94684D01*
G01Y136654D02*
X93503D01*
G01Y137835D02*
X94684D01*
G01Y138622D02*
X93503D01*
G01Y139803D02*
X94684D01*
G01Y140591D02*
X93503D01*
G01Y141772D02*
X94684D01*
G01Y142559D02*
X93503D01*
G01Y143740D02*
X94684D01*
G01Y144528D02*
X93503D01*
G01X94684Y161457D02*
G03X94881Y161654I0J197D01*
G01X94684Y159488D02*
G03X94881Y159685I0J197D01*
G01Y160079D02*
G03X94684Y160276I-197J0D01*
G01Y157520D02*
G03X94881Y157717I0J197D01*
G01Y158110D02*
G03X94684Y158307I-197J0D01*
G01Y155551D02*
G03X94881Y155748I0J197D01*
G01Y156142D02*
G03X94684Y156339I-197J0D01*
G01Y153583D02*
G03X94881Y153780I0J197D01*
G01Y154173D02*
G03X94684Y154370I-197J0D01*
G01Y151614D02*
G03X94881Y151811I0J197D01*
G01Y152205D02*
G03X94684Y152402I-197J0D01*
G01Y149646D02*
G03X94881Y149843I0J197D01*
G01Y150236D02*
G03X94684Y150433I-197J0D01*
G01Y147677D02*
G03X94881Y147874I0J197D01*
G01Y148268D02*
G03X94684Y148465I-197J0D01*
G01Y145709D02*
G03X94881Y145906I0J197D01*
G01Y146299D02*
G03X94684Y146496I-197J0D01*
G01X94881Y161654D02*
Y162047D01*
G01Y159685D02*
Y160079D01*
G01Y157717D02*
Y158110D01*
G01Y155748D02*
Y156142D01*
G01Y153780D02*
Y154173D01*
G01Y151811D02*
Y152205D01*
G01Y149843D02*
Y150236D01*
G01Y147874D02*
Y148268D01*
G01Y145906D02*
Y146299D01*
G01X93503Y145709D02*
X94684D01*
G01Y146496D02*
X93503D01*
G01Y147677D02*
X94684D01*
G01Y148465D02*
X93503D01*
G01Y149646D02*
X94684D01*
G01Y150433D02*
X93503D01*
G01Y151614D02*
X94684D01*
G01Y152402D02*
X93503D01*
G01Y153583D02*
X94684D01*
G01Y154370D02*
X93503D01*
G01Y155551D02*
X94684D01*
G01Y156339D02*
X93503D01*
G01Y157520D02*
X94684D01*
G01Y158307D02*
X93503D01*
G01Y159488D02*
X94684D01*
G01Y160276D02*
X93503D01*
G01Y161457D02*
X94684D01*
G01Y167362D02*
G03X94881Y167559I0J197D01*
G01X94684Y165394D02*
G03X94881Y165591I0J197D01*
G01Y165984D02*
G03X94684Y166181I-197J0D01*
G01Y163425D02*
G03X94881Y163622I0J197D01*
G01Y164016D02*
G03X94684Y164213I-197J0D01*
G01X94881Y162047D02*
G03X94684Y162244I-197J0D01*
G01Y173268D02*
G03X94881Y173465I0J197D01*
G01Y173858D02*
G03X94684Y174055I-197J0D01*
G01Y171299D02*
G03X94881Y171496I0J197D01*
G01Y171890D02*
G03X94684Y172087I-197J0D01*
G01Y169331D02*
G03X94881Y169528I0J197D01*
G01Y169921D02*
G03X94684Y170118I-197J0D01*
G01X94881Y167953D02*
G03X94684Y168150I-197J0D01*
G01X94881Y173465D02*
Y173858D01*
G01Y171496D02*
Y171890D01*
G01Y169528D02*
Y169921D01*
G01Y167559D02*
Y167953D01*
G01Y165591D02*
Y165984D01*
G01Y163622D02*
Y164016D01*
G01X94684Y162244D02*
X93503D01*
G01Y163425D02*
X94684D01*
G01Y164213D02*
X93503D01*
G01Y165394D02*
X94684D01*
G01Y166181D02*
X93503D01*
G01Y167362D02*
X94684D01*
G01Y168150D02*
X93503D01*
G01Y169331D02*
X94684D01*
G01Y170118D02*
X93503D01*
G01Y171299D02*
X94684D01*
G01Y172087D02*
X93503D01*
G01Y173268D02*
X94684D01*
G01Y174055D02*
X93503D01*
G01X94684Y189016D02*
G03X94881Y189213I0J197D01*
G01Y189606D02*
G03X94684Y189803I-197J0D01*
G01Y187047D02*
G03X94881Y187244I0J197D01*
G01Y187638D02*
G03X94684Y187835I-197J0D01*
G01Y185079D02*
G03X94881Y185276I0J197D01*
G01Y185669D02*
G03X94684Y185866I-197J0D01*
G01Y183110D02*
G03X94881Y183307I0J197D01*
G01Y183701D02*
G03X94684Y183898I-197J0D01*
G01X94881Y189213D02*
Y189606D01*
G01Y187244D02*
Y187638D01*
G01Y185276D02*
Y185669D01*
G01Y183307D02*
Y183701D01*
G01X93503Y183110D02*
X94684D01*
G01Y183898D02*
X93503D01*
G01Y185079D02*
X94684D01*
G01Y185866D02*
X93503D01*
G01Y187047D02*
X94684D01*
G01Y187835D02*
X93503D01*
G01Y189016D02*
X94684D01*
G01Y189803D02*
X93503D01*
G01X105350Y209642D02*
Y217442D01*
G01X117950Y209642D02*
X105350D01*
G01X104250Y208542D02*
Y218542D01*
G01X119050Y208542D02*
X104250D01*
G01X128149Y240354D02*
G03X96653I-15748J0D01*
G03X128149I15748J0D01*
G01D02*
G03X96653I-15748J0D01*
G03X128149I15748J0D01*
G01X105350Y217442D02*
X117950D01*
G01X104250Y218542D02*
X119050D01*
G01X119389Y240354D02*
G03X105413I-6988J0D01*
G03X119389I6988J0D01*
G01D02*
G03X105413I-6988J0D01*
G03X119389I6988J0D01*
G01X112401Y247343D02*
G03Y233366I0J-6988D01*
G01X91268Y619690D02*
Y602367D01*
G01X117950Y217442D02*
Y209642D01*
G01X119050Y218542D02*
Y208542D01*
G01X111650Y215542D02*
G03Y211542I0J-2000D01*
G01D02*
G03Y215542I0J2000D01*
G01X112401Y233366D02*
G03Y247343I0J6989D01*
G01X133464Y0D02*
G03X141338Y-7874I7874J0D01*
G01X133464Y0D02*
G03X141338Y-7874I7874J0D01*
G01X133464Y0D02*
G03X141338Y-7874I7874J0D01*
G01X133464Y0D02*
G03X141338Y-7874I7874J0D01*
G01X133464Y0D02*
G03X141338Y-7874I7874J0D01*
G01X133464Y250197D02*
Y0D01*
G01Y250197D02*
Y0D01*
G01Y250197D02*
Y0D01*
G01Y250197D02*
Y-984D01*
G01Y0D02*
Y250197D01*
G01X141338Y116437D02*
G03X133464I-3937J0D01*
G01Y141634D02*
G03X141338I3937J0D01*
G01X133464Y250197D02*
G03X125590Y258071I-7874J0D01*
G01X133464Y250197D02*
G03X125590Y258071I-7874J0D01*
G01X133464Y250197D02*
G03X125590Y258071I-7874J0D01*
G01X133464Y250197D02*
G03X125590Y258071I-7874J0D01*
G01X133464Y250197D02*
G03X125590Y258071I-7874J0D01*
G01X341535Y-7874D02*
X141338D01*
G01D02*
X341535D01*
G01D02*
X141338D01*
G01X341535D02*
X141337D01*
G01X141338Y0D02*
Y116437D01*
G01X162106Y0D02*
X141337D01*
G01X141338Y141634D02*
Y258071D01*
G01D02*
X162106D01*
G01X168979Y-69933D02*
Y-54333D01*
G01X173464Y-69933D02*
X164494D01*
G01X162106Y-7874D02*
G03Y0I0J3937D01*
G01X179626Y62719D02*
G03X171044I-4291J0D01*
G03X179626I4291J0D01*
G01Y189063D02*
G03X171044Y189062I-4291J0D01*
G03X179626Y189063I4291J1D01*
G01X162106Y258071D02*
G03Y265945I0J3937D01*
G01X183509Y-750749D02*
X183979Y-751484D01*
X184605Y-751904D01*
X185310Y-752009D01*
X185937Y-751904D01*
X186564Y-751379D01*
X186955Y-750749D01*
X187034Y-750119D01*
X186877Y-749384D01*
X186329Y-748859D01*
X185780Y-748649D01*
X185075D01*
G01X185780D02*
X186250Y-748334D01*
X186642Y-747809D01*
X186799Y-747179D01*
X186642Y-746549D01*
X186250Y-746024D01*
X185545Y-745709D01*
X184840Y-745814D01*
X184135Y-746234D01*
G01X187302Y0D02*
G03Y-7874I1J-3937D01*
G01X208071Y0D02*
X187302D01*
G01Y265945D02*
G03Y258071I1J-3937D01*
G01D02*
X208071D01*
G01X180429Y328004D02*
Y312404D01*
G01X175944Y328004D02*
X184914D01*
G01X183509Y609881D02*
X183979Y609146D01*
X184605Y608726D01*
X185310Y608621D01*
X185937Y608726D01*
X186564Y609251D01*
X186955Y609881D01*
X187034Y610511D01*
X186877Y611246D01*
X186329Y611771D01*
X185780Y611981D01*
X185075D01*
G01X185780D02*
X186250Y612296D01*
X186642Y612821D01*
X186799Y613451D01*
X186642Y614081D01*
X186250Y614606D01*
X185545Y614921D01*
X184840Y614816D01*
X184135Y614396D01*
G01X207913Y0D02*
X208071D01*
G01X215945Y7874D02*
G03X223819Y0I7874J0D01*
G01X208071Y116437D02*
Y0D01*
G01X215945Y258071D02*
Y7874D01*
G01D02*
G03X223819Y0I7874J0D01*
G01X215945Y7874D02*
G03X223819Y0I7874J0D01*
G01X215945Y7874D02*
G03X223819Y0I7874J0D01*
G01X215945Y7874D02*
G03X223819Y0I7874J0D01*
G01X215945Y7874D02*
Y258070D01*
G01Y7874D02*
Y258070D01*
G01Y7874D02*
Y258070D01*
G01Y7874D02*
Y259055D01*
G01X287401Y40551D02*
X215945D01*
G01Y57874D02*
X319094D01*
G01X215945Y116437D02*
G03X208071I-3937J0D01*
G01Y141634D02*
G03X215945I3937J0D01*
G01X208071Y258071D02*
Y141634D01*
G01X266535Y150393D02*
X215945D01*
G01Y166535D02*
X266535D01*
G01X215945Y258071D02*
G03X208071Y265945I-7874J0D01*
G01X215945Y258070D02*
G03X208071Y265945I-7874J1D01*
G01X215945Y258070D02*
G03X208071Y265945I-7874J1D01*
G01X215945Y258070D02*
G03X208071Y265945I-7874J1D01*
G01X215945Y258070D02*
G03X208071Y265945I-7874J1D01*
G01X215945Y259055D02*
X266535D01*
G01X237000Y-113228D02*
G03Y-105354I0J3937D01*
G01X243996Y17716D02*
G03X230019Y17717I-6989J0D01*
G03X243996Y17716I6988J-1D01*
G01X252756D02*
G03X221259Y17717I-15748J0D01*
G03X252756Y17716I15748J-1D01*
G01X243996D02*
G03X230019Y17717I-6989J0D01*
G03X243996Y17716I6988J-1D01*
G01X252756D02*
G03X221259Y17717I-15748J0D01*
G03X252756Y17716I15748J-1D01*
G01X237008Y24705D02*
G03Y10728I0J-6989D01*
G01D02*
G03Y24705I0J6988D01*
G01X223819Y0D02*
X347441D01*
G01X223819D02*
X347441D01*
G01X223819D02*
X347441D01*
G01X223819D02*
X347441D01*
G01X223819D02*
X347441D01*
G01X237758Y46529D02*
G03Y42529I0J-2000D01*
G01X244058Y40629D02*
X231458D01*
G01D02*
Y48429D01*
G01X245158Y39529D02*
X230358D01*
G01D02*
Y49529D01*
G01X231458Y48429D02*
X244058D01*
G01X230358Y49529D02*
X245158D01*
G01X237000Y363425D02*
G03Y371299I0J3937D01*
G01X237758Y42529D02*
G03Y46529I0J2000D01*
G01X244058Y48429D02*
Y40629D01*
G01X245158Y49529D02*
Y39529D01*
G01X249682Y383110D02*
Y382716D01*
G01Y383110D02*
Y383504D01*
G01X249190Y383110D02*
X250174D01*
G01X245745D02*
G03X253619I3937J0D01*
G01X722440Y371299D02*
Y375236D01*
G03X714566Y383110I-7874J0D01*
G01X253619D01*
G01X264496Y-740940D02*
Y-758263D01*
G01X262196Y-113228D02*
X460244D01*
G01X262196Y-105354D02*
G03Y-113228I0J-3937D01*
G01X266535Y60787D02*
Y57874D01*
G01X265354Y63248D02*
Y60787D01*
G01X261417Y63248D02*
Y60787D01*
G01X255905Y147401D02*
Y60787D01*
G01D02*
X287204D01*
G01X254724Y69055D02*
G03X254527Y68858I0J-197D01*
G01Y68464D02*
G03X254724Y68267I197J0D01*
G01Y71023D02*
G03X254527Y70826I0J-197D01*
G01Y70433D02*
G03X254724Y70236I197J0D01*
G01Y72992D02*
G03X254527Y72795I0J-197D01*
G01Y72401D02*
G03X254724Y72204I197J0D01*
G01Y74960D02*
G03X254527Y74763I0J-197D01*
G01Y74370D02*
G03X254724Y74173I197J0D01*
G01X262598Y64429D02*
G03X261417Y63248I0J-1181D01*
G01X263582Y82145D02*
G03Y77815I0J-2165D01*
G01X265354Y63248D02*
Y144941D01*
G01X264409Y74212D02*
Y74921D01*
G01Y72244D02*
Y72952D01*
G01Y70275D02*
Y70984D01*
G01Y68307D02*
Y69015D01*
G01X254527Y68858D02*
Y68464D01*
G01Y70826D02*
Y70433D01*
G01Y72795D02*
Y72401D01*
G01Y74763D02*
Y74370D01*
G01X263582Y77815D02*
X265354D01*
G01X255905Y74960D02*
X254724D01*
G01X265354Y74921D02*
X264409D01*
G01Y74212D02*
X265354D01*
G01X254724Y74173D02*
X255905D01*
G01Y72992D02*
X254724D01*
G01X265354Y72952D02*
X264409D01*
G01Y72244D02*
X265354D01*
G01X254724Y72204D02*
X255905D01*
G01Y71023D02*
X254724D01*
G01X265354Y70984D02*
X264409D01*
G01Y70275D02*
X265354D01*
G01X254724Y70236D02*
X255905D01*
G01Y69055D02*
X254724D01*
G01X265354Y69015D02*
X264409D01*
G01Y68307D02*
X265354D01*
G01X254724Y68267D02*
X255905D01*
G01X265354Y64429D02*
X262598D01*
G01X265354Y63248D02*
X261417D01*
G01X254724Y90708D02*
G03X254527Y90511I0J-197D01*
G01X254724Y92677D02*
G03X254527Y92480I0J-197D01*
G01Y92086D02*
G03X254724Y91889I197J0D01*
G01Y94645D02*
G03X254527Y94448I0J-197D01*
G01Y94055D02*
G03X254724Y93858I197J0D01*
G01Y84803D02*
G03X254527Y84606I0J-197D01*
G01Y84212D02*
G03X254724Y84015I197J0D01*
G01Y86771D02*
G03X254527Y86574I0J-197D01*
G01Y86181D02*
G03X254724Y85984I197J0D01*
G01Y88740D02*
G03X254527Y88543I0J-197D01*
G01Y88149D02*
G03X254724Y87952I197J0D01*
G01X254527Y90118D02*
G03X254724Y89921I197J0D01*
G01X264409Y93897D02*
Y94606D01*
G01Y91929D02*
Y92637D01*
G01Y87992D02*
Y88700D01*
G01Y89960D02*
Y90669D01*
G01Y86023D02*
Y86732D01*
G01Y84055D02*
Y84763D01*
G01X254527Y84606D02*
Y84212D01*
G01Y86574D02*
Y86181D01*
G01Y88543D02*
Y88149D01*
G01Y90511D02*
Y90118D01*
G01Y92480D02*
Y92086D01*
G01Y94448D02*
Y94055D01*
G01X255905Y94645D02*
X254724D01*
G01X265354Y94606D02*
X264409D01*
G01Y93897D02*
X265354D01*
G01X254724Y93858D02*
X255905D01*
G01Y92677D02*
X254724D01*
G01X265354Y92637D02*
X264409D01*
G01Y91929D02*
X265354D01*
G01X254724Y91889D02*
X255905D01*
G01Y90708D02*
X254724D01*
G01X265354Y90669D02*
X264409D01*
G01Y89960D02*
X265354D01*
G01X254724Y89921D02*
X255905D01*
G01Y88740D02*
X254724D01*
G01X265354Y88700D02*
X264409D01*
G01Y87992D02*
X265354D01*
G01X254724Y87952D02*
X255905D01*
G01Y86771D02*
X254724D01*
G01X265354Y86732D02*
X264409D01*
G01Y86023D02*
X265354D01*
G01X254724Y85984D02*
X255905D01*
G01Y84803D02*
X254724D01*
G01X265354Y84763D02*
X264409D01*
G01Y84055D02*
X265354D01*
G01X254724Y84015D02*
X255905D01*
G01X265354Y82145D02*
X263582D01*
G01X254724Y96614D02*
G03X254527Y96417I0J-197D01*
G01Y96023D02*
G03X254724Y95826I197J0D01*
G01Y98582D02*
G03X254527Y98385I0J-197D01*
G01Y97992D02*
G03X254724Y97795I197J0D01*
G01Y100551D02*
G03X254527Y100354I0J-197D01*
G01Y99960D02*
G03X254724Y99763I197J0D01*
G01Y102519D02*
G03X254527Y102322I0J-197D01*
G01Y101929D02*
G03X254724Y101732I197J0D01*
G01Y104488D02*
G03X254527Y104291I0J-197D01*
G01Y103897D02*
G03X254724Y103700I197J0D01*
G01Y106456D02*
G03X254527Y106259I0J-197D01*
G01Y105866D02*
G03X254724Y105669I197J0D01*
G01Y108425D02*
G03X254527Y108228I0J-197D01*
G01Y107834D02*
G03X254724Y107637I197J0D01*
G01Y110393D02*
G03X254527Y110196I0J-197D01*
G01Y109803D02*
G03X254724Y109606I197J0D01*
G01Y112362D02*
G03X254527Y112165I0J-197D01*
G01Y111771D02*
G03X254724Y111574I197J0D01*
G01X264409Y111614D02*
Y112322D01*
G01Y109645D02*
Y110354D01*
G01Y107677D02*
Y108385D01*
G01Y105708D02*
Y106417D01*
G01Y103740D02*
Y104448D01*
G01Y101771D02*
Y102480D01*
G01Y99803D02*
Y100511D01*
G01Y97834D02*
Y98543D01*
G01Y95866D02*
Y96574D01*
G01X254527Y96417D02*
Y96023D01*
G01Y98385D02*
Y97992D01*
G01Y100354D02*
Y99960D01*
G01Y102322D02*
Y101929D01*
G01Y104291D02*
Y103897D01*
G01Y106259D02*
Y105866D01*
G01Y108228D02*
Y107834D01*
G01Y110196D02*
Y109803D01*
G01Y112165D02*
Y111771D01*
G01X264409Y111614D02*
X265354D01*
G01X254724Y111574D02*
X255905D01*
G01Y110393D02*
X254724D01*
G01X265354Y110354D02*
X264409D01*
G01Y109645D02*
X265354D01*
G01X254724Y109606D02*
X255905D01*
G01Y108425D02*
X254724D01*
G01X265354Y108385D02*
X264409D01*
G01Y107677D02*
X265354D01*
G01X254724Y107637D02*
X255905D01*
G01Y106456D02*
X254724D01*
G01X265354Y106417D02*
X264409D01*
G01Y105708D02*
X265354D01*
G01X254724Y105669D02*
X255905D01*
G01Y104488D02*
X254724D01*
G01X265354Y104448D02*
X264409D01*
G01Y103740D02*
X265354D01*
G01X254724Y103700D02*
X255905D01*
G01Y102519D02*
X254724D01*
G01X265354Y102480D02*
X264409D01*
G01Y101771D02*
X265354D01*
G01X254724Y101732D02*
X255905D01*
G01Y100551D02*
X254724D01*
G01X265354Y100511D02*
X264409D01*
G01Y99803D02*
X265354D01*
G01X254724Y99763D02*
X255905D01*
G01Y98582D02*
X254724D01*
G01X265354Y98543D02*
X264409D01*
G01Y97834D02*
X265354D01*
G01X254724Y97795D02*
X255905D01*
G01Y96614D02*
X254724D01*
G01X265354Y96574D02*
X264409D01*
G01Y95866D02*
X265354D01*
G01X254724Y95826D02*
X255905D01*
G01X269567Y122519D02*
G03X270354Y121732I787J0D01*
G01X254724Y114330D02*
G03X254527Y114133I0J-197D01*
G01Y113740D02*
G03X254724Y113543I197J0D01*
G01Y116299D02*
G03X254527Y116102I0J-197D01*
G01Y115708D02*
G03X254724Y115511I197J0D01*
G01Y118267D02*
G03X254527Y118070I0J-197D01*
G01Y117677D02*
G03X254724Y117480I197J0D01*
G01Y120236D02*
G03X254527Y120039I0J-197D01*
G01Y119645D02*
G03X254724Y119448I197J0D01*
G01Y122204D02*
G03X254527Y122008I0J-197D01*
G01Y121614D02*
G03X254724Y121417I197J0D01*
G01Y124173D02*
G03X254527Y123976I0J-197D01*
G01Y123582D02*
G03X254724Y123385I197J0D01*
G01Y126141D02*
G03X254527Y125945I0J-197D01*
G01Y125551D02*
G03X254724Y125354I197J0D01*
G01Y128110D02*
G03X254527Y127913I0J-197D01*
G01Y127519D02*
G03X254724Y127322I197J0D01*
G01X269567Y142165D02*
Y122519D01*
G01X264409Y127362D02*
Y128070D01*
G01Y125393D02*
Y126102D01*
G01Y123425D02*
Y124133D01*
G01Y121456D02*
Y122165D01*
G01Y119488D02*
Y120196D01*
G01Y117519D02*
Y118228D01*
G01Y115551D02*
Y116259D01*
G01Y113582D02*
Y114291D01*
G01X254527Y114133D02*
Y113740D01*
G01Y116102D02*
Y115708D01*
G01Y118070D02*
Y117677D01*
G01Y120039D02*
Y119645D01*
G01Y122008D02*
Y121614D01*
G01Y123976D02*
Y123582D01*
G01Y125945D02*
Y125551D01*
G01Y127913D02*
Y127519D01*
G01X255905Y128110D02*
X254724D01*
G01X265354Y128070D02*
X264409D01*
G01Y127362D02*
X265354D01*
G01X254724Y127322D02*
X255905D01*
G01Y126141D02*
X254724D01*
G01X265354Y126102D02*
X264409D01*
G01Y125393D02*
X265354D01*
G01X254724Y125354D02*
X255905D01*
G01Y124173D02*
X254724D01*
G01X265354Y124133D02*
X264409D01*
G01Y123425D02*
X265354D01*
G01X254724Y123385D02*
X255905D01*
G01Y122204D02*
X254724D01*
G01X265354Y122165D02*
X264409D01*
G01X270354Y121732D02*
X279212D01*
G01X264409Y121456D02*
X265354D01*
G01X254724Y121417D02*
X255905D01*
G01Y120236D02*
X254724D01*
G01X265354Y120196D02*
X264409D01*
G01Y119488D02*
X265354D01*
G01X254724Y119448D02*
X255905D01*
G01Y118267D02*
X254724D01*
G01X265354Y118228D02*
X264409D01*
G01Y117519D02*
X265354D01*
G01X254724Y117480D02*
X255905D01*
G01Y116299D02*
X254724D01*
G01X265354Y116259D02*
X264409D01*
G01Y115551D02*
X265354D01*
G01X254724Y115511D02*
X255905D01*
G01Y114330D02*
X254724D01*
G01X265354Y114291D02*
X264409D01*
G01Y113582D02*
X265354D01*
G01X254724Y113543D02*
X255905D01*
G01Y112362D02*
X254724D01*
G01X265354Y112322D02*
X264409D01*
G01X270354Y142952D02*
G03X269567Y142165I0J-787D01*
G01X254724Y135984D02*
G03X254527Y135787I0J-197D01*
G01Y135393D02*
G03X254724Y135196I197J0D01*
G01Y137952D02*
G03X254527Y137756I0J-197D01*
G01Y137362D02*
G03X254724Y137165I197J0D01*
G01Y139921D02*
G03X254527Y139724I0J-197D01*
G01Y139330D02*
G03X254724Y139133I197J0D01*
G01X261417Y144941D02*
G03X262598Y143759I1181J-1D01*
G01X254724Y130078D02*
G03X254527Y129882I0J-197D01*
G01Y129488D02*
G03X254724Y129291I197J0D01*
G01Y132047D02*
G03X254527Y131850I0J-197D01*
G01Y131456D02*
G03X254724Y131259I197J0D01*
G01Y134015D02*
G03X254527Y133819I0J-197D01*
G01Y133425D02*
G03X254724Y133228I197J0D01*
G01X270551Y133622D02*
Y134015D01*
G01Y130866D02*
Y131259D01*
G01Y132178D02*
Y132703D01*
G01X265354Y147401D02*
Y144941D01*
G01X264409Y137204D02*
Y137913D01*
G01Y139173D02*
Y139882D01*
G01Y135236D02*
Y135945D01*
G01Y133267D02*
Y133976D01*
G01Y131299D02*
Y132008D01*
G01Y129330D02*
Y130039D01*
G01X261417Y147401D02*
Y144941D01*
G01X270551Y132703D02*
X273030Y133622D01*
G01X254527Y129882D02*
Y129488D01*
G01Y131850D02*
Y131456D01*
G01Y133819D02*
Y133425D01*
G01Y135787D02*
Y135393D01*
G01Y137756D02*
Y137362D01*
G01Y139724D02*
Y139330D01*
G01X273030Y131259D02*
X270551Y132178D01*
G01X261417Y144941D02*
X265354D01*
G01Y143759D02*
X262598D01*
G01X279212Y142952D02*
X270354D01*
G01X255905Y139921D02*
X254724D01*
G01X265354Y139882D02*
X264409D01*
G01Y139173D02*
X265354D01*
G01X254724Y139133D02*
X255905D01*
G01Y137952D02*
X254724D01*
G01X265354Y137913D02*
X264409D01*
G01Y137204D02*
X265354D01*
G01X254724Y137165D02*
X255905D01*
G01Y135984D02*
X254724D01*
G01X265354Y135945D02*
X264409D01*
G01Y135236D02*
X265354D01*
G01X254724Y135196D02*
X255905D01*
G01X270551Y134015D02*
X273700D01*
G01X255905D02*
X254724D01*
G01X265354Y133976D02*
X264409D01*
G01X273030Y133622D02*
X270551D01*
G01X264409Y133267D02*
X265354D01*
G01X254724Y133228D02*
X255905D01*
G01Y132047D02*
X254724D01*
G01X265354Y132008D02*
X264409D01*
G01Y131299D02*
X265354D01*
G01X270551Y131259D02*
X273030D01*
G01X254724D02*
X255905D01*
G01X273700Y130866D02*
X270551D01*
G01X255905Y130078D02*
X254724D01*
G01X265354Y130039D02*
X264409D01*
G01Y129330D02*
X265354D01*
G01X254724Y129291D02*
X255905D01*
G01X266535Y150393D02*
Y147401D01*
G01X255905D02*
X287204D01*
G01X254724Y177716D02*
G03X254527Y177519I0J-197D01*
G01Y177126D02*
G03X254724Y176929I197J0D01*
G01X262598Y173090D02*
G03X261417Y171909I0J-1181D01*
G01X266535Y169448D02*
Y166535D01*
G01X265354Y171909D02*
Y253602D01*
G01Y171909D02*
Y169448D01*
G01X264409Y176968D02*
Y177677D01*
G01X261417Y171909D02*
Y169448D01*
G01X255905Y256063D02*
Y169448D01*
G01X254527Y177519D02*
Y177126D01*
G01X255905Y177716D02*
X254724D01*
G01X265354Y177677D02*
X264409D01*
G01Y176968D02*
X265354D01*
G01X254724Y176929D02*
X255905D01*
G01X265354Y173090D02*
X262598D01*
G01X265354Y171909D02*
X261417D01*
G01X255905Y169448D02*
X287204D01*
G01X254724Y179685D02*
G03X254527Y179488I0J-197D01*
G01Y179094D02*
G03X254724Y178897I197J0D01*
G01Y181653D02*
G03X254527Y181456I0J-197D01*
G01Y181063D02*
G03X254724Y180866I197J0D01*
G01Y183622D02*
G03X254527Y183425I0J-197D01*
G01Y183031D02*
G03X254724Y182834I197J0D01*
G01Y193464D02*
G03X254527Y193267I0J-197D01*
G01Y192874D02*
G03X254724Y192677I197J0D01*
G01X254527Y194842D02*
G03X254724Y194645I197J0D01*
G01X263582Y190807D02*
G03Y186476I0J-2165D01*
G01X264409Y194685D02*
Y195393D01*
G01Y192716D02*
Y193425D01*
G01Y182874D02*
Y183582D01*
G01Y180905D02*
Y181614D01*
G01Y178937D02*
Y179645D01*
G01X254527Y179488D02*
Y179094D01*
G01Y181456D02*
Y181063D01*
G01Y183425D02*
Y183031D01*
G01Y193267D02*
Y192874D01*
G01X264409Y194685D02*
X265354D01*
G01X254724Y194645D02*
X255905D01*
G01Y193464D02*
X254724D01*
G01X265354Y193425D02*
X264409D01*
G01Y192716D02*
X265354D01*
G01X254724Y192677D02*
X255905D01*
G01X265354Y190807D02*
X263582D01*
G01Y186476D02*
X265354D01*
G01X255905Y183622D02*
X254724D01*
G01X265354Y183582D02*
X264409D01*
G01Y182874D02*
X265354D01*
G01X254724Y182834D02*
X255905D01*
G01Y181653D02*
X254724D01*
G01X265354Y181614D02*
X264409D01*
G01Y180905D02*
X265354D01*
G01X254724Y180866D02*
X255905D01*
G01Y179685D02*
X254724D01*
G01X265354Y179645D02*
X264409D01*
G01Y178937D02*
X265354D01*
G01X254724Y178897D02*
X255905D01*
G01X254724Y195433D02*
G03X254527Y195236I0J-197D01*
G01X254724Y197401D02*
G03X254527Y197204I0J-197D01*
G01Y196811D02*
G03X254724Y196614I197J0D01*
G01Y199370D02*
G03X254527Y199173I0J-197D01*
G01Y198779D02*
G03X254724Y198582I197J0D01*
G01Y201338D02*
G03X254527Y201141I0J-197D01*
G01Y200748D02*
G03X254724Y200551I197J0D01*
G01Y203307D02*
G03X254527Y203110I0J-197D01*
G01Y202716D02*
G03X254724Y202519I197J0D01*
G01Y205275D02*
G03X254527Y205078I0J-197D01*
G01Y204685D02*
G03X254724Y204488I197J0D01*
G01Y207244D02*
G03X254527Y207047I0J-197D01*
G01Y206653D02*
G03X254724Y206456I197J0D01*
G01Y209212D02*
G03X254527Y209015I0J-197D01*
G01Y208622D02*
G03X254724Y208425I197J0D01*
G01Y211181D02*
G03X254527Y210984I0J-197D01*
G01Y210590D02*
G03X254724Y210393I197J0D01*
G01X264409Y210433D02*
Y211141D01*
G01Y208464D02*
Y209173D01*
G01Y206496D02*
Y207204D01*
G01Y204527D02*
Y205236D01*
G01Y202559D02*
Y203267D01*
G01Y200590D02*
Y201299D01*
G01Y198622D02*
Y199330D01*
G01Y196653D02*
Y197362D01*
G01X254527Y195236D02*
Y194842D01*
G01Y197204D02*
Y196811D01*
G01Y199173D02*
Y198779D01*
G01Y201141D02*
Y200748D01*
G01Y203110D02*
Y202716D01*
G01Y205078D02*
Y204685D01*
G01Y207047D02*
Y206653D01*
G01Y209015D02*
Y208622D01*
G01Y210984D02*
Y210590D01*
G01X255905Y211181D02*
X254724D01*
G01X265354Y211141D02*
X264409D01*
G01Y210433D02*
X265354D01*
G01X254724Y210393D02*
X255905D01*
G01Y209212D02*
X254724D01*
G01X265354Y209173D02*
X264409D01*
G01Y208464D02*
X265354D01*
G01X254724Y208425D02*
X255905D01*
G01Y207244D02*
X254724D01*
G01X265354Y207204D02*
X264409D01*
G01Y206496D02*
X265354D01*
G01X254724Y206456D02*
X255905D01*
G01Y205275D02*
X254724D01*
G01X265354Y205236D02*
X264409D01*
G01Y204527D02*
X265354D01*
G01X254724Y204488D02*
X255905D01*
G01Y203307D02*
X254724D01*
G01X265354Y203267D02*
X264409D01*
G01Y202559D02*
X265354D01*
G01X254724Y202519D02*
X255905D01*
G01Y201338D02*
X254724D01*
G01X265354Y201299D02*
X264409D01*
G01Y200590D02*
X265354D01*
G01X254724Y200551D02*
X255905D01*
G01Y199370D02*
X254724D01*
G01X265354Y199330D02*
X264409D01*
G01Y198622D02*
X265354D01*
G01X254724Y198582D02*
X255905D01*
G01Y197401D02*
X254724D01*
G01X265354Y197362D02*
X264409D01*
G01Y196653D02*
X265354D01*
G01X254724Y196614D02*
X255905D01*
G01Y195433D02*
X254724D01*
G01X265354Y195393D02*
X264409D01*
G01X254724Y219055D02*
G03X254527Y218858I0J-197D01*
G01X254724Y221023D02*
G03X254527Y220826I0J-197D01*
G01Y220433D02*
G03X254724Y220236I197J0D01*
G01Y222992D02*
G03X254527Y222795I0J-197D01*
G01Y222401D02*
G03X254724Y222204I197J0D01*
G01Y224960D02*
G03X254527Y224763I0J-197D01*
G01Y224370D02*
G03X254724Y224173I197J0D01*
G01Y226929D02*
G03X254527Y226732I0J-197D01*
G01Y226338D02*
G03X254724Y226141I197J0D01*
G01Y213149D02*
G03X254527Y212952I0J-197D01*
G01Y212559D02*
G03X254724Y212362I197J0D01*
G01Y215118D02*
G03X254527Y214921I0J-197D01*
G01Y214527D02*
G03X254724Y214330I197J0D01*
G01Y217086D02*
G03X254527Y216889I0J-197D01*
G01Y216496D02*
G03X254724Y216299I197J0D01*
G01X254527Y218464D02*
G03X254724Y218267I197J0D01*
G01X264409Y226181D02*
Y226889D01*
G01Y224212D02*
Y224921D01*
G01Y222244D02*
Y222952D01*
G01Y220275D02*
Y220984D01*
G01Y218307D02*
Y219015D01*
G01Y214370D02*
Y215078D01*
G01Y216338D02*
Y217047D01*
G01Y212401D02*
Y213110D01*
G01X254527Y212952D02*
Y212559D01*
G01Y214921D02*
Y214527D01*
G01Y216889D02*
Y216496D01*
G01Y218858D02*
Y218464D01*
G01Y220826D02*
Y220433D01*
G01Y222795D02*
Y222401D01*
G01Y224763D02*
Y224370D01*
G01Y226732D02*
Y226338D01*
G01X255826Y219104D02*
X255905Y219078D01*
G01Y226929D02*
X254724D01*
G01X265354Y226889D02*
X264409D01*
G01Y226181D02*
X265354D01*
G01X254724Y226141D02*
X255905D01*
G01Y224960D02*
X254724D01*
G01X265354Y224921D02*
X264409D01*
G01Y224212D02*
X265354D01*
G01X254724Y224173D02*
X255905D01*
G01Y222992D02*
X254724D01*
G01X265354Y222952D02*
X264409D01*
G01Y222244D02*
X265354D01*
G01X254724Y222204D02*
X255905D01*
G01Y221023D02*
X254724D01*
G01X265354Y220984D02*
X264409D01*
G01Y220275D02*
X265354D01*
G01X254724Y220236D02*
X255905D01*
G01X254842Y219104D02*
X255826D01*
G01X265354Y219015D02*
X264409D01*
G01Y218307D02*
X265354D01*
G01X254724Y218267D02*
X255905D01*
G01Y217086D02*
X254724D01*
G01X265354Y217047D02*
X264409D01*
G01Y216338D02*
X265354D01*
G01X254724Y216299D02*
X255905D01*
G01Y215118D02*
X254724D01*
G01X265354Y215078D02*
X264409D01*
G01Y214370D02*
X265354D01*
G01X254724Y214330D02*
X255905D01*
G01Y213149D02*
X254724D01*
G01X265354Y213110D02*
X264409D01*
G01Y212401D02*
X265354D01*
G01X254724Y212362D02*
X255905D01*
G01X254721Y219063D02*
X254842Y219104D01*
G01X254724Y228897D02*
G03X254527Y228700I0J-197D01*
G01Y228307D02*
G03X254724Y228110I197J0D01*
G01Y230866D02*
G03X254527Y230669I0J-197D01*
G01Y230275D02*
G03X254724Y230078I197J0D01*
G01Y232834D02*
G03X254527Y232637I0J-197D01*
G01Y232244D02*
G03X254724Y232047I197J0D01*
G01Y234803D02*
G03X254527Y234606I0J-197D01*
G01Y234212D02*
G03X254724Y234015I197J0D01*
G01Y236771D02*
G03X254527Y236574I0J-197D01*
G01Y236181D02*
G03X254724Y235984I197J0D01*
G01Y238740D02*
G03X254527Y238543I0J-197D01*
G01Y238149D02*
G03X254724Y237952I197J0D01*
G01Y240708D02*
G03X254527Y240511I0J-197D01*
G01Y240118D02*
G03X254724Y239921I197J0D01*
G01Y242677D02*
G03X254527Y242480I0J-197D01*
G01Y242086D02*
G03X254724Y241889I197J0D01*
G01X254527Y244055D02*
G03X254724Y243858I197J0D01*
G01X269567Y231181D02*
G03X270354Y230393I787J-1D01*
G01X273030Y239921D02*
X270551Y240840D01*
G01Y242283D02*
Y242677D01*
G01Y240840D02*
Y241365D01*
G01Y239527D02*
Y239921D01*
G01X269567Y250826D02*
Y231181D01*
G01X264409Y243897D02*
Y244606D01*
G01Y241929D02*
Y242637D01*
G01Y239960D02*
Y240669D01*
G01Y237992D02*
Y238700D01*
G01Y236023D02*
Y236732D01*
G01Y234055D02*
Y234763D01*
G01Y232086D02*
Y232795D01*
G01Y230118D02*
Y230826D01*
G01Y228149D02*
Y228858D01*
G01X254527Y228700D02*
Y228307D01*
G01Y230669D02*
Y230275D01*
G01Y232637D02*
Y232244D01*
G01Y234606D02*
Y234212D01*
G01Y236574D02*
Y236181D01*
G01Y238543D02*
Y238149D01*
G01Y240511D02*
Y240118D01*
G01Y242480D02*
Y242086D01*
G01Y244448D02*
Y244055D01*
G01X264409Y243897D02*
X265354D01*
G01X254724Y243858D02*
X255905D01*
G01X270551Y242677D02*
X273700D01*
G01X255905D02*
X254724D01*
G01X265354Y242637D02*
X264409D01*
G01X273030Y242283D02*
X270551D01*
G01X264409Y241929D02*
X265354D01*
G01X254724Y241889D02*
X255905D01*
G01Y240708D02*
X254724D01*
G01X265354Y240669D02*
X264409D01*
G01Y239960D02*
X265354D01*
G01X270551Y239921D02*
X273030D01*
G01X254724D02*
X255905D01*
G01X273700Y239527D02*
X270551D01*
G01X255905Y238740D02*
X254724D01*
G01X265354Y238700D02*
X264409D01*
G01Y237992D02*
X265354D01*
G01X254724Y237952D02*
X255905D01*
G01Y236771D02*
X254724D01*
G01X265354Y236732D02*
X264409D01*
G01Y236023D02*
X265354D01*
G01X254724Y235984D02*
X255905D01*
G01Y234803D02*
X254724D01*
G01X265354Y234763D02*
X264409D01*
G01Y234055D02*
X265354D01*
G01X254724Y234015D02*
X255905D01*
G01Y232834D02*
X254724D01*
G01X265354Y232795D02*
X264409D01*
G01Y232086D02*
X265354D01*
G01X254724Y232047D02*
X255905D01*
G01Y230866D02*
X254724D01*
G01X265354Y230826D02*
X264409D01*
G01X270354Y230393D02*
X279212D01*
G01X264409Y230118D02*
X265354D01*
G01X254724Y230078D02*
X255905D01*
G01Y228897D02*
X254724D01*
G01X265354Y228858D02*
X264409D01*
G01Y228149D02*
X265354D01*
G01X254724Y228110D02*
X255905D01*
G01X270551Y241365D02*
X273030Y242283D01*
G01X254724Y244645D02*
G03X254527Y244448I0J-197D01*
G01X254724Y246614D02*
G03X254527Y246417I0J-197D01*
G01Y246023D02*
G03X254724Y245826I197J0D01*
G01Y248582D02*
G03X254527Y248385I0J-197D01*
G01Y247992D02*
G03X254724Y247795I197J0D01*
G01X270354Y251614D02*
G03X269567Y250826I0J-787D01*
G01X261417Y253602D02*
G03X262598Y252421I1181J0D01*
G01X266535Y259055D02*
Y256063D01*
G01X265354D02*
Y253602D01*
G01X264409Y247834D02*
Y248543D01*
G01Y245866D02*
Y246574D01*
G01X261417Y256063D02*
Y253602D01*
G01X266535Y257086D02*
X319094D01*
G01X255905Y256063D02*
X287204D01*
G01X261417Y253602D02*
X265354D01*
G01Y252421D02*
X262598D01*
G01X279212Y251614D02*
X270354D01*
G01X254527Y246417D02*
Y246023D01*
G01Y248385D02*
Y247992D01*
G01X255905Y248582D02*
X254724D01*
G01X265354Y248543D02*
X264409D01*
G01Y247834D02*
X265354D01*
G01X254724Y247795D02*
X255905D01*
G01Y246614D02*
X254724D01*
G01X265354Y246574D02*
X264409D01*
G01Y245866D02*
X265354D01*
G01X254724Y245826D02*
X255905D01*
G01Y244645D02*
X254724D01*
G01X265354Y244606D02*
X264409D01*
G01X311614Y320118D02*
X264370D01*
G01D02*
Y363425D01*
G01X262196Y371299D02*
X460244D01*
G01X262196D02*
G03Y363425I0J-3937D01*
G01X264496Y619690D02*
Y602367D01*
G01X286300Y67283D02*
G03X286497Y67480I0J197D01*
G01Y67874D02*
G03X286300Y68070I-197J-1D01*
G01Y69252D02*
G03X286497Y69448I0J197D01*
G01Y69842D02*
G03X286300Y70039I-197J0D01*
G01Y71220D02*
G03X286497Y71417I0J197D01*
G01Y71811D02*
G03X286300Y72008I-197J0D01*
G01Y73189D02*
G03X286497Y73385I0J197D01*
G01Y73779D02*
G03X286300Y73976I-197J0D01*
G01Y75157D02*
G03X286497Y75354I0J197D01*
G01Y75748D02*
G03X286300Y75945I-197J0D01*
G01X286497Y67874D02*
Y67480D01*
G01Y69842D02*
Y69448D01*
G01Y71811D02*
Y71417D01*
G01Y73779D02*
Y73385D01*
G01Y75748D02*
Y75354D01*
G01X285039Y144252D02*
Y63937D01*
G01X282677Y144252D02*
Y63937D01*
G01X285039Y75945D02*
X286300D01*
G01X285039Y75157D02*
X286300D01*
G01X285039Y73976D02*
X286300D01*
G01X285039Y73189D02*
X286300D01*
G01X285039Y72008D02*
X286300D01*
G01X285039Y71220D02*
X286300D01*
G01X285039Y70039D02*
X286300D01*
G01X285039Y69252D02*
X286300D01*
G01X285039Y68070D02*
X286300D01*
G01X285039Y67283D02*
X286300D01*
G01X285039Y65708D02*
X287992D01*
G01X285039Y65118D02*
X287992D01*
G01X282677Y63937D02*
X287992D01*
G01X286300Y90905D02*
G03X286497Y91102I0J197D01*
G01Y91496D02*
G03X286300Y91693I-197J0D01*
G01Y92874D02*
G03X286497Y93070I0J197D01*
G01Y93464D02*
G03X286300Y93661I-197J0D01*
G01Y94842D02*
G03X286497Y95039I0J197D01*
G01Y95433D02*
G03X286300Y95630I-197J0D01*
G01Y85000D02*
G03X286497Y85196I0J197D01*
G01Y85590D02*
G03X286300Y85787I-197J0D01*
G01Y86968D02*
G03X286497Y87165I0J197D01*
G01Y87559D02*
G03X286300Y87756I-197J0D01*
G01Y88937D02*
G03X286497Y89133I0J197D01*
G01Y89527D02*
G03X286300Y89724I-197J0D01*
G01X286497Y85590D02*
Y85196D01*
G01Y87559D02*
Y87165D01*
G01Y89527D02*
Y89133D01*
G01Y91496D02*
Y91102D01*
G01Y93464D02*
Y93070D01*
G01Y95433D02*
Y95039D01*
G01X285039Y95630D02*
X286300D01*
G01X285039Y94842D02*
X286300D01*
G01X285039Y93661D02*
X286300D01*
G01X285039Y92874D02*
X286300D01*
G01X285039Y91693D02*
X286300D01*
G01X285039Y90905D02*
X286300D01*
G01X285039Y89724D02*
X286300D01*
G01X285039Y88937D02*
X286300D01*
G01X285039Y87756D02*
X286300D01*
G01X285039Y86968D02*
X286300D01*
G01X285039Y85787D02*
X286300D01*
G01X285039Y85000D02*
X286300D01*
G01Y96811D02*
G03X286497Y97008I0J197D01*
G01Y97401D02*
G03X286300Y97598I-197J0D01*
G01Y98779D02*
G03X286497Y98976I0J197D01*
G01Y99370D02*
G03X286300Y99567I-197J0D01*
G01Y100748D02*
G03X286497Y100945I0J197D01*
G01Y101338D02*
G03X286300Y101535I-197J0D01*
G01Y102716D02*
G03X286497Y102913I0J197D01*
G01Y103307D02*
G03X286300Y103504I-197J0D01*
G01Y104685D02*
G03X286497Y104882I0J197D01*
G01Y105275D02*
G03X286300Y105472I-197J0D01*
G01Y106653D02*
G03X286497Y106850I0J197D01*
G01Y107244D02*
G03X286300Y107441I-197J0D01*
G01Y108622D02*
G03X286497Y108819I0J197D01*
G01Y109212D02*
G03X286300Y109409I-197J0D01*
G01Y110590D02*
G03X286497Y110787I0J197D01*
G01Y111181D02*
G03X286300Y111378I-197J0D01*
G01X286497Y97401D02*
Y97008D01*
G01Y99370D02*
Y98976D01*
G01Y101338D02*
Y100945D01*
G01Y103307D02*
Y102913D01*
G01Y105275D02*
Y104882D01*
G01Y107244D02*
Y106850D01*
G01Y109212D02*
Y108819D01*
G01Y111181D02*
Y110787D01*
G01X285039Y111378D02*
X286300D01*
G01X285039Y110590D02*
X286300D01*
G01X285039Y109409D02*
X286300D01*
G01X285039Y108622D02*
X286300D01*
G01X285039Y107441D02*
X286300D01*
G01X285039Y106653D02*
X286300D01*
G01X285039Y105472D02*
X286300D01*
G01X285039Y104685D02*
X286300D01*
G01X285039Y103504D02*
X286300D01*
G01X285039Y102716D02*
X286300D01*
G01X285039Y101535D02*
X286300D01*
G01X285039Y100748D02*
X286300D01*
G01X285039Y99567D02*
X286300D01*
G01X285039Y98779D02*
X286300D01*
G01X285039Y97598D02*
X286300D01*
G01X285039Y96811D02*
X286300D01*
G01Y112559D02*
G03X286497Y112756I0J197D01*
G01Y113149D02*
G03X286300Y113346I-197J0D01*
G01Y114527D02*
G03X286497Y114724I0J197D01*
G01Y115118D02*
G03X286300Y115315I-197J0D01*
G01Y116496D02*
G03X286497Y116693I0J197D01*
G01Y117086D02*
G03X286300Y117283I-197J0D01*
G01Y118464D02*
G03X286497Y118661I0J197D01*
G01Y119055D02*
G03X286300Y119252I-197J0D01*
G01Y120433D02*
G03X286497Y120630I0J197D01*
G01Y121023D02*
G03X286300Y121220I-197J0D01*
G01Y122401D02*
G03X286497Y122598I0J197D01*
G01Y122992D02*
G03X286300Y123189I-197J0D01*
G01Y124370D02*
G03X286497Y124567I0J197D01*
G01Y124960D02*
G03X286300Y125157I-197J0D01*
G01Y126338D02*
G03X286497Y126535I0J197D01*
G01Y126929D02*
G03X286300Y127126I-197J0D01*
G01Y128307D02*
G03X286497Y128504I0J197D01*
G01X279212Y121732D02*
G03X280000Y122519I1J787D01*
G01X277663Y123976D02*
X277463Y123845D01*
G01X277261Y124108D02*
X277463Y124239D01*
G01X277798Y124108D02*
X277663Y123976D01*
G01X277463Y124239D02*
X277596Y124370D01*
G01X277730Y126601D02*
X277596Y126470D01*
G01X276256Y125289D02*
X276122Y125157D01*
G01X277395Y126732D02*
X277530Y126863D01*
G01X275921Y125420D02*
X276055Y125551D01*
G01X277865Y126798D02*
X277730Y126601D01*
G01X277865Y124239D02*
X277798Y124108D01*
G01X277530Y126863D02*
X277596Y126995D01*
G01X275854Y125289D02*
X275921Y125420D01*
G01X277932Y126995D02*
X277865Y126798D01*
G01X277932Y124501D02*
X277865Y124239D01*
G01X277596Y124370D02*
X277663Y124632D01*
G01X277596Y126995D02*
X277663Y127257D01*
G01X276122Y125157D02*
X276055Y124895D01*
G01X275787Y125026D02*
X275854Y125289D01*
G01X286497Y113149D02*
Y112756D01*
G01Y115118D02*
Y114724D01*
G01Y117086D02*
Y116693D01*
G01Y119055D02*
Y118661D01*
G01Y121023D02*
Y120630D01*
G01Y122992D02*
Y122598D01*
G01Y124960D02*
Y124567D01*
G01Y126929D02*
Y126535D01*
G01Y128897D02*
Y128504D01*
G01X280000Y122519D02*
Y142165D01*
G01X278937Y123189D02*
Y122861D01*
G01X277932Y125026D02*
Y124501D01*
G01Y127257D02*
Y126995D01*
G01Y128176D02*
Y127848D01*
G01X277865Y127519D02*
X277932Y127257D01*
G01X277663D02*
X277596Y127519D01*
G01X277463Y123845D02*
X277261Y123779D01*
G01X276457Y125420D02*
X276256Y125289D01*
G01X276055Y125551D02*
X276256Y125682D01*
G01X277663Y124632D02*
Y124895D01*
G01X276859Y128700D02*
Y130472D01*
G01X276457Y129029D02*
Y128700D01*
G01X276055Y124895D02*
Y124632D01*
G01X275787Y126338D02*
Y126667D01*
G01Y127848D02*
Y128176D01*
G01Y124501D02*
Y125026D01*
G01Y122861D02*
Y123189D01*
G01X277865Y125289D02*
X277932Y125026D01*
G01X277663Y124895D02*
X277596Y125157D01*
G01X276055Y124632D02*
X276122Y124370D01*
G01X275854Y124239D02*
X275787Y124501D01*
G01X277596Y126470D02*
X277395Y126404D01*
G01X277798Y125420D02*
X277865Y125289D01*
G01X275921Y124108D02*
X275854Y124239D01*
G01X277730Y127716D02*
X277865Y127519D01*
G01X277596D02*
X277463Y127716D01*
G01X277596Y127848D02*
X277730Y127716D01*
G01X277463D02*
X277328Y127848D01*
G01X277663Y125551D02*
X277798Y125420D01*
G01X277596Y125157D02*
X277463Y125289D01*
G01X276122Y124370D02*
X276256Y124239D01*
G01X276055Y123976D02*
X275921Y124108D01*
G01X277463Y125682D02*
X277663Y125551D01*
G01X277463Y125289D02*
X277261Y125420D01*
G01X276256Y124239D02*
X276457Y124108D01*
G01X276256Y123845D02*
X276055Y123976D01*
G01X277261Y125748D02*
X277463Y125682D01*
G01X276725Y123714D02*
X276256Y123845D01*
G01X276457Y128700D02*
X276189Y128766D01*
G01X276993Y125813D02*
X277261Y125748D01*
G01Y125420D02*
X276993Y125485D01*
G01X276457Y124108D02*
X276725Y124042D01*
G01X277128Y128700D02*
X276859D01*
G01X285039Y128307D02*
X286300D01*
G01X275787Y128176D02*
X277932D01*
G01X277328Y127848D02*
X275787D01*
G01X277932D02*
X277596D01*
G01X285039Y127126D02*
X286300D01*
G01X275787Y126667D02*
X277060D01*
G01X285039Y126338D02*
X286300D01*
G01X277060D02*
X275787D01*
G01X276725Y125813D02*
X276993D01*
G01Y125485D02*
X276725D01*
G01X285039Y125157D02*
X286300D01*
G01X285039Y124370D02*
X286300D01*
G01X276725Y124042D02*
X276993D01*
G01Y123714D02*
X276725D01*
G01X285039Y123189D02*
X286300D01*
G01X275787D02*
X278937D01*
G01Y122861D02*
X275787D01*
G01X285039Y122401D02*
X286300D01*
G01X285039Y121220D02*
X286300D01*
G01X285039Y120433D02*
X286300D01*
G01X285039Y119252D02*
X286300D01*
G01X285039Y118464D02*
X286300D01*
G01X285039Y117283D02*
X286300D01*
G01X285039Y116496D02*
X286300D01*
G01X285039Y115315D02*
X286300D01*
G01X285039Y114527D02*
X286300D01*
G01X285039Y113346D02*
X286300D01*
G01X285039Y112559D02*
X286300D01*
G01X277060Y126667D02*
X277395Y126732D01*
G01Y126404D02*
X277060Y126338D01*
G01X277395Y128766D02*
X277128Y128700D01*
G01X276725Y125485D02*
X276457Y125420D01*
G01X276993Y124042D02*
X277261Y124108D01*
G01Y123779D02*
X276993Y123714D01*
G01X276256Y125682D02*
X276725Y125813D01*
G01X286497Y134803D02*
G03X286300Y135000I-197J0D01*
G01Y136181D02*
G03X286497Y136378I0J197D01*
G01Y136771D02*
G03X286300Y136968I-197J0D01*
G01Y138149D02*
G03X286497Y138346I0J197D01*
G01Y138740D02*
G03X286300Y138937I-197J0D01*
G01Y140118D02*
G03X286497Y140315I0J197D01*
G01Y140708D02*
G03X286300Y140905I-197J0D01*
G01X286497Y128897D02*
G03X286300Y129094I-197J0D01*
G01Y130275D02*
G03X286497Y130472I0J197D01*
G01Y130866D02*
G03X286300Y131063I-197J0D01*
G01Y132244D02*
G03X286497Y132441I0J197D01*
G01Y132834D02*
G03X286300Y133031I-197J0D01*
G01Y134212D02*
G03X286497Y134409I0J197D01*
G01X280000Y142165D02*
G03X279212Y142952I-787J0D01*
G01X277663Y128963D02*
X277395Y128766D01*
G01X277730Y131588D02*
X277596Y131456D01*
G01X276390Y130341D02*
X276189Y130144D01*
G01X277395Y131719D02*
X277530Y131850D01*
G01X276055Y130472D02*
X276189Y130604D01*
G01X277730Y134015D02*
X277530Y133819D01*
G01X277865Y136574D02*
X277730Y136443D01*
G01X277530Y136706D02*
X277596Y136771D01*
G01X275921Y135262D02*
X276055Y135393D01*
G01X277865Y137624D02*
X277663Y137428D01*
G01X277530Y137756D02*
X277596Y137821D01*
G01X277463Y129160D02*
X277596Y129357D01*
G01X277865Y131785D02*
X277730Y131588D01*
G01X275921Y130275D02*
X276055Y130472D01*
G01X277865Y134212D02*
X277730Y134015D01*
G01X276323Y135328D02*
X276189Y135131D01*
G01X277865Y129291D02*
X277663Y128963D01*
G01X277530Y131850D02*
X277596Y131982D01*
G01X276189Y130144D02*
X276122Y130013D01*
G01X277463Y134212D02*
X277596Y134475D01*
G01Y136771D02*
X277663Y136903D01*
G01X277596Y137821D02*
X277663Y137952D01*
G01X275854Y135131D02*
X275921Y135262D01*
G01X277932Y131982D02*
X277865Y131785D01*
G01X275854Y130078D02*
X275921Y130275D01*
G01X277932Y136771D02*
X277865Y136574D01*
G01X277932Y137821D02*
X277865Y137624D01*
G01X277596Y131982D02*
X277663Y132244D01*
G01X277932Y134475D02*
X277865Y134212D01*
G01X276122Y130013D02*
X276055Y129750D01*
G01X276189Y135131D02*
X276122Y134869D01*
G01X275787D02*
X275854Y135131D01*
G01X277932Y129685D02*
X277865Y129291D01*
G01X277596Y129357D02*
X277663Y129750D01*
G01X275787Y129685D02*
X275854Y130078D01*
G01X286497Y130866D02*
Y130472D01*
G01Y132834D02*
Y132441D01*
G01Y134803D02*
Y134409D01*
G01Y136771D02*
Y136378D01*
G01Y138740D02*
Y138346D01*
G01Y140708D02*
Y140315D01*
G01X278937Y133163D02*
Y132834D01*
G01Y140840D02*
Y140315D01*
G01X277932Y132244D02*
Y131982D01*
G01Y134869D02*
Y134475D01*
G01Y135787D02*
Y135459D01*
G01Y137034D02*
Y136771D01*
G01Y138084D02*
Y137821D01*
G01Y138740D02*
Y138412D01*
G01X276055Y129750D02*
X276122Y129291D01*
G01X275854Y129226D02*
X275787Y129685D01*
G01X277865Y130078D02*
X277932Y129685D01*
G01X277865Y135131D02*
X277932Y134869D01*
G01X277596D02*
X277530Y135131D01*
G01X277865Y132506D02*
X277932Y132244D01*
G01X277663D02*
X277596Y132506D01*
G01X277663Y129750D02*
X277596Y130013D01*
G01X276122Y134606D02*
X276189Y134344D01*
G01X276524Y130407D02*
X276390Y130341D01*
G01X276189Y130604D02*
X276457Y130735D01*
G01X277596Y131456D02*
X277463Y131391D01*
G01X277530Y133819D02*
X277395Y133753D01*
G01X277261Y129029D02*
X277463Y129160D01*
G01X277261Y134081D02*
X277463Y134212D01*
G01X276524Y135459D02*
X276323Y135328D01*
G01X277663Y137952D02*
Y138084D01*
G01Y136903D02*
Y137100D01*
G01X277596Y134475D02*
Y134869D01*
G01X277128Y130407D02*
Y129029D01*
G01X276859Y141168D02*
Y139987D01*
G01X276591Y139921D02*
Y141233D01*
G01X276122Y134869D02*
Y134606D01*
G01X275787Y141496D02*
Y141889D01*
G01Y137362D02*
Y137690D01*
G01Y138412D02*
Y138740D01*
G01Y139265D02*
Y139659D01*
G01Y136312D02*
Y136640D01*
G01Y132834D02*
Y133163D01*
G01Y134475D02*
Y134869D01*
G01Y131325D02*
Y131653D01*
G01X274715Y135459D02*
Y135787D01*
G01X273700Y131456D02*
Y130866D01*
G01Y134015D02*
Y133425D01*
G01X275854Y134212D02*
X275787Y134475D01*
G01X277865Y138281D02*
X277932Y138084D01*
G01X277663D02*
X277596Y138281D01*
G01X277865Y137231D02*
X277932Y137034D01*
G01X277798Y130275D02*
X277865Y130078D01*
G01X277663Y137100D02*
X277596Y137231D01*
G01X277798Y135262D02*
X277865Y135131D01*
G01X276725Y130472D02*
X276524Y130407D01*
G01X277060Y134015D02*
X277261Y134081D01*
G01X276859Y139987D02*
X278669Y140577D01*
G01X275787Y139659D02*
X276591Y139921D01*
G01X278937Y140315D02*
X275787Y139265D01*
G01X273700Y133425D02*
X270886Y132441D01*
G01X277730Y136443D02*
X277395Y136312D01*
G01X276055Y135393D02*
X276189Y135459D01*
G01X277395Y136640D02*
X277530Y136706D01*
G01X277395Y137690D02*
X277530Y137756D01*
G01X277596Y130013D02*
X277530Y130144D01*
G01X275988Y128963D02*
X275854Y129226D01*
G01X277530Y135131D02*
X277395Y135328D01*
G01X277730Y132703D02*
X277865Y132506D01*
G01X277596D02*
X277463Y132703D01*
G01X276189Y134344D02*
X276323Y134147D01*
G01X275988Y134015D02*
X275854Y134212D01*
G01X277663Y130472D02*
X277798Y130275D01*
G01X276122Y129291D02*
X276256Y129094D01*
G01X277730Y138412D02*
X277865Y138281D01*
G01X277596D02*
X277463Y138412D01*
G01X277663Y137428D02*
X277865Y137231D01*
G01X277596D02*
X277530Y137296D01*
G01X277663Y135393D02*
X277798Y135262D01*
G01X277596Y132834D02*
X277730Y132703D01*
G01X277463D02*
X277328Y132834D01*
G01X277530Y130604D02*
X277663Y130472D01*
G01X277530Y130144D02*
X277328Y130341D01*
G01X276189Y128766D02*
X275988Y128963D01*
G01X276323Y133753D02*
X275988Y134015D01*
G01X277395Y135328D02*
X277195Y135459D01*
G01X277530Y137296D02*
X277395Y137362D01*
G01X277530Y135459D02*
X277663Y135393D01*
G01X276323Y134147D02*
X276457Y134081D01*
G01X277261Y130735D02*
X277530Y130604D01*
G01X277328Y130341D02*
X277195Y130407D01*
G01X275787Y141889D02*
X278937Y140840D01*
G01X278669Y140577D02*
X276859Y141168D01*
G01X276591Y141233D02*
X275787Y141496D01*
G01X276457Y134081D02*
X276658Y134015D01*
G01X270886Y132441D02*
X273700Y131456D01*
G01X276256Y129094D02*
X276457Y129029D01*
G01X276591Y133687D02*
X276323Y133753D01*
G01X276859Y130800D02*
X277261Y130735D01*
G01X287992Y144252D02*
X282677D01*
G01X287992Y143070D02*
X285039D01*
G01Y142480D02*
X287992D01*
G01X285039Y140905D02*
X286300D01*
G01X285039Y140118D02*
X286300D01*
G01X285039Y138937D02*
X286300D01*
G01X275787Y138740D02*
X277932D01*
G01X277463Y138412D02*
X275787D01*
G01X277932D02*
X277730D01*
G01X285039Y138149D02*
X286300D01*
G01X275787Y137690D02*
X277395D01*
G01Y137362D02*
X275787D01*
G01X285039Y136968D02*
X286300D01*
G01X275787Y136640D02*
X277395D01*
G01Y136312D02*
X275787D01*
G01X285039Y136181D02*
X286300D01*
G01X274715Y135787D02*
X277932D01*
G01X276189Y135459D02*
X274715D01*
G01X277195D02*
X276524D01*
G01X277932D02*
X277530D01*
G01X285039Y135000D02*
X286300D01*
G01X285039Y134212D02*
X286300D01*
G01X276658Y134015D02*
X277060D01*
G01X277128Y133687D02*
X276591D01*
G01X275787Y133163D02*
X278937D01*
G01X285039Y133031D02*
X286300D01*
G01X277328Y132834D02*
X275787D01*
G01X278937D02*
X277596D01*
G01X285039Y132244D02*
X286300D01*
G01X275787Y131653D02*
X277128D01*
G01Y131325D02*
X275787D01*
G01X285039Y131063D02*
X286300D01*
G01X276859Y130472D02*
X276725D01*
G01X277195Y130407D02*
X277128D01*
G01X285039Y130275D02*
X286300D01*
G01X285039Y129094D02*
X286300D01*
G01X277128Y129029D02*
X277261D01*
G01X276457Y130735D02*
X276859Y130800D01*
G01X277463Y131391D02*
X277128Y131325D01*
G01X277395Y133753D02*
X277128Y133687D01*
G01Y131653D02*
X277395Y131719D01*
G01X286300Y175945D02*
G03X286497Y176141I0J197D01*
G01Y176535D02*
G03X286300Y176732I-197J0D01*
G01Y177913D02*
G03X286497Y178110I0J197D01*
G01Y176535D02*
Y176141D01*
G01Y178504D02*
Y178110D01*
G01X285039Y252913D02*
Y172598D01*
G01X282677Y252913D02*
Y172598D01*
G01X285039Y177913D02*
X286300D01*
G01X285039Y176732D02*
X286300D01*
G01X285039Y175945D02*
X286300D01*
G01X285039Y174370D02*
X287992D01*
G01X285039Y173779D02*
X287992D01*
G01X282677Y172598D02*
X287992D01*
G01X286300Y179882D02*
G03X286497Y180078I0J197D01*
G01Y180472D02*
G03X286300Y180669I-197J0D01*
G01Y181850D02*
G03X286497Y182047I0J197D01*
G01Y182441D02*
G03X286300Y182637I-197J-1D01*
G01Y183819D02*
G03X286497Y184015I0J197D01*
G01Y184409D02*
G03X286300Y184606I-197J0D01*
G01Y193661D02*
G03X286497Y193858I0J197D01*
G01Y194252D02*
G03X286300Y194448I-197J-1D01*
G01X286497Y178504D02*
G03X286300Y178700I-197J-1D01*
G01X286497Y180472D02*
Y180078D01*
G01Y182441D02*
Y182047D01*
G01Y184409D02*
Y184015D01*
G01Y194252D02*
Y193858D01*
G01X285039Y194448D02*
X286300D01*
G01X285039Y193661D02*
X286300D01*
G01X285039Y184606D02*
X286300D01*
G01X285039Y183819D02*
X286300D01*
G01X285039Y182637D02*
X286300D01*
G01X285039Y181850D02*
X286300D01*
G01X285039Y180669D02*
X286300D01*
G01X285039Y179882D02*
X286300D01*
G01X285039Y178700D02*
X286300D01*
G01Y195630D02*
G03X286497Y195826I0J197D01*
G01Y196220D02*
G03X286300Y196417I-197J0D01*
G01Y197598D02*
G03X286497Y197795I0J197D01*
G01Y198189D02*
G03X286300Y198385I-197J-1D01*
G01Y199567D02*
G03X286497Y199763I0J197D01*
G01Y200157D02*
G03X286300Y200354I-197J0D01*
G01Y201535D02*
G03X286497Y201732I0J197D01*
G01Y202126D02*
G03X286300Y202322I-197J-1D01*
G01Y203504D02*
G03X286497Y203700I0J197D01*
G01Y204094D02*
G03X286300Y204291I-197J0D01*
G01Y205472D02*
G03X286497Y205669I0J197D01*
G01Y206063D02*
G03X286300Y206259I-197J-1D01*
G01Y207441D02*
G03X286497Y207637I0J197D01*
G01Y208031D02*
G03X286300Y208228I-197J0D01*
G01Y209409D02*
G03X286497Y209606I0J197D01*
G01Y210000D02*
G03X286300Y210196I-197J-1D01*
G01X286497Y196220D02*
Y195826D01*
G01Y198189D02*
Y197795D01*
G01Y200157D02*
Y199763D01*
G01Y202126D02*
Y201732D01*
G01Y204094D02*
Y203700D01*
G01Y206063D02*
Y205669D01*
G01Y208031D02*
Y207637D01*
G01Y210000D02*
Y209606D01*
G01X285039Y210196D02*
X286300D01*
G01X285039Y209409D02*
X286300D01*
G01X285039Y208228D02*
X286300D01*
G01X285039Y207441D02*
X286300D01*
G01X285039Y206259D02*
X286300D01*
G01X285039Y205472D02*
X286300D01*
G01X285039Y204291D02*
X286300D01*
G01X285039Y203504D02*
X286300D01*
G01X285039Y202322D02*
X286300D01*
G01X285039Y201535D02*
X286300D01*
G01X285039Y200354D02*
X286300D01*
G01X285039Y199567D02*
X286300D01*
G01X285039Y198385D02*
X286300D01*
G01X285039Y197598D02*
X286300D01*
G01X285039Y196417D02*
X286300D01*
G01X285039Y195630D02*
X286300D01*
G01Y221220D02*
G03X286497Y221417I0J197D01*
G01Y221811D02*
G03X286300Y222008I-197J0D01*
G01Y223189D02*
G03X286497Y223385I0J197D01*
G01Y223779D02*
G03X286300Y223976I-197J0D01*
G01Y225157D02*
G03X286497Y225354I0J197D01*
G01Y225748D02*
G03X286300Y225945I-197J0D01*
G01Y227126D02*
G03X286497Y227322I0J197D01*
G01Y227716D02*
G03X286300Y227913I-197J0D01*
G01X286497Y217874D02*
G03X286300Y218070I-197J-1D01*
G01Y219252D02*
G03X286497Y219448I0J197D01*
G01Y219842D02*
G03X286300Y220039I-197J0D01*
G01Y211378D02*
G03X286497Y211574I0J197D01*
G01Y211968D02*
G03X286300Y212165I-197J0D01*
G01Y213346D02*
G03X286497Y213543I0J197D01*
G01Y213937D02*
G03X286300Y214133I-197J-1D01*
G01Y215315D02*
G03X286497Y215511I0J197D01*
G01Y215905D02*
G03X286300Y216102I-197J0D01*
G01Y217283D02*
G03X286497Y217480I0J197D01*
G01Y211968D02*
Y211574D01*
G01Y213937D02*
Y213543D01*
G01Y215905D02*
Y215511D01*
G01Y217874D02*
Y217480D01*
G01Y221811D02*
Y221417D01*
G01Y219842D02*
Y219448D01*
G01Y223779D02*
Y223385D01*
G01Y225748D02*
Y225354D01*
G01Y227716D02*
Y227322D01*
G01X285039Y227126D02*
X286300D01*
G01X285039Y225945D02*
X286300D01*
G01X285039Y225157D02*
X286300D01*
G01X285039Y223976D02*
X286300D01*
G01X285039Y223189D02*
X286300D01*
G01X285039Y222008D02*
X286300D01*
G01X285039Y221220D02*
X286300D01*
G01X285039Y220039D02*
X286300D01*
G01X285039Y219252D02*
X286300D01*
G01X285039Y218070D02*
X286300D01*
G01X285039Y217283D02*
X286300D01*
G01X285039Y216102D02*
X286300D01*
G01X285039Y215315D02*
X286300D01*
G01X285039Y214133D02*
X286300D01*
G01X285039Y213346D02*
X286300D01*
G01X285039Y212165D02*
X286300D01*
G01X285039Y211378D02*
X286300D01*
G01Y229094D02*
G03X286497Y229291I0J197D01*
G01Y229685D02*
G03X286300Y229882I-197J0D01*
G01Y231063D02*
G03X286497Y231259I0J197D01*
G01Y231653D02*
G03X286300Y231850I-197J0D01*
G01Y233031D02*
G03X286497Y233228I0J197D01*
G01Y233622D02*
G03X286300Y233819I-197J0D01*
G01Y235000D02*
G03X286497Y235196I0J197D01*
G01Y235590D02*
G03X286300Y235787I-197J0D01*
G01Y236968D02*
G03X286497Y237165I0J197D01*
G01Y237559D02*
G03X286300Y237756I-197J0D01*
G01Y238937D02*
G03X286497Y239133I0J197D01*
G01Y239527D02*
G03X286300Y239724I-197J0D01*
G01Y240905D02*
G03X286497Y241102I0J197D01*
G01Y241496D02*
G03X286300Y241693I-197J0D01*
G01Y242874D02*
G03X286497Y243070I0J197D01*
G01Y243464D02*
G03X286300Y243661I-197J0D01*
G01X279212Y230393D02*
G03X280000Y231181I0J788D01*
G01X277798Y243924D02*
X277865Y243793D01*
G01X277530D02*
X277395Y243989D01*
G01X276055Y238412D02*
X276122Y237952D01*
G01X275854Y237887D02*
X275787Y238346D01*
G01X277865Y238740D02*
X277932Y238346D01*
G01X277865Y243793D02*
X277932Y243530D01*
G01X277596D02*
X277530Y243793D01*
G01X277865Y241168D02*
X277932Y240905D01*
G01X277663D02*
X277596Y241168D01*
G01X277663Y238412D02*
X277596Y238674D01*
G01X276122Y243267D02*
X276189Y243005D01*
G01X277865Y236181D02*
X277932Y235919D01*
G01X277663D02*
X277596Y236181D01*
G01X275854Y242874D02*
X275787Y243136D01*
G01X277865Y233950D02*
X277932Y233687D01*
G01X277663Y233556D02*
X277596Y233819D01*
G01X276055Y233294D02*
X276122Y233031D01*
G01X275854Y232900D02*
X275787Y233163D01*
G01X277798Y238937D02*
X277865Y238740D01*
G01X277596Y238674D02*
X277530Y238806D01*
G01X275988Y237624D02*
X275854Y237887D01*
G01X277798Y234081D02*
X277865Y233950D01*
G01X275921Y232769D02*
X275854Y232900D01*
G01X277730Y241365D02*
X277865Y241168D01*
G01X277596D02*
X277463Y241365D01*
G01X276189Y243005D02*
X276323Y242808D01*
G01X275988Y242677D02*
X275854Y242874D01*
G01X277663Y239133D02*
X277798Y238937D01*
G01X277730Y236378D02*
X277865Y236181D01*
G01X277596D02*
X277463Y236378D01*
G01X276122Y237952D02*
X276256Y237756D01*
G01X277663Y244055D02*
X277798Y243924D01*
G01X277596Y241496D02*
X277730Y241365D01*
G01X277463D02*
X277328Y241496D01*
G01X277530Y239265D02*
X277663Y239133D01*
G01X277530Y238806D02*
X277328Y239002D01*
G01X277596Y236509D02*
X277730Y236378D01*
G01X277463D02*
X277328Y236509D01*
G01X276189Y237428D02*
X275988Y237624D01*
G01X277663Y234212D02*
X277798Y234081D01*
G01X277596Y233819D02*
X277463Y233950D01*
G01X276122Y233031D02*
X276256Y232900D01*
G01X276055Y232637D02*
X275921Y232769D01*
G01X276323Y242415D02*
X275988Y242677D01*
G01X277395Y243989D02*
X277195Y244120D01*
G01X286497Y229685D02*
Y229291D01*
G01Y231653D02*
Y231259D01*
G01Y233622D02*
Y233228D01*
G01Y235590D02*
Y235196D01*
G01Y237559D02*
Y237165D01*
G01Y239527D02*
Y239133D01*
G01Y241496D02*
Y241102D01*
G01Y243464D02*
Y243070D01*
G01X280000Y231181D02*
Y250826D01*
G01X278937Y231850D02*
Y231522D01*
G01Y241824D02*
Y241496D01*
G01X277932Y233687D02*
Y233163D01*
G01Y235919D02*
Y235656D01*
G01Y236837D02*
Y236509D01*
G01Y240905D02*
Y240643D01*
G01Y243530D02*
Y243136D01*
G01Y244448D02*
Y244120D01*
G01X277463Y234344D02*
X277663Y234212D01*
G01X277463Y233950D02*
X277261Y234081D01*
G01X276256Y232900D02*
X276457Y232769D01*
G01X276256Y232506D02*
X276055Y232637D01*
G01X277530Y244120D02*
X277663Y244055D01*
G01X276323Y242808D02*
X276457Y242743D01*
G01X277261Y239396D02*
X277530Y239265D01*
G01X277328Y239002D02*
X277195Y239068D01*
G01X270886Y241102D02*
X273700Y240118D01*
G01X276457Y242743D02*
X276658Y242677D01*
G01X277932Y233163D02*
X277865Y232900D01*
G01X277596Y233031D02*
X277663Y233294D01*
G01X277596Y235656D02*
X277663Y235919D01*
G01X277932Y238346D02*
X277865Y237952D01*
G01X277596Y238018D02*
X277663Y238412D01*
G01X275787Y238346D02*
X275854Y238740D01*
G01X277663Y233294D02*
Y233556D01*
G01X277596Y243136D02*
Y243530D01*
G01X277128Y239068D02*
Y237690D01*
G01X276859Y237362D02*
Y239133D01*
G01X276457Y237690D02*
Y237362D01*
G01X276122Y243530D02*
Y243267D01*
G01X276055Y233556D02*
Y233294D01*
G01X275787Y243136D02*
Y243530D01*
G01Y241496D02*
Y241824D01*
G01Y239987D02*
Y240315D01*
G01Y236509D02*
Y236837D01*
G01Y233163D02*
Y233687D01*
G01Y235000D02*
Y235328D01*
G01Y231522D02*
Y231850D01*
G01X274715Y244120D02*
Y244448D01*
G01X273700Y240118D02*
Y239527D01*
G01Y242677D02*
Y242086D01*
G01X276256Y237756D02*
X276457Y237690D01*
G01X277261Y234409D02*
X277463Y234344D01*
G01X276725Y232375D02*
X276256Y232506D01*
G01X276591Y242349D02*
X276323Y242415D01*
G01X276457Y237362D02*
X276189Y237428D01*
G01X276993Y234475D02*
X277261Y234409D01*
G01Y234081D02*
X276993Y234147D01*
G01X276457Y232769D02*
X276725Y232703D01*
G01X276859Y239462D02*
X277261Y239396D01*
G01X277932Y235656D02*
X277865Y235459D01*
G01X277932Y240643D02*
X277865Y240446D01*
G01X275854Y238740D02*
X275921Y238937D01*
G01X276122Y233819D02*
X276055Y233556D01*
G01X277596Y240643D02*
X277663Y240905D01*
G01X275787Y233687D02*
X275854Y233950D01*
G01X277932Y243136D02*
X277865Y242874D01*
G01X276122Y238674D02*
X276055Y238412D01*
G01X276189Y243793D02*
X276122Y243530D01*
G01X275787D02*
X275854Y243793D01*
G01X276189Y244120D02*
X274715D01*
G01X277195D02*
X276524D01*
G01X277932D02*
X277530D01*
G01X285039Y243661D02*
X286300D01*
G01X285039Y242874D02*
X286300D01*
G01X276658Y242677D02*
X277060D01*
G01X277128Y242349D02*
X276591D01*
G01X275787Y241824D02*
X278937D01*
G01X285039Y241693D02*
X286300D01*
G01X277328Y241496D02*
X275787D01*
G01X278937D02*
X277596D01*
G01X285039Y240905D02*
X286300D01*
G01X275787Y240315D02*
X277128D01*
G01Y239987D02*
X275787D01*
G01X285039Y239724D02*
X286300D01*
G01X276859Y239133D02*
X276725D01*
G01X277195Y239068D02*
X277128D01*
G01X285039Y238937D02*
X286300D01*
G01X285039Y237756D02*
X286300D01*
G01X277128Y237690D02*
X277261D01*
G01X277128Y237362D02*
X276859D01*
G01X285039Y236968D02*
X286300D01*
G01X275787Y236837D02*
X277932D01*
G01X277328Y236509D02*
X275787D01*
G01X277932D02*
X277596D01*
G01X285039Y235787D02*
X286300D01*
G01X275787Y235328D02*
X277060D01*
G01X285039Y235000D02*
X286300D01*
G01X277060D02*
X275787D01*
G01X276725Y234475D02*
X276993D01*
G01X277865Y235459D02*
X277730Y235262D01*
G01X277463Y237821D02*
X277596Y238018D01*
G01X277865Y237952D02*
X277663Y237624D01*
G01X277865Y232900D02*
X277798Y232769D01*
G01X277530Y235525D02*
X277596Y235656D01*
G01X275854Y233950D02*
X275921Y234081D01*
G01X277530Y240511D02*
X277596Y240643D01*
G01X276189Y238806D02*
X276122Y238674D01*
G01X277463Y242874D02*
X277596Y243136D01*
G01X275854Y243793D02*
X275921Y243924D01*
G01X276993Y234147D02*
X276725D01*
G01X285039Y233819D02*
X286300D01*
G01X285039Y233031D02*
X286300D01*
G01X276725Y232703D02*
X276993D01*
G01Y232375D02*
X276725D01*
G01X285039Y231850D02*
X286300D01*
G01X275787D02*
X278937D01*
G01Y231522D02*
X275787D01*
G01X285039Y231063D02*
X286300D01*
G01X285039Y229882D02*
X286300D01*
G01X285039Y229094D02*
X286300D01*
G01X285039Y227913D02*
X286300D01*
G01X276457Y239396D02*
X276859Y239462D01*
G01X277463Y240052D02*
X277128Y239987D01*
G01X277865Y240446D02*
X277730Y240249D01*
G01X275921Y238937D02*
X276055Y239133D01*
G01X277865Y242874D02*
X277730Y242677D01*
G01X276323Y243989D02*
X276189Y243793D01*
G01X277060Y235328D02*
X277395Y235393D01*
G01Y235065D02*
X277060Y235000D01*
G01X277395Y242415D02*
X277128Y242349D01*
G01Y240315D02*
X277395Y240380D01*
G01Y237428D02*
X277128Y237362D01*
G01X276725Y234147D02*
X276457Y234081D01*
G01X276993Y232703D02*
X277261Y232769D01*
G01Y232441D02*
X276993Y232375D01*
G01X276256Y234344D02*
X276725Y234475D01*
G01X277798Y232769D02*
X277663Y232637D01*
G01X277463Y232900D02*
X277596Y233031D01*
G01X277730Y235262D02*
X277596Y235131D01*
G01X276256Y233950D02*
X276122Y233819D01*
G01X277395Y235393D02*
X277530Y235525D01*
G01X275921Y234081D02*
X276055Y234212D01*
G01X277730Y240249D02*
X277596Y240118D01*
G01X276390Y239002D02*
X276189Y238806D01*
G01X277395Y240380D02*
X277530Y240511D01*
G01X276055Y239133D02*
X276189Y239265D01*
G01X277730Y242677D02*
X277530Y242480D01*
G01X275921Y243924D02*
X276055Y244055D01*
G01X277663Y232637D02*
X277463Y232506D01*
G01X277261Y232769D02*
X277463Y232900D01*
G01X276457Y234081D02*
X276256Y233950D01*
G01X276055Y234212D02*
X276256Y234344D01*
G01X277261Y237690D02*
X277463Y237821D01*
G01X277261Y242743D02*
X277463Y242874D01*
G01X276524Y244120D02*
X276323Y243989D01*
G01X277663Y237624D02*
X277395Y237428D01*
G01X276524Y239068D02*
X276390Y239002D01*
G01X276189Y239265D02*
X276457Y239396D01*
G01X277596Y240118D02*
X277463Y240052D01*
G01X277530Y242480D02*
X277395Y242415D01*
G01X276055Y244055D02*
X276189Y244120D01*
G01X277463Y232506D02*
X277261Y232441D01*
G01X277596Y235131D02*
X277395Y235065D01*
G01X276725Y239133D02*
X276524Y239068D01*
G01X277060Y242677D02*
X277261Y242743D01*
G01X273700Y242086D02*
X270886Y241102D01*
G01X286300Y244842D02*
G03X286497Y245039I0J197D01*
G01Y245433D02*
G03X286300Y245630I-197J0D01*
G01Y246811D02*
G03X286497Y247008I0J197D01*
G01Y247401D02*
G03X286300Y247598I-197J0D01*
G01Y248779D02*
G03X286497Y248976I0J197D01*
G01Y249370D02*
G03X286300Y249567I-197J0D01*
G01X280000Y250826D02*
G03X279212Y251614I-787J1D01*
G01X277663Y245761D02*
X277596Y245892D01*
G01X277865Y246942D02*
X277932Y246745D01*
G01X277663D02*
X277596Y246942D01*
G01X277865Y245892D02*
X277932Y245695D01*
G01X277730Y247073D02*
X277865Y246942D01*
G01X277596D02*
X277463Y247073D01*
G01X277663Y246089D02*
X277865Y245892D01*
G01X277596D02*
X277530Y245958D01*
G01X286497Y245433D02*
Y245039D01*
G01Y247401D02*
Y247008D01*
G01Y249370D02*
Y248976D01*
G01X278937Y249501D02*
Y248976D01*
G01X277932Y245695D02*
Y245433D01*
G01Y246745D02*
Y246483D01*
G01Y247401D02*
Y247073D01*
G01X277530Y245958D02*
X277395Y246023D01*
G01X275787Y250551D02*
X278937Y249501D01*
G01X278669Y249239D02*
X276859Y249829D01*
G01X276591Y249895D02*
X275787Y250157D01*
G01X277663Y246614D02*
Y246745D01*
G01Y245564D02*
Y245761D01*
G01X276859Y249829D02*
Y248648D01*
G01X276591Y248582D02*
Y249895D01*
G01X275787Y250157D02*
Y250551D01*
G01Y247926D02*
Y248320D01*
G01Y246023D02*
Y246352D01*
G01Y244974D02*
Y245302D01*
G01Y247073D02*
Y247401D01*
G01X287992Y252913D02*
X282677D01*
G01X287992Y251732D02*
X285039D01*
G01X277932Y245433D02*
X277865Y245236D01*
G01X277932Y246483D02*
X277865Y246286D01*
G01X285039Y251141D02*
X287992D01*
G01X285039Y249567D02*
X286300D01*
G01X285039Y248779D02*
X286300D01*
G01X285039Y247598D02*
X286300D01*
G01X275787Y247401D02*
X277932D01*
G01X277463Y247073D02*
X275787D01*
G01X277932D02*
X277730D01*
G01X285039Y246811D02*
X286300D01*
G01X275787Y246352D02*
X277395D01*
G01Y246023D02*
X275787D01*
G01X285039Y245630D02*
X286300D01*
G01X275787Y245302D02*
X277395D01*
G01Y244974D02*
X275787D01*
G01X285039Y244842D02*
X286300D01*
G01X274715Y244448D02*
X277932D01*
G01X277596Y245433D02*
X277663Y245564D01*
G01X277596Y246483D02*
X277663Y246614D01*
G01X277865Y245236D02*
X277730Y245105D01*
G01X277530Y245367D02*
X277596Y245433D01*
G01X277865Y246286D02*
X277663Y246089D01*
G01X277530Y246417D02*
X277596Y246483D01*
G01X277395Y245302D02*
X277530Y245367D01*
G01X277395Y246352D02*
X277530Y246417D01*
G01X278937Y248976D02*
X275787Y247926D01*
G01X277730Y245105D02*
X277395Y244974D01*
G01X276859Y248648D02*
X278669Y249239D01*
G01X275787Y248320D02*
X276591Y248582D01*
G01X294389Y345708D02*
G03X280414Y345709I-6988J0D01*
G03X294389Y345708I6987J-1D01*
G01D02*
G03X280414Y345709I-6988J0D01*
G03X294389Y345708I6987J-1D01*
G01X303149D02*
G03X271654Y345709I-15748J0D01*
G03X303149Y345708I15747J-1D01*
G01X294389D02*
G03X280414Y345709I-6988J0D01*
G03X294389Y345708I6987J-1D01*
G01X303149D02*
G03X271654Y345709I-15748J0D01*
G03X303149Y345708I15747J-1D01*
G01X287402Y352697D02*
G03Y338720I0J-6988D01*
G01X281177Y381710D02*
Y384510D01*
G01X294291Y-105354D02*
Y-7874D01*
G01X302165Y25708D02*
G03X303346Y24527I1181J0D01*
G01X302295Y22834D02*
G03X287401Y33464I-14893J-5118D01*
G01X302165Y41653D02*
Y25708D01*
G01X303346Y24527D02*
X319280D01*
G01X303538Y22834D02*
X312200D01*
G01X303346Y42834D02*
G03X302165Y41653I0J-1181D01*
G01X302952Y39674D02*
Y35737D01*
G01X287401Y34645D02*
Y40551D01*
G01X303346Y42834D02*
X319254D01*
G01X302952Y39674D02*
X306889D01*
G01X302952Y35737D02*
X306889D01*
G01X287204Y60787D02*
G03X287992Y61574I1J787D01*
G01D02*
Y65708D01*
G01Y142480D02*
Y146614D01*
G01D02*
G03X287204Y147401I-787J0D01*
G01X302165Y175630D02*
G03X303346Y174448I1181J-1D01*
G01X287204Y169448D02*
G03X287992Y170236I0J788D01*
G01X302952Y179173D02*
Y175236D01*
G01X302165Y175630D02*
Y191574D01*
G01X302952Y175236D02*
X306889D01*
G01X319280Y174448D02*
X303346D01*
G01X287992Y170236D02*
Y174370D01*
G01X303346Y192756D02*
G03X302165Y191574I0J-1181D01*
G01X303346Y192756D02*
X319254D01*
G01X306889Y179173D02*
X302952D01*
G01X287992Y255275D02*
G03X287204Y256063I-788J0D01*
G01X288189Y265945D02*
Y257086D01*
G01X287992Y251141D02*
Y255275D01*
G01X287402Y338720D02*
G03Y352697I0J6989D01*
G01X302849Y406660D02*
X304620D01*
G01X303734D02*
Y400754D01*
G01X302849D02*
X304620D01*
G01X308016D02*
Y406660D01*
X309492D01*
X310082Y406365D01*
X310525Y405971D01*
X310894Y405380D01*
X311190Y404691D01*
X311263Y403707D01*
X311190Y402723D01*
X310894Y402034D01*
X310525Y401443D01*
X310082Y401049D01*
X309492Y400754D01*
X308016D01*
G01X314585Y402723D02*
X316504D01*
G01X319973Y406660D02*
Y400754D01*
X322926D01*
G01X325509D02*
X327354Y406660D01*
X329200Y400754D01*
G01X328536Y402821D02*
X326173D01*
G01X333850Y403904D02*
X334145Y404199D01*
X334367Y404691D01*
X334514Y405380D01*
X334367Y405971D01*
X334072Y406365D01*
X333555Y406660D01*
X331562D01*
Y400754D01*
X333998D01*
X334514Y401148D01*
X334810Y401738D01*
X334957Y402427D01*
X334810Y403116D01*
X334367Y403707D01*
X333850Y403904D01*
X331562D01*
G01X340641Y400754D02*
X337688D01*
Y406660D01*
X340641D01*
G01X339460Y403806D02*
X337688D01*
G01X343593Y406660D02*
Y400754D01*
X346546D01*
G01X350015Y402723D02*
X351934D01*
G01X356879Y400754D02*
Y406660D01*
X355994Y405479D01*
G01Y400754D02*
X357765D01*
G01X361382Y403215D02*
X361899Y403904D01*
X362342Y404298D01*
X362932Y404494D01*
X363449Y404298D01*
X363818Y403904D01*
X364113Y403313D01*
X364187Y402624D01*
X364113Y402034D01*
X363818Y401443D01*
X363375Y400951D01*
X362858Y400754D01*
X362268Y400951D01*
X361751Y401541D01*
X361456Y402427D01*
X361382Y403412D01*
X361530Y404691D01*
X361751Y405380D01*
X362120Y406069D01*
X362637Y406562D01*
X363154Y406660D01*
X363670Y406463D01*
X364039Y405971D01*
G01X367730Y402723D02*
X369649D01*
G01X372971Y406660D02*
Y402427D01*
X373266Y401541D01*
X373856Y400951D01*
X374594Y400754D01*
X375333Y400951D01*
X375923Y401541D01*
X376218Y402427D01*
Y406660D01*
G01X339566Y-58110D02*
G03X308070Y-58111I-15748J0D01*
G03X339566Y-58110I15748J1D01*
G01D02*
G03X308070Y-58111I-15748J0D01*
G03X339566Y-58110I15748J1D01*
G01X330806D02*
G03X316830Y-58111I-6988J0D01*
G03X330806Y-58110I6988J1D01*
G01D02*
G03X316830Y-58111I-6988J0D01*
G03X330806Y-58110I6988J1D01*
G01D02*
G03X316830Y-58111I-6988J0D01*
G03X330806Y-58110I6988J1D01*
G01X323818Y-51122D02*
G03Y-65098I0J-6988D01*
G01X310621Y-7874D02*
G03Y0I0J3937D01*
G01X312200Y22834D02*
Y0D01*
G01X319094Y25335D02*
Y42067D01*
G01X319093Y25335D02*
G03X321063Y23366I1969J0D01*
G01X319094Y25334D02*
G03X321063Y23366I1969J1D01*
G01X319094Y25334D02*
G03X321063Y23366I1969J1D01*
G01X310630Y34429D02*
G03Y29311I0J-2559D01*
G01X312598D02*
G03Y34429I0J2559D01*
G01X319094Y25334D02*
G03X321063Y23366I1969J1D01*
G01X319094Y25334D02*
G03X321063Y23366I1969J1D01*
G01X319488Y24527D02*
Y42834D01*
G01Y24216D02*
Y24527D01*
G01Y13700D02*
Y24216D01*
G01X319094Y25334D02*
Y42067D01*
G01Y25334D02*
Y42067D01*
G01X317519Y42834D02*
Y24527D01*
G01X317126Y27126D02*
Y36574D01*
G01X312598Y29311D02*
Y30492D01*
G01X310630Y29311D02*
Y30492D01*
G01X307677Y36574D02*
Y27126D01*
G01X312598Y29311D02*
X310630D01*
G01X322637Y28464D02*
X319488D01*
G01X317126Y27126D02*
X307677D01*
G01X319280Y24527D02*
X349409D01*
G01Y22559D02*
X319488D01*
G01Y20433D02*
X349409D01*
G01X319488Y19842D02*
X349409D01*
G01X319488Y19252D02*
X349409D01*
G01X319488Y17992D02*
X349409D01*
G01X329330Y17401D02*
X319488D01*
G01X329330Y16811D02*
X319488D01*
G01X329330Y13700D02*
X319488D01*
G01X319094Y25334D02*
Y363425D01*
G01Y25334D02*
Y42067D01*
G01X321063Y44035D02*
G03X319094Y42067I0J-1969D01*
G01X318051Y44790D02*
X318078Y44821D01*
G01X318021Y44770D02*
X318051Y44790D01*
G01X317988Y44763D02*
X318021Y44770D01*
G01X317655Y45328D02*
X317629Y45296D01*
G01X317685Y45347D02*
X317655Y45328D01*
G01X317719Y45354D02*
X317685Y45347D01*
G01X312214Y44790D02*
X312188Y44821D01*
G01X312245Y44770D02*
X312214Y44790D01*
G01X312278Y44763D02*
X312245Y44770D01*
G01X312610Y45328D02*
X312637Y45296D01*
G01X312580Y45347D02*
X312610Y45328D01*
G01X312547Y45354D02*
X312580Y45347D01*
G01X311826D02*
X311793Y45354D01*
G01X311856Y45328D02*
X311826Y45347D01*
G01X311883Y45296D02*
X311856Y45328D01*
G01X312999Y44770D02*
X313032Y44763D01*
G01X312968Y44790D02*
X312999Y44770D01*
G01X312942Y44821D02*
X312968Y44790D01*
G01X317267Y44770D02*
X317234Y44763D01*
G01X317297Y44790D02*
X317267Y44770D01*
G01X317323Y44821D02*
X317297Y44790D01*
G01X318440Y45347D02*
X318472Y45354D01*
G01X318409Y45328D02*
X318440Y45347D01*
G01X318383Y45296D02*
X318409Y45328D01*
G01X321063Y44035D02*
G03X319094Y42067I0J-1969D01*
G01X321063Y44035D02*
G03X319094Y42067I0J-1969D01*
G01X312598Y30492D02*
G03Y33248I0J1378D01*
G01X310630D02*
G03Y30492I0J-1378D01*
G01Y33641D02*
G03Y30098I0J-1772D01*
G01X312598D02*
G03Y33641I0J1771D01*
G01X321063Y44035D02*
G03X319094Y42067I0J-1969D01*
G01X321063Y44035D02*
G03X319094Y42067I0J-1969D01*
G01X318078Y44821D02*
X318383Y45296D01*
G01X317629D02*
X317323Y44821D01*
G01X319680Y46929D02*
Y45354D01*
G01X318926Y46929D02*
Y45354D01*
G01X318172D02*
Y46929D01*
G01X312598Y34429D02*
Y33248D01*
G01X312069Y45354D02*
Y46929D01*
G01X311315D02*
Y45354D01*
G01X310630Y33248D02*
Y34429D01*
G01X310561Y46929D02*
Y45354D01*
G01X307806Y46929D02*
Y45354D01*
G01X306889Y35737D02*
Y39674D01*
G01X312637Y45296D02*
X312942Y44821D01*
G01X312188D02*
X311883Y45296D01*
G01X317719Y45354D02*
X320271D01*
G01X307806D02*
X312547D01*
G01X311883Y45296D02*
X312637D01*
G01X318383D02*
X317629D01*
G01X317323Y44821D02*
X318078D01*
G01X312942D02*
X312188D01*
G01X317988Y44763D02*
X312278D01*
G01X319254Y42834D02*
X348228D01*
G01X317126Y36574D02*
X307677D01*
G01X310630Y34429D02*
X312598D01*
G01Y33641D02*
X310630D01*
G01Y33248D02*
X312598D01*
G01Y30492D02*
X310630D01*
G01Y30098D02*
X312598D01*
G01X311856Y46955D02*
X311883Y46987D01*
G01X311826Y46935D02*
X311856Y46955D01*
G01X311793Y46929D02*
X311826Y46935D01*
G01X312968Y47493D02*
X312942Y47462D01*
G01X312999Y47513D02*
X312968Y47493D01*
G01X313032Y47519D02*
X312999Y47513D01*
G01X318051Y49790D02*
X318078Y49821D01*
G01X318021Y49770D02*
X318051Y49790D01*
G01X317988Y49763D02*
X318021Y49770D01*
G01X317655Y50328D02*
X317629Y50296D01*
G01X317685Y50347D02*
X317655Y50328D01*
G01X317719Y50354D02*
X317685Y50347D01*
G01X311856Y51955D02*
X311883Y51987D01*
G01X311826Y51935D02*
X311856Y51955D01*
G01X311793Y51929D02*
X311826Y51935D01*
G01X312968Y52493D02*
X312942Y52462D01*
G01X312999Y52513D02*
X312968Y52493D01*
G01X313032Y52519D02*
X312999Y52513D01*
G01X318051Y54790D02*
X318078Y54821D01*
G01X318021Y54770D02*
X318051Y54790D01*
G01X317988Y54763D02*
X318021Y54770D01*
G01X317655Y55328D02*
X317629Y55296D01*
G01X317685Y55347D02*
X317655Y55328D01*
G01X317719Y55354D02*
X317685Y55347D01*
G01X311856Y56955D02*
X311883Y56987D01*
G01X311826Y56935D02*
X311856Y56955D01*
G01X311793Y56929D02*
X311826Y56935D01*
G01X312968Y57493D02*
X312942Y57462D01*
G01X312999Y57513D02*
X312968Y57493D01*
G01X313032Y57519D02*
X312999Y57513D01*
G01X318051Y59790D02*
X318078Y59821D01*
G01X318021Y59770D02*
X318051Y59790D01*
G01X317988Y59763D02*
X318021Y59770D01*
G01X317655Y60328D02*
X317629Y60296D01*
G01X317685Y60347D02*
X317655Y60328D01*
G01X317719Y60354D02*
X317685Y60347D01*
G01X311856Y61955D02*
X311883Y61987D01*
G01X311826Y61935D02*
X311856Y61955D01*
G01X311793Y61929D02*
X311826Y61935D01*
G01X312968Y62493D02*
X312942Y62462D01*
G01X312999Y62513D02*
X312968Y62493D01*
G01X313032Y62519D02*
X312999Y62513D01*
G01X318409Y46955D02*
X318383Y46987D01*
G01X318440Y46935D02*
X318409Y46955D01*
G01X318472Y46929D02*
X318440Y46935D01*
G01X317297Y47493D02*
X317323Y47462D01*
G01X317267Y47513D02*
X317297Y47493D01*
G01X317234Y47519D02*
X317267Y47513D01*
G01X312214Y49790D02*
X312188Y49821D01*
G01X312245Y49770D02*
X312214Y49790D01*
G01X312278Y49763D02*
X312245Y49770D01*
G01X312610Y50328D02*
X312637Y50296D01*
G01X312580Y50347D02*
X312610Y50328D01*
G01X312547Y50354D02*
X312580Y50347D01*
G01X318409Y51955D02*
X318383Y51987D01*
G01X318440Y51935D02*
X318409Y51955D01*
G01X318472Y51929D02*
X318440Y51935D01*
G01X317297Y52493D02*
X317323Y52462D01*
G01X317267Y52513D02*
X317297Y52493D01*
G01X317234Y52519D02*
X317267Y52513D01*
G01X312214Y54790D02*
X312188Y54821D01*
G01X312245Y54770D02*
X312214Y54790D01*
G01X312278Y54763D02*
X312245Y54770D01*
G01X312610Y55328D02*
X312637Y55296D01*
G01X312580Y55347D02*
X312610Y55328D01*
G01X312547Y55354D02*
X312580Y55347D01*
G01X318409Y56955D02*
X318383Y56987D01*
G01X318440Y56935D02*
X318409Y56955D01*
G01X318472Y56929D02*
X318440Y56935D01*
G01X317297Y57493D02*
X317323Y57462D01*
G01X317267Y57513D02*
X317297Y57493D01*
G01X317234Y57519D02*
X317267Y57513D01*
G01X312214Y59790D02*
X312188Y59821D01*
G01X312245Y59770D02*
X312214Y59790D01*
G01X312278Y59763D02*
X312245Y59770D01*
G01X312610Y60328D02*
X312637Y60296D01*
G01X312580Y60347D02*
X312610Y60328D01*
G01X312547Y60354D02*
X312580Y60347D01*
G01X318409Y61955D02*
X318383Y61987D01*
G01X318440Y61935D02*
X318409Y61955D01*
G01X318472Y61929D02*
X318440Y61935D01*
G01X317297Y62493D02*
X317323Y62462D01*
G01X317267Y62513D02*
X317297Y62493D01*
G01X317234Y62519D02*
X317267Y62513D01*
G01X311826Y50347D02*
X311793Y50354D01*
G01X311856Y50328D02*
X311826Y50347D01*
G01X311883Y50296D02*
X311856Y50328D01*
G01X312999Y49770D02*
X313032Y49763D01*
G01X312968Y49790D02*
X312999Y49770D01*
G01X312942Y49821D02*
X312968Y49790D01*
G01X317685Y46935D02*
X317719Y46929D01*
G01X317655Y46955D02*
X317685Y46935D01*
G01X317629Y46987D02*
X317655Y46955D01*
G01X318021Y47513D02*
X317988Y47519D01*
G01X318051Y47493D02*
X318021Y47513D01*
G01X318078Y47462D02*
X318051Y47493D01*
G01X311826Y55347D02*
X311793Y55354D01*
G01X311856Y55328D02*
X311826Y55347D01*
G01X311883Y55296D02*
X311856Y55328D01*
G01X312999Y54770D02*
X313032Y54763D01*
G01X312968Y54790D02*
X312999Y54770D01*
G01X312942Y54821D02*
X312968Y54790D01*
G01X317685Y51935D02*
X317719Y51929D01*
G01X317655Y51955D02*
X317685Y51935D01*
G01X317629Y51987D02*
X317655Y51955D01*
G01X318021Y52513D02*
X317988Y52519D01*
G01X318051Y52493D02*
X318021Y52513D01*
G01X318078Y52462D02*
X318051Y52493D01*
G01X311826Y60347D02*
X311793Y60354D01*
G01X311856Y60328D02*
X311826Y60347D01*
G01X311883Y60296D02*
X311856Y60328D01*
G01X312999Y59770D02*
X313032Y59763D01*
G01X312968Y59790D02*
X312999Y59770D01*
G01X312942Y59821D02*
X312968Y59790D01*
G01X317685Y56935D02*
X317719Y56929D01*
G01X317655Y56955D02*
X317685Y56935D01*
G01X317629Y56987D02*
X317655Y56955D01*
G01X318021Y57513D02*
X317988Y57519D01*
G01X318051Y57493D02*
X318021Y57513D01*
G01X318078Y57462D02*
X318051Y57493D01*
G01X317685Y61935D02*
X317719Y61929D01*
G01X317655Y61955D02*
X317685Y61935D01*
G01X317629Y61987D02*
X317655Y61955D01*
G01X318021Y62513D02*
X317988Y62519D01*
G01X318051Y62493D02*
X318021Y62513D01*
G01X318078Y62462D02*
X318051Y62493D01*
G01X312245Y62513D02*
X312278Y62519D01*
G01X312214Y62493D02*
X312245Y62513D01*
G01X312188Y62462D02*
X312214Y62493D01*
G01X312580Y61935D02*
X312547Y61929D01*
G01X312610Y61955D02*
X312580Y61935D01*
G01X312637Y61987D02*
X312610Y61955D01*
G01X312245Y57513D02*
X312278Y57519D01*
G01X312214Y57493D02*
X312245Y57513D01*
G01X312188Y57462D02*
X312214Y57493D01*
G01X312580Y56935D02*
X312547Y56929D01*
G01X312610Y56955D02*
X312580Y56935D01*
G01X312637Y56987D02*
X312610Y56955D01*
G01X317267Y59770D02*
X317234Y59763D01*
G01X317297Y59790D02*
X317267Y59770D01*
G01X317323Y59821D02*
X317297Y59790D01*
G01X318440Y60347D02*
X318472Y60354D01*
G01X318409Y60328D02*
X318440Y60347D01*
G01X318383Y60296D02*
X318409Y60328D01*
G01X312245Y52513D02*
X312278Y52519D01*
G01X312214Y52493D02*
X312245Y52513D01*
G01X312188Y52462D02*
X312214Y52493D01*
G01X312580Y51935D02*
X312547Y51929D01*
G01X312610Y51955D02*
X312580Y51935D01*
G01X312637Y51987D02*
X312610Y51955D01*
G01X317267Y54770D02*
X317234Y54763D01*
G01X317297Y54790D02*
X317267Y54770D01*
G01X317323Y54821D02*
X317297Y54790D01*
G01X318440Y55347D02*
X318472Y55354D01*
G01X318409Y55328D02*
X318440Y55347D01*
G01X318383Y55296D02*
X318409Y55328D01*
G01X312245Y47513D02*
X312278Y47519D01*
G01X312214Y47493D02*
X312245Y47513D01*
G01X312188Y47462D02*
X312214Y47493D01*
G01X312580Y46935D02*
X312547Y46929D01*
G01X312610Y46955D02*
X312580Y46935D01*
G01X312637Y46987D02*
X312610Y46955D01*
G01X317267Y49770D02*
X317234Y49763D01*
G01X317297Y49790D02*
X317267Y49770D01*
G01X317323Y49821D02*
X317297Y49790D01*
G01X318440Y50347D02*
X318472Y50354D01*
G01X318409Y50328D02*
X318440Y50347D01*
G01X318383Y50296D02*
X318409Y50328D01*
G01X318078Y49821D02*
X318383Y50296D01*
G01X317629D02*
X317323Y49821D01*
G01X318078Y54821D02*
X318383Y55296D01*
G01X312942Y47462D02*
X312637Y46987D01*
G01X317629Y55296D02*
X317323Y54821D01*
G01X311883Y46987D02*
X312188Y47462D01*
G01X318078Y59821D02*
X318383Y60296D01*
G01X312942Y52462D02*
X312637Y51987D01*
G01X317629Y60296D02*
X317323Y59821D01*
G01X311883Y51987D02*
X312188Y52462D01*
G01X312942Y57462D02*
X312637Y56987D01*
G01X311883D02*
X312188Y57462D01*
G01X312942Y62462D02*
X312637Y61987D01*
G01X311883D02*
X312188Y62462D01*
G01X319680Y60354D02*
Y61929D01*
G01Y55354D02*
Y56929D01*
G01Y51929D02*
Y50354D01*
G01X318926Y51929D02*
Y50354D01*
G01Y56929D02*
Y55354D01*
G01Y61929D02*
Y60354D01*
G01X318172Y50354D02*
Y51929D01*
G01Y56929D02*
Y55354D01*
G01Y61929D02*
Y60354D01*
G01X317772Y55767D02*
Y56633D01*
G01Y46319D02*
Y47185D01*
G01Y50334D02*
Y49468D01*
G01Y53484D02*
Y52618D01*
G01Y59783D02*
Y58917D01*
G01Y62933D02*
Y62067D01*
G01X312069Y60354D02*
Y61929D01*
G01Y55354D02*
Y56929D01*
G01Y50354D02*
Y51929D01*
G01X311315D02*
Y50354D01*
G01Y56929D02*
Y55354D01*
G01Y61929D02*
Y60354D01*
G01X310561Y51929D02*
Y50354D01*
G01Y56929D02*
Y55354D01*
G01Y61929D02*
Y60354D01*
G01X307806Y51929D02*
Y50354D01*
G01Y56929D02*
Y55354D01*
G01Y61929D02*
Y60354D01*
G01X318383Y61987D02*
X318078Y62462D01*
G01X317323D02*
X317629Y61987D01*
G01X318383Y56987D02*
X318078Y57462D01*
G01X317323D02*
X317629Y56987D01*
G01X318383Y51987D02*
X318078Y52462D01*
G01X312637Y60296D02*
X312942Y59821D01*
G01X317323Y52462D02*
X317629Y51987D01*
G01X312188Y59821D02*
X311883Y60296D01*
G01X318383Y46987D02*
X318078Y47462D01*
G01X312637Y55296D02*
X312942Y54821D01*
G01X317323Y47462D02*
X317629Y46987D01*
G01X312188Y54821D02*
X311883Y55296D01*
G01X312637Y50296D02*
X312942Y49821D01*
G01X312188D02*
X311883Y50296D01*
G01X312278Y62519D02*
X317988D01*
G01X317323Y62462D02*
X318078D01*
G01X312942D02*
X312188D01*
G01X322727Y62067D02*
X317772D01*
G01X312637Y61987D02*
X311883D01*
G01X318383D02*
X317629D01*
G01X317719Y61929D02*
X320271D01*
G01X307806D02*
X312547D01*
G01X317719Y60354D02*
X320271D01*
G01X307806D02*
X312547D01*
G01X311883Y60296D02*
X312637D01*
G01X318383D02*
X317629D01*
G01X317323Y59821D02*
X318078D01*
G01X312942D02*
X312188D01*
G01X317772Y59783D02*
X322727D01*
G01X317988Y59763D02*
X312278D01*
G01X322727Y58917D02*
X317772D01*
G01X312278Y57519D02*
X317988D01*
G01X317323Y57462D02*
X318078D01*
G01X312942D02*
X312188D01*
G01X312637Y56987D02*
X311883D01*
G01X318383D02*
X317629D01*
G01X317719Y56929D02*
X320271D01*
G01X307806D02*
X312547D01*
G01X317772Y56633D02*
X322727D01*
G01Y55767D02*
X317772D01*
G01X317719Y55354D02*
X320271D01*
G01X307806D02*
X312547D01*
G01X311883Y55296D02*
X312637D01*
G01X318383D02*
X317629D01*
G01X317323Y54821D02*
X318078D01*
G01X312942D02*
X312188D01*
G01X317988Y54763D02*
X312278D01*
G01X317772Y53484D02*
X322727D01*
G01Y52618D02*
X317772D01*
G01X312278Y52519D02*
X317988D01*
G01X312942Y52462D02*
X312188D01*
G01X318078D02*
X317323D01*
G01X311883Y51987D02*
X312637D01*
G01X318383D02*
X317629D01*
G01X317719Y51929D02*
X320271D01*
G01X307806D02*
X312547D01*
G01X317719Y50354D02*
X320271D01*
G01X307806D02*
X312547D01*
G01X317772Y50334D02*
X322727D01*
G01X311883Y50296D02*
X312637D01*
G01X318383D02*
X317629D01*
G01X317323Y49821D02*
X318078D01*
G01X312942D02*
X312188D01*
G01X317988Y49763D02*
X312278D01*
G01X322727Y49468D02*
X317772D01*
G01X312278Y47519D02*
X317988D01*
G01X312942Y47462D02*
X312188D01*
G01X318078D02*
X317323D01*
G01X317772Y47185D02*
X322727D01*
G01X311883Y46987D02*
X312637D01*
G01X318383D02*
X317629D01*
G01X317719Y46929D02*
X320271D01*
G01X307806D02*
X312547D01*
G01X322727Y46319D02*
X317772D01*
G01X318051Y64790D02*
X318078Y64821D01*
G01X318021Y64770D02*
X318051Y64790D01*
G01X317988Y64763D02*
X318021Y64770D01*
G01X317655Y65328D02*
X317629Y65296D01*
G01X317685Y65347D02*
X317655Y65328D01*
G01X317719Y65354D02*
X317685Y65347D01*
G01X311856Y66955D02*
X311883Y66987D01*
G01X311826Y66935D02*
X311856Y66955D01*
G01X311793Y66929D02*
X311826Y66935D01*
G01X312968Y67493D02*
X312942Y67462D01*
G01X312999Y67513D02*
X312968Y67493D01*
G01X313032Y67519D02*
X312999Y67513D01*
G01X318051Y69790D02*
X318078Y69821D01*
G01X318021Y69770D02*
X318051Y69790D01*
G01X317988Y69763D02*
X318021Y69770D01*
G01X317655Y70328D02*
X317629Y70296D01*
G01X317685Y70347D02*
X317655Y70328D01*
G01X317719Y70354D02*
X317685Y70347D01*
G01X311856Y71955D02*
X311883Y71987D01*
G01X311826Y71935D02*
X311856Y71955D01*
G01X311793Y71929D02*
X311826Y71935D01*
G01X312968Y72493D02*
X312942Y72462D01*
G01X312999Y72513D02*
X312968Y72493D01*
G01X313032Y72519D02*
X312999Y72513D01*
G01X318051Y74790D02*
X318078Y74821D01*
G01X318021Y74770D02*
X318051Y74790D01*
G01X317988Y74763D02*
X318021Y74770D01*
G01X317655Y75328D02*
X317629Y75296D01*
G01X317685Y75347D02*
X317655Y75328D01*
G01X317719Y75354D02*
X317685Y75347D01*
G01X311856Y76955D02*
X311883Y76987D01*
G01X311826Y76935D02*
X311856Y76955D01*
G01X311793Y76929D02*
X311826Y76935D01*
G01X312968Y77493D02*
X312942Y77462D01*
G01X312999Y77513D02*
X312968Y77493D01*
G01X313032Y77519D02*
X312999Y77513D01*
G01X312214Y64790D02*
X312188Y64821D01*
G01X312245Y64770D02*
X312214Y64790D01*
G01X312278Y64763D02*
X312245Y64770D01*
G01X312610Y65328D02*
X312637Y65296D01*
G01X312580Y65347D02*
X312610Y65328D01*
G01X312547Y65354D02*
X312580Y65347D01*
G01X318409Y66955D02*
X318383Y66987D01*
G01X318440Y66935D02*
X318409Y66955D01*
G01X318472Y66929D02*
X318440Y66935D01*
G01X317297Y67493D02*
X317323Y67462D01*
G01X317267Y67513D02*
X317297Y67493D01*
G01X317234Y67519D02*
X317267Y67513D01*
G01X312214Y69790D02*
X312188Y69821D01*
G01X312245Y69770D02*
X312214Y69790D01*
G01X312278Y69763D02*
X312245Y69770D01*
G01X312610Y70328D02*
X312637Y70296D01*
G01X312580Y70347D02*
X312610Y70328D01*
G01X312547Y70354D02*
X312580Y70347D01*
G01X318409Y71955D02*
X318383Y71987D01*
G01X318440Y71935D02*
X318409Y71955D01*
G01X318472Y71929D02*
X318440Y71935D01*
G01X317297Y72493D02*
X317323Y72462D01*
G01X317267Y72513D02*
X317297Y72493D01*
G01X317234Y72519D02*
X317267Y72513D01*
G01X312214Y74790D02*
X312188Y74821D01*
G01X312245Y74770D02*
X312214Y74790D01*
G01X312278Y74763D02*
X312245Y74770D01*
G01X312610Y75328D02*
X312637Y75296D01*
G01X312580Y75347D02*
X312610Y75328D01*
G01X312547Y75354D02*
X312580Y75347D01*
G01X318409Y76955D02*
X318383Y76987D01*
G01X318440Y76935D02*
X318409Y76955D01*
G01X318472Y76929D02*
X318440Y76935D01*
G01X317297Y77493D02*
X317323Y77462D01*
G01X317267Y77513D02*
X317297Y77493D01*
G01X317234Y77519D02*
X317267Y77513D01*
G01X311826Y65347D02*
X311793Y65354D01*
G01X311856Y65328D02*
X311826Y65347D01*
G01X311883Y65296D02*
X311856Y65328D01*
G01X312999Y64770D02*
X313032Y64763D01*
G01X312968Y64790D02*
X312999Y64770D01*
G01X312942Y64821D02*
X312968Y64790D01*
G01X311826Y70347D02*
X311793Y70354D01*
G01X311856Y70328D02*
X311826Y70347D01*
G01X311883Y70296D02*
X311856Y70328D01*
G01X312999Y69770D02*
X313032Y69763D01*
G01X312968Y69790D02*
X312999Y69770D01*
G01X312942Y69821D02*
X312968Y69790D01*
G01X317685Y66935D02*
X317719Y66929D01*
G01X317655Y66955D02*
X317685Y66935D01*
G01X317629Y66987D02*
X317655Y66955D01*
G01X318021Y67513D02*
X317988Y67519D01*
G01X318051Y67493D02*
X318021Y67513D01*
G01X318078Y67462D02*
X318051Y67493D01*
G01X311826Y75347D02*
X311793Y75354D01*
G01X311856Y75328D02*
X311826Y75347D01*
G01X311883Y75296D02*
X311856Y75328D01*
G01X312999Y74770D02*
X313032Y74763D01*
G01X312968Y74790D02*
X312999Y74770D01*
G01X312942Y74821D02*
X312968Y74790D01*
G01X317685Y71935D02*
X317719Y71929D01*
G01X317655Y71955D02*
X317685Y71935D01*
G01X317629Y71987D02*
X317655Y71955D01*
G01X318021Y72513D02*
X317988Y72519D01*
G01X318051Y72493D02*
X318021Y72513D01*
G01X318078Y72462D02*
X318051Y72493D01*
G01X317685Y76935D02*
X317719Y76929D01*
G01X317655Y76955D02*
X317685Y76935D01*
G01X317629Y76987D02*
X317655Y76955D01*
G01X318021Y77513D02*
X317988Y77519D01*
G01X318051Y77493D02*
X318021Y77513D01*
G01X318078Y77462D02*
X318051Y77493D01*
G01X312245Y77513D02*
X312278Y77519D01*
G01X312214Y77493D02*
X312245Y77513D01*
G01X312188Y77462D02*
X312214Y77493D01*
G01X312580Y76935D02*
X312547Y76929D01*
G01X312610Y76955D02*
X312580Y76935D01*
G01X312637Y76987D02*
X312610Y76955D01*
G01X312245Y72513D02*
X312278Y72519D01*
G01X312214Y72493D02*
X312245Y72513D01*
G01X312188Y72462D02*
X312214Y72493D01*
G01X312580Y71935D02*
X312547Y71929D01*
G01X312610Y71955D02*
X312580Y71935D01*
G01X312637Y71987D02*
X312610Y71955D01*
G01X317267Y74770D02*
X317234Y74763D01*
G01X317297Y74790D02*
X317267Y74770D01*
G01X317323Y74821D02*
X317297Y74790D01*
G01X318440Y75347D02*
X318472Y75354D01*
G01X318409Y75328D02*
X318440Y75347D01*
G01X318383Y75296D02*
X318409Y75328D01*
G01X312245Y67513D02*
X312278Y67519D01*
G01X312214Y67493D02*
X312245Y67513D01*
G01X312188Y67462D02*
X312214Y67493D01*
G01X312580Y66935D02*
X312547Y66929D01*
G01X312610Y66955D02*
X312580Y66935D01*
G01X312637Y66987D02*
X312610Y66955D01*
G01X317267Y69770D02*
X317234Y69763D01*
G01X317297Y69790D02*
X317267Y69770D01*
G01X317323Y69821D02*
X317297Y69790D01*
G01X318440Y70347D02*
X318472Y70354D01*
G01X318409Y70328D02*
X318440Y70347D01*
G01X318383Y70296D02*
X318409Y70328D01*
G01X317267Y64770D02*
X317234Y64763D01*
G01X317297Y64790D02*
X317267Y64770D01*
G01X317323Y64821D02*
X317297Y64790D01*
G01X318440Y65347D02*
X318472Y65354D01*
G01X318409Y65328D02*
X318440Y65347D01*
G01X318383Y65296D02*
X318409Y65328D01*
G01X318078Y64821D02*
X318383Y65296D01*
G01X317629D02*
X317323Y64821D01*
G01X318078Y69821D02*
X318383Y70296D01*
G01X317629D02*
X317323Y69821D01*
G01X318078Y74821D02*
X318383Y75296D01*
G01X312942Y67462D02*
X312637Y66987D01*
G01X317629Y75296D02*
X317323Y74821D01*
G01X311883Y66987D02*
X312188Y67462D01*
G01X312942Y72462D02*
X312637Y71987D01*
G01X311883D02*
X312188Y72462D01*
G01X312942Y77462D02*
X312637Y76987D01*
G01X311883D02*
X312188Y77462D01*
G01X319680Y70354D02*
Y71929D01*
G01Y66929D02*
Y65354D01*
G01Y76929D02*
Y75354D01*
G01X318926Y66929D02*
Y65354D01*
G01Y71929D02*
Y70354D01*
G01Y76929D02*
Y75354D01*
G01X318172D02*
Y76929D01*
G01Y65354D02*
Y66929D01*
G01Y71929D02*
Y70354D01*
G01X317772Y74665D02*
Y75531D01*
G01Y65216D02*
Y66082D01*
G01Y69232D02*
Y68366D01*
G01Y72382D02*
Y71515D01*
G01Y78681D02*
Y77815D01*
G01X312069Y75354D02*
Y76929D01*
G01Y70354D02*
Y71929D01*
G01Y65354D02*
Y66929D01*
G01X311315D02*
Y65354D01*
G01Y71929D02*
Y70354D01*
G01Y76929D02*
Y75354D01*
G01X310561Y66929D02*
Y65354D01*
G01Y71929D02*
Y70354D01*
G01Y76929D02*
Y75354D01*
G01X307806Y66929D02*
Y65354D01*
G01Y71929D02*
Y70354D01*
G01Y76929D02*
Y75354D01*
G01X318383Y76987D02*
X318078Y77462D01*
G01X317323D02*
X317629Y76987D01*
G01X318383Y71987D02*
X318078Y72462D01*
G01X317323D02*
X317629Y71987D01*
G01X318383Y66987D02*
X318078Y67462D01*
G01X312637Y75296D02*
X312942Y74821D01*
G01X317323Y67462D02*
X317629Y66987D01*
G01X312188Y74821D02*
X311883Y75296D01*
G01X312637Y70296D02*
X312942Y69821D01*
G01X312188D02*
X311883Y70296D01*
G01X312637Y65296D02*
X312942Y64821D01*
G01X312188D02*
X311883Y65296D01*
G01X317772Y78681D02*
X322727D01*
G01Y77815D02*
X317772D01*
G01X312278Y77519D02*
X317988D01*
G01X317323Y77462D02*
X318078D01*
G01X312942D02*
X312188D01*
G01X312637Y76987D02*
X311883D01*
G01X318383D02*
X317629D01*
G01X317719Y76929D02*
X320271D01*
G01X307806D02*
X312547D01*
G01X317772Y75531D02*
X322727D01*
G01X317719Y75354D02*
X320271D01*
G01X307806D02*
X312547D01*
G01X311883Y75296D02*
X312637D01*
G01X318383D02*
X317629D01*
G01X317323Y74821D02*
X318078D01*
G01X312942D02*
X312188D01*
G01X317988Y74763D02*
X312278D01*
G01X322727Y74665D02*
X317772D01*
G01X312278Y72519D02*
X317988D01*
G01X317323Y72462D02*
X318078D01*
G01X312942D02*
X312188D01*
G01X317772Y72382D02*
X322727D01*
G01X312637Y71987D02*
X311883D01*
G01X318383D02*
X317629D01*
G01X317719Y71929D02*
X320271D01*
G01X307806D02*
X312547D01*
G01X322727Y71515D02*
X317772D01*
G01X317719Y70354D02*
X320271D01*
G01X307806D02*
X312547D01*
G01X311883Y70296D02*
X312637D01*
G01X318383D02*
X317629D01*
G01X317323Y69821D02*
X318078D01*
G01X312942D02*
X312188D01*
G01X317988Y69763D02*
X312278D01*
G01X317772Y69232D02*
X322727D01*
G01Y68366D02*
X317772D01*
G01X312278Y67519D02*
X317988D01*
G01X317323Y67462D02*
X318078D01*
G01X312942D02*
X312188D01*
G01X312637Y66987D02*
X311883D01*
G01X318383D02*
X317629D01*
G01X317719Y66929D02*
X320271D01*
G01X307806D02*
X312547D01*
G01X317772Y66082D02*
X322727D01*
G01X317719Y65354D02*
X320271D01*
G01X307806D02*
X312547D01*
G01X311883Y65296D02*
X312637D01*
G01X318383D02*
X317629D01*
G01X322727Y65216D02*
X317772D01*
G01X317323Y64821D02*
X318078D01*
G01X312942D02*
X312188D01*
G01X317988Y64763D02*
X312278D01*
G01X317772Y62933D02*
X322727D01*
G01X318051Y79790D02*
X318078Y79821D01*
G01X318021Y79770D02*
X318051Y79790D01*
G01X317988Y79763D02*
X318021Y79770D01*
G01X317655Y80328D02*
X317629Y80296D01*
G01X317685Y80347D02*
X317655Y80328D01*
G01X317719Y80354D02*
X317685Y80347D01*
G01X311856Y81955D02*
X311883Y81987D01*
G01X311826Y81935D02*
X311856Y81955D01*
G01X311793Y81929D02*
X311826Y81935D01*
G01X312968Y82493D02*
X312942Y82462D01*
G01X312999Y82513D02*
X312968Y82493D01*
G01X313032Y82519D02*
X312999Y82513D01*
G01X318051Y84790D02*
X318078Y84821D01*
G01X318021Y84770D02*
X318051Y84790D01*
G01X317988Y84763D02*
X318021Y84770D01*
G01X317655Y85328D02*
X317629Y85296D01*
G01X317685Y85347D02*
X317655Y85328D01*
G01X317719Y85354D02*
X317685Y85347D01*
G01X311856Y86955D02*
X311883Y86987D01*
G01X311826Y86935D02*
X311856Y86955D01*
G01X311793Y86929D02*
X311826Y86935D01*
G01X312968Y87493D02*
X312942Y87462D01*
G01X312999Y87513D02*
X312968Y87493D01*
G01X313032Y87519D02*
X312999Y87513D01*
G01X318051Y89790D02*
X318078Y89821D01*
G01X318021Y89770D02*
X318051Y89790D01*
G01X317988Y89763D02*
X318021Y89770D01*
G01X317655Y90328D02*
X317629Y90296D01*
G01X317685Y90347D02*
X317655Y90328D01*
G01X317719Y90354D02*
X317685Y90347D01*
G01X311856Y91955D02*
X311883Y91987D01*
G01X311826Y91935D02*
X311856Y91955D01*
G01X311793Y91929D02*
X311826Y91935D01*
G01X312968Y92493D02*
X312942Y92462D01*
G01X312999Y92513D02*
X312968Y92493D01*
G01X313032Y92519D02*
X312999Y92513D01*
G01X318051Y94790D02*
X318078Y94821D01*
G01X318021Y94770D02*
X318051Y94790D01*
G01X317988Y94763D02*
X318021Y94770D01*
G01X317655Y95328D02*
X317629Y95296D01*
G01X317685Y95347D02*
X317655Y95328D01*
G01X317719Y95354D02*
X317685Y95347D01*
G01X312214Y79790D02*
X312188Y79821D01*
G01X312245Y79770D02*
X312214Y79790D01*
G01X312278Y79763D02*
X312245Y79770D01*
G01X312610Y80328D02*
X312637Y80296D01*
G01X312580Y80347D02*
X312610Y80328D01*
G01X312547Y80354D02*
X312580Y80347D01*
G01X318409Y81955D02*
X318383Y81987D01*
G01X318440Y81935D02*
X318409Y81955D01*
G01X318472Y81929D02*
X318440Y81935D01*
G01X317297Y82493D02*
X317323Y82462D01*
G01X317267Y82513D02*
X317297Y82493D01*
G01X317234Y82519D02*
X317267Y82513D01*
G01X312214Y84790D02*
X312188Y84821D01*
G01X312245Y84770D02*
X312214Y84790D01*
G01X312278Y84763D02*
X312245Y84770D01*
G01X312610Y85328D02*
X312637Y85296D01*
G01X312580Y85347D02*
X312610Y85328D01*
G01X312547Y85354D02*
X312580Y85347D01*
G01X318409Y86955D02*
X318383Y86987D01*
G01X318440Y86935D02*
X318409Y86955D01*
G01X318472Y86929D02*
X318440Y86935D01*
G01X317297Y87493D02*
X317323Y87462D01*
G01X317267Y87513D02*
X317297Y87493D01*
G01X317234Y87519D02*
X317267Y87513D01*
G01X312214Y89790D02*
X312188Y89821D01*
G01X312245Y89770D02*
X312214Y89790D01*
G01X312278Y89763D02*
X312245Y89770D01*
G01X312610Y90328D02*
X312637Y90296D01*
G01X312580Y90347D02*
X312610Y90328D01*
G01X312547Y90354D02*
X312580Y90347D01*
G01X318409Y91955D02*
X318383Y91987D01*
G01X318440Y91935D02*
X318409Y91955D01*
G01X318472Y91929D02*
X318440Y91935D01*
G01X317297Y92493D02*
X317323Y92462D01*
G01X317267Y92513D02*
X317297Y92493D01*
G01X317234Y92519D02*
X317267Y92513D01*
G01X312214Y94790D02*
X312188Y94821D01*
G01X312245Y94770D02*
X312214Y94790D01*
G01X312278Y94763D02*
X312245Y94770D01*
G01X312610Y95328D02*
X312637Y95296D01*
G01X312580Y95347D02*
X312610Y95328D01*
G01X312547Y95354D02*
X312580Y95347D01*
G01X311826Y80347D02*
X311793Y80354D01*
G01X311856Y80328D02*
X311826Y80347D01*
G01X311883Y80296D02*
X311856Y80328D01*
G01X312999Y79770D02*
X313032Y79763D01*
G01X312968Y79790D02*
X312999Y79770D01*
G01X312942Y79821D02*
X312968Y79790D01*
G01X311826Y85347D02*
X311793Y85354D01*
G01X311856Y85328D02*
X311826Y85347D01*
G01X311883Y85296D02*
X311856Y85328D01*
G01X312999Y84770D02*
X313032Y84763D01*
G01X312968Y84790D02*
X312999Y84770D01*
G01X312942Y84821D02*
X312968Y84790D01*
G01X317685Y81935D02*
X317719Y81929D01*
G01X317655Y81955D02*
X317685Y81935D01*
G01X317629Y81987D02*
X317655Y81955D01*
G01X318021Y82513D02*
X317988Y82519D01*
G01X318051Y82493D02*
X318021Y82513D01*
G01X318078Y82462D02*
X318051Y82493D01*
G01X311826Y90347D02*
X311793Y90354D01*
G01X311856Y90328D02*
X311826Y90347D01*
G01X311883Y90296D02*
X311856Y90328D01*
G01X312999Y89770D02*
X313032Y89763D01*
G01X312968Y89790D02*
X312999Y89770D01*
G01X312942Y89821D02*
X312968Y89790D01*
G01X317685Y86935D02*
X317719Y86929D01*
G01X317655Y86955D02*
X317685Y86935D01*
G01X317629Y86987D02*
X317655Y86955D01*
G01X318021Y87513D02*
X317988Y87519D01*
G01X318051Y87493D02*
X318021Y87513D01*
G01X318078Y87462D02*
X318051Y87493D01*
G01X311826Y95347D02*
X311793Y95354D01*
G01X311856Y95328D02*
X311826Y95347D01*
G01X311883Y95296D02*
X311856Y95328D01*
G01X312999Y94770D02*
X313032Y94763D01*
G01X312968Y94790D02*
X312999Y94770D01*
G01X312942Y94821D02*
X312968Y94790D01*
G01X317685Y91935D02*
X317719Y91929D01*
G01X317655Y91955D02*
X317685Y91935D01*
G01X317629Y91987D02*
X317655Y91955D01*
G01X318021Y92513D02*
X317988Y92519D01*
G01X318051Y92493D02*
X318021Y92513D01*
G01X318078Y92462D02*
X318051Y92493D01*
G01X312245Y92513D02*
X312278Y92519D01*
G01X312214Y92493D02*
X312245Y92513D01*
G01X312188Y92462D02*
X312214Y92493D01*
G01X312580Y91935D02*
X312547Y91929D01*
G01X312610Y91955D02*
X312580Y91935D01*
G01X312637Y91987D02*
X312610Y91955D01*
G01X317267Y94770D02*
X317234Y94763D01*
G01X317297Y94790D02*
X317267Y94770D01*
G01X317323Y94821D02*
X317297Y94790D01*
G01X318440Y95347D02*
X318472Y95354D01*
G01X318409Y95328D02*
X318440Y95347D01*
G01X318383Y95296D02*
X318409Y95328D01*
G01X312245Y87513D02*
X312278Y87519D01*
G01X312214Y87493D02*
X312245Y87513D01*
G01X312188Y87462D02*
X312214Y87493D01*
G01X312580Y86935D02*
X312547Y86929D01*
G01X312610Y86955D02*
X312580Y86935D01*
G01X312637Y86987D02*
X312610Y86955D01*
G01X317267Y89770D02*
X317234Y89763D01*
G01X317297Y89790D02*
X317267Y89770D01*
G01X317323Y89821D02*
X317297Y89790D01*
G01X318440Y90347D02*
X318472Y90354D01*
G01X318409Y90328D02*
X318440Y90347D01*
G01X318383Y90296D02*
X318409Y90328D01*
G01X312245Y82513D02*
X312278Y82519D01*
G01X312214Y82493D02*
X312245Y82513D01*
G01X312188Y82462D02*
X312214Y82493D01*
G01X312580Y81935D02*
X312547Y81929D01*
G01X312610Y81955D02*
X312580Y81935D01*
G01X312637Y81987D02*
X312610Y81955D01*
G01X317267Y84770D02*
X317234Y84763D01*
G01X317297Y84790D02*
X317267Y84770D01*
G01X317323Y84821D02*
X317297Y84790D01*
G01X318440Y85347D02*
X318472Y85354D01*
G01X318409Y85328D02*
X318440Y85347D01*
G01X318383Y85296D02*
X318409Y85328D01*
G01X317267Y79770D02*
X317234Y79763D01*
G01X317297Y79790D02*
X317267Y79770D01*
G01X317323Y79821D02*
X317297Y79790D01*
G01X318440Y80347D02*
X318472Y80354D01*
G01X318409Y80328D02*
X318440Y80347D01*
G01X318383Y80296D02*
X318409Y80328D01*
G01X318078Y79821D02*
X318383Y80296D01*
G01X317629D02*
X317323Y79821D01*
G01X318078Y84821D02*
X318383Y85296D01*
G01X317629D02*
X317323Y84821D01*
G01X318078Y89821D02*
X318383Y90296D01*
G01X312942Y82462D02*
X312637Y81987D01*
G01X317629Y90296D02*
X317323Y89821D01*
G01X311883Y81987D02*
X312188Y82462D01*
G01X318078Y94821D02*
X318383Y95296D01*
G01X312942Y87462D02*
X312637Y86987D01*
G01X317629Y95296D02*
X317323Y94821D01*
G01X311883Y86987D02*
X312188Y87462D01*
G01X312942Y92462D02*
X312637Y91987D01*
G01X311883D02*
X312188Y92462D01*
G01X319680Y95354D02*
Y96929D01*
G01Y90354D02*
Y91929D01*
G01Y85354D02*
Y86929D01*
G01Y81929D02*
Y80354D01*
G01X318926Y81929D02*
Y80354D01*
G01Y86929D02*
Y85354D01*
G01Y91929D02*
Y90354D01*
G01Y96929D02*
Y95354D01*
G01X318172Y85354D02*
Y86929D01*
G01Y80354D02*
Y81929D01*
G01Y91929D02*
Y90354D01*
G01Y96929D02*
Y95354D01*
G01X317772Y93563D02*
Y94429D01*
G01Y84114D02*
Y84980D01*
G01Y81830D02*
Y80964D01*
G01Y88130D02*
Y87263D01*
G01Y91279D02*
Y90413D01*
G01X312069Y95354D02*
Y96929D01*
G01Y90354D02*
Y91929D01*
G01Y85354D02*
Y86929D01*
G01Y80354D02*
Y81929D01*
G01X311315D02*
Y80354D01*
G01Y86929D02*
Y85354D01*
G01Y91929D02*
Y90354D01*
G01Y96929D02*
Y95354D01*
G01X310561Y81929D02*
Y80354D01*
G01Y86929D02*
Y85354D01*
G01Y91929D02*
Y90354D01*
G01Y96929D02*
Y95354D01*
G01X307806Y81929D02*
Y80354D01*
G01Y86929D02*
Y85354D01*
G01Y91929D02*
Y90354D01*
G01Y96929D02*
Y95354D01*
G01X318383Y91987D02*
X318078Y92462D01*
G01X317323D02*
X317629Y91987D01*
G01X318383Y86987D02*
X318078Y87462D01*
G01X312637Y95296D02*
X312942Y94821D01*
G01X317323Y87462D02*
X317629Y86987D01*
G01X312188Y94821D02*
X311883Y95296D01*
G01X318383Y81987D02*
X318078Y82462D01*
G01X312637Y90296D02*
X312942Y89821D01*
G01X317323Y82462D02*
X317629Y81987D01*
G01X312188Y89821D02*
X311883Y90296D01*
G01X312637Y85296D02*
X312942Y84821D01*
G01X312188D02*
X311883Y85296D01*
G01X312637Y80296D02*
X312942Y79821D01*
G01X312188D02*
X311883Y80296D01*
G01X317719Y95354D02*
X320271D01*
G01X307806D02*
X312547D01*
G01X311883Y95296D02*
X312637D01*
G01X318383D02*
X317629D01*
G01X317323Y94821D02*
X318078D01*
G01X312942D02*
X312188D01*
G01X317988Y94763D02*
X312278D01*
G01X317772Y94429D02*
X322727D01*
G01Y93563D02*
X317772D01*
G01X312278Y92519D02*
X317988D01*
G01X317323Y92462D02*
X318078D01*
G01X312942D02*
X312188D01*
G01X312637Y91987D02*
X311883D01*
G01X318383D02*
X317629D01*
G01X317719Y91929D02*
X320271D01*
G01X307806D02*
X312547D01*
G01X317772Y91279D02*
X322727D01*
G01Y90413D02*
X317772D01*
G01X317719Y90354D02*
X320271D01*
G01X307806D02*
X312547D01*
G01X311883Y90296D02*
X312637D01*
G01X318383D02*
X317629D01*
G01X317323Y89821D02*
X318078D01*
G01X312942D02*
X312188D01*
G01X317988Y89763D02*
X312278D01*
G01X317772Y88130D02*
X322727D01*
G01X312278Y87519D02*
X317988D01*
G01X312942Y87462D02*
X312188D01*
G01X318078D02*
X317323D01*
G01X322727Y87263D02*
X317772D01*
G01X311883Y86987D02*
X312637D01*
G01X318383D02*
X317629D01*
G01X317719Y86929D02*
X320271D01*
G01X307806D02*
X312547D01*
G01X317719Y85354D02*
X320271D01*
G01X307806D02*
X312547D01*
G01X311883Y85296D02*
X312637D01*
G01X318383D02*
X317629D01*
G01X317772Y84980D02*
X322727D01*
G01X317323Y84821D02*
X318078D01*
G01X312942D02*
X312188D01*
G01X317988Y84763D02*
X312278D01*
G01X322727Y84114D02*
X317772D01*
G01X312278Y82519D02*
X317988D01*
G01X317323Y82462D02*
X318078D01*
G01X312942D02*
X312188D01*
G01X312637Y81987D02*
X311883D01*
G01X318383D02*
X317629D01*
G01X317719Y81929D02*
X320271D01*
G01X307806D02*
X312547D01*
G01X317772Y81830D02*
X322727D01*
G01Y80964D02*
X317772D01*
G01X317719Y80354D02*
X320271D01*
G01X307806D02*
X312547D01*
G01X311883Y80296D02*
X312637D01*
G01X318383D02*
X317629D01*
G01X317323Y79821D02*
X318078D01*
G01X312942D02*
X312188D01*
G01X317988Y79763D02*
X312278D01*
G01X311856Y96955D02*
X311883Y96987D01*
G01X311826Y96935D02*
X311856Y96955D01*
G01X311793Y96929D02*
X311826Y96935D01*
G01X312968Y97493D02*
X312942Y97462D01*
G01X312999Y97513D02*
X312968Y97493D01*
G01X313032Y97519D02*
X312999Y97513D01*
G01X318051Y99790D02*
X318078Y99821D01*
G01X318021Y99770D02*
X318051Y99790D01*
G01X317988Y99763D02*
X318021Y99770D01*
G01X317655Y100328D02*
X317629Y100296D01*
G01X317685Y100347D02*
X317655Y100328D01*
G01X317719Y100354D02*
X317685Y100347D01*
G01X311856Y101955D02*
X311883Y101987D01*
G01X311826Y101935D02*
X311856Y101955D01*
G01X311793Y101929D02*
X311826Y101935D01*
G01X312968Y102493D02*
X312942Y102462D01*
G01X312999Y102513D02*
X312968Y102493D01*
G01X313032Y102519D02*
X312999Y102513D01*
G01X318051Y104790D02*
X318078Y104821D01*
G01X318021Y104770D02*
X318051Y104790D01*
G01X317988Y104763D02*
X318021Y104770D01*
G01X317655Y105328D02*
X317629Y105296D01*
G01X317685Y105347D02*
X317655Y105328D01*
G01X317719Y105354D02*
X317685Y105347D01*
G01X311856Y106955D02*
X311883Y106987D01*
G01X311826Y106935D02*
X311856Y106955D01*
G01X311793Y106929D02*
X311826Y106935D01*
G01X312968Y107493D02*
X312942Y107462D01*
G01X312999Y107513D02*
X312968Y107493D01*
G01X313032Y107519D02*
X312999Y107513D01*
G01X318051Y109790D02*
X318078Y109821D01*
G01X318021Y109770D02*
X318051Y109790D01*
G01X317988Y109763D02*
X318021Y109770D01*
G01X317655Y110328D02*
X317629Y110296D01*
G01X317685Y110347D02*
X317655Y110328D01*
G01X317719Y110354D02*
X317685Y110347D01*
G01X311856Y111955D02*
X311883Y111987D01*
G01X311826Y111935D02*
X311856Y111955D01*
G01X311793Y111929D02*
X311826Y111935D01*
G01X318409Y96955D02*
X318383Y96987D01*
G01X318440Y96935D02*
X318409Y96955D01*
G01X318472Y96929D02*
X318440Y96935D01*
G01X317297Y97493D02*
X317323Y97462D01*
G01X317267Y97513D02*
X317297Y97493D01*
G01X317234Y97519D02*
X317267Y97513D01*
G01X312214Y99790D02*
X312188Y99821D01*
G01X312245Y99770D02*
X312214Y99790D01*
G01X312278Y99763D02*
X312245Y99770D01*
G01X312610Y100328D02*
X312637Y100296D01*
G01X312580Y100347D02*
X312610Y100328D01*
G01X312547Y100354D02*
X312580Y100347D01*
G01X318409Y101955D02*
X318383Y101987D01*
G01X318440Y101935D02*
X318409Y101955D01*
G01X318472Y101929D02*
X318440Y101935D01*
G01X317297Y102493D02*
X317323Y102462D01*
G01X317267Y102513D02*
X317297Y102493D01*
G01X317234Y102519D02*
X317267Y102513D01*
G01X312214Y104790D02*
X312188Y104821D01*
G01X312245Y104770D02*
X312214Y104790D01*
G01X312278Y104763D02*
X312245Y104770D01*
G01X312610Y105328D02*
X312637Y105296D01*
G01X312580Y105347D02*
X312610Y105328D01*
G01X312547Y105354D02*
X312580Y105347D01*
G01X318409Y106955D02*
X318383Y106987D01*
G01X318440Y106935D02*
X318409Y106955D01*
G01X318472Y106929D02*
X318440Y106935D01*
G01X317297Y107493D02*
X317323Y107462D01*
G01X317267Y107513D02*
X317297Y107493D01*
G01X317234Y107519D02*
X317267Y107513D01*
G01X312214Y109790D02*
X312188Y109821D01*
G01X312245Y109770D02*
X312214Y109790D01*
G01X312278Y109763D02*
X312245Y109770D01*
G01X312610Y110328D02*
X312637Y110296D01*
G01X312580Y110347D02*
X312610Y110328D01*
G01X312547Y110354D02*
X312580Y110347D01*
G01X318409Y111955D02*
X318383Y111987D01*
G01X318440Y111935D02*
X318409Y111955D01*
G01X318472Y111929D02*
X318440Y111935D01*
G01X311826Y100347D02*
X311793Y100354D01*
G01X311856Y100328D02*
X311826Y100347D01*
G01X311883Y100296D02*
X311856Y100328D01*
G01X312999Y99770D02*
X313032Y99763D01*
G01X312968Y99790D02*
X312999Y99770D01*
G01X312942Y99821D02*
X312968Y99790D01*
G01X317685Y96935D02*
X317719Y96929D01*
G01X317655Y96955D02*
X317685Y96935D01*
G01X317629Y96987D02*
X317655Y96955D01*
G01X318021Y97513D02*
X317988Y97519D01*
G01X318051Y97493D02*
X318021Y97513D01*
G01X318078Y97462D02*
X318051Y97493D01*
G01X311826Y105347D02*
X311793Y105354D01*
G01X311856Y105328D02*
X311826Y105347D01*
G01X311883Y105296D02*
X311856Y105328D01*
G01X312999Y104770D02*
X313032Y104763D01*
G01X312968Y104790D02*
X312999Y104770D01*
G01X312942Y104821D02*
X312968Y104790D01*
G01X317685Y101935D02*
X317719Y101929D01*
G01X317655Y101955D02*
X317685Y101935D01*
G01X317629Y101987D02*
X317655Y101955D01*
G01X318021Y102513D02*
X317988Y102519D01*
G01X318051Y102493D02*
X318021Y102513D01*
G01X318078Y102462D02*
X318051Y102493D01*
G01X311826Y110347D02*
X311793Y110354D01*
G01X311856Y110328D02*
X311826Y110347D01*
G01X311883Y110296D02*
X311856Y110328D01*
G01X312999Y109770D02*
X313032Y109763D01*
G01X312968Y109790D02*
X312999Y109770D01*
G01X312942Y109821D02*
X312968Y109790D01*
G01X317685Y106935D02*
X317719Y106929D01*
G01X317655Y106955D02*
X317685Y106935D01*
G01X317629Y106987D02*
X317655Y106955D01*
G01X318021Y107513D02*
X317988Y107519D01*
G01X318051Y107493D02*
X318021Y107513D01*
G01X318078Y107462D02*
X318051Y107493D01*
G01X317685Y111935D02*
X317719Y111929D01*
G01X317655Y111955D02*
X317685Y111935D01*
G01X317629Y111987D02*
X317655Y111955D01*
G01X312580Y111935D02*
X312547Y111929D01*
G01X312610Y111955D02*
X312580Y111935D01*
G01X312637Y111987D02*
X312610Y111955D01*
G01X312245Y107513D02*
X312278Y107519D01*
G01X312214Y107493D02*
X312245Y107513D01*
G01X312188Y107462D02*
X312214Y107493D01*
G01X312580Y106935D02*
X312547Y106929D01*
G01X312610Y106955D02*
X312580Y106935D01*
G01X312637Y106987D02*
X312610Y106955D01*
G01X317267Y109770D02*
X317234Y109763D01*
G01X317297Y109790D02*
X317267Y109770D01*
G01X317323Y109821D02*
X317297Y109790D01*
G01X318440Y110347D02*
X318472Y110354D01*
G01X318409Y110328D02*
X318440Y110347D01*
G01X318383Y110296D02*
X318409Y110328D01*
G01X312245Y102513D02*
X312278Y102519D01*
G01X312214Y102493D02*
X312245Y102513D01*
G01X312188Y102462D02*
X312214Y102493D01*
G01X312580Y101935D02*
X312547Y101929D01*
G01X312610Y101955D02*
X312580Y101935D01*
G01X312637Y101987D02*
X312610Y101955D01*
G01X317267Y104770D02*
X317234Y104763D01*
G01X317297Y104790D02*
X317267Y104770D01*
G01X317323Y104821D02*
X317297Y104790D01*
G01X318440Y105347D02*
X318472Y105354D01*
G01X318409Y105328D02*
X318440Y105347D01*
G01X318383Y105296D02*
X318409Y105328D01*
G01X312245Y97513D02*
X312278Y97519D01*
G01X312214Y97493D02*
X312245Y97513D01*
G01X312188Y97462D02*
X312214Y97493D01*
G01X312580Y96935D02*
X312547Y96929D01*
G01X312610Y96955D02*
X312580Y96935D01*
G01X312637Y96987D02*
X312610Y96955D01*
G01X317267Y99770D02*
X317234Y99763D01*
G01X317297Y99790D02*
X317267Y99770D01*
G01X317323Y99821D02*
X317297Y99790D01*
G01X318440Y100347D02*
X318472Y100354D01*
G01X318409Y100328D02*
X318440Y100347D01*
G01X318383Y100296D02*
X318409Y100328D01*
G01X318078Y99821D02*
X318383Y100296D01*
G01X317629D02*
X317323Y99821D01*
G01X318078Y104821D02*
X318383Y105296D01*
G01X312942Y97462D02*
X312637Y96987D01*
G01X317629Y105296D02*
X317323Y104821D01*
G01X311883Y96987D02*
X312188Y97462D01*
G01X318078Y109821D02*
X318383Y110296D01*
G01X312942Y102462D02*
X312637Y101987D01*
G01X317629Y110296D02*
X317323Y109821D01*
G01X311883Y101987D02*
X312188Y102462D01*
G01X312942Y107462D02*
X312637Y106987D01*
G01X311883D02*
X312188Y107462D01*
G01X312942Y112462D02*
X312637Y111987D01*
G01X311883D02*
X312188Y112462D01*
G01X319680Y105354D02*
Y106929D01*
G01Y100354D02*
Y101929D01*
G01Y111929D02*
Y110354D01*
G01X318926Y101929D02*
Y100354D01*
G01Y106929D02*
Y105354D01*
G01Y111929D02*
Y110354D01*
G01X318172D02*
Y111929D01*
G01Y105354D02*
Y106929D01*
G01Y101929D02*
Y100354D01*
G01X317772Y103011D02*
Y103878D01*
G01Y97578D02*
Y96712D01*
G01Y100728D02*
Y99862D01*
G01Y107027D02*
Y106161D01*
G01Y110177D02*
Y109311D01*
G01X312069Y110354D02*
Y111929D01*
G01Y105354D02*
Y106929D01*
G01Y100354D02*
Y101929D01*
G01X311315D02*
Y100354D01*
G01Y106929D02*
Y105354D01*
G01Y111929D02*
Y110354D01*
G01X310561Y101929D02*
Y100354D01*
G01Y106929D02*
Y105354D01*
G01Y111929D02*
Y110354D01*
G01X307806Y101929D02*
Y100354D01*
G01Y106929D02*
Y105354D01*
G01Y111929D02*
Y110354D01*
G01X318383Y111987D02*
X318078Y112462D01*
G01X317323D02*
X317629Y111987D01*
G01X318383Y106987D02*
X318078Y107462D01*
G01X317323D02*
X317629Y106987D01*
G01X318383Y101987D02*
X318078Y102462D01*
G01X312637Y110296D02*
X312942Y109821D01*
G01X317323Y102462D02*
X317629Y101987D01*
G01X312188Y109821D02*
X311883Y110296D01*
G01X318383Y96987D02*
X318078Y97462D01*
G01X312637Y105296D02*
X312942Y104821D01*
G01X317323Y97462D02*
X317629Y96987D01*
G01X312188Y104821D02*
X311883Y105296D01*
G01X312637Y100296D02*
X312942Y99821D01*
G01X312188D02*
X311883Y100296D01*
G01X312637Y111987D02*
X311883D01*
G01X318383D02*
X317629D01*
G01X317719Y111929D02*
X320271D01*
G01X307806D02*
X312547D01*
G01X317719Y110354D02*
X320271D01*
G01X307806D02*
X312547D01*
G01X311883Y110296D02*
X312637D01*
G01X318383D02*
X317629D01*
G01X317772Y110177D02*
X322727D01*
G01X317323Y109821D02*
X318078D01*
G01X312942D02*
X312188D01*
G01X317988Y109763D02*
X312278D01*
G01X322727Y109311D02*
X317772D01*
G01X312278Y107519D02*
X317988D01*
G01X312942Y107462D02*
X312188D01*
G01X318078D02*
X317323D01*
G01X317772Y107027D02*
X322727D01*
G01X311883Y106987D02*
X312637D01*
G01X318383D02*
X317629D01*
G01X317719Y106929D02*
X320271D01*
G01X307806D02*
X312547D01*
G01X322727Y106161D02*
X317772D01*
G01X317719Y105354D02*
X320271D01*
G01X307806D02*
X312547D01*
G01X311883Y105296D02*
X312637D01*
G01X318383D02*
X317629D01*
G01X317323Y104821D02*
X318078D01*
G01X312942D02*
X312188D01*
G01X317988Y104763D02*
X312278D01*
G01X317772Y103878D02*
X322727D01*
G01Y103011D02*
X317772D01*
G01X312278Y102519D02*
X317988D01*
G01X317323Y102462D02*
X318078D01*
G01X312942D02*
X312188D01*
G01X312637Y101987D02*
X311883D01*
G01X318383D02*
X317629D01*
G01X317719Y101929D02*
X320271D01*
G01X307806D02*
X312547D01*
G01X317772Y100728D02*
X322727D01*
G01X317719Y100354D02*
X320271D01*
G01X307806D02*
X312547D01*
G01X311883Y100296D02*
X312637D01*
G01X318383D02*
X317629D01*
G01X322727Y99862D02*
X317772D01*
G01X317323Y99821D02*
X318078D01*
G01X312942D02*
X312188D01*
G01X317988Y99763D02*
X312278D01*
G01X317772Y97578D02*
X322727D01*
G01X312278Y97519D02*
X317988D01*
G01X317323Y97462D02*
X318078D01*
G01X312942D02*
X312188D01*
G01X312637Y96987D02*
X311883D01*
G01X318383D02*
X317629D01*
G01X317719Y96929D02*
X320271D01*
G01X307806D02*
X312547D01*
G01X322727Y96712D02*
X317772D01*
G01X312968Y112493D02*
X312942Y112462D01*
G01X312999Y112513D02*
X312968Y112493D01*
G01X313032Y112519D02*
X312999Y112513D01*
G01X318051Y114790D02*
X318078Y114821D01*
G01X318021Y114770D02*
X318051Y114790D01*
G01X317988Y114763D02*
X318021Y114770D01*
G01X317655Y115328D02*
X317629Y115296D01*
G01X317685Y115347D02*
X317655Y115328D01*
G01X317719Y115354D02*
X317685Y115347D01*
G01X311856Y116955D02*
X311883Y116987D01*
G01X311826Y116935D02*
X311856Y116955D01*
G01X311793Y116929D02*
X311826Y116935D01*
G01X312968Y117493D02*
X312942Y117462D01*
G01X312999Y117513D02*
X312968Y117493D01*
G01X313032Y117519D02*
X312999Y117513D01*
G01X320063Y120052D02*
X320037Y120021D01*
G01X320094Y120072D02*
X320063Y120052D01*
G01X320127Y120078D02*
X320094Y120072D01*
G01X311861Y121128D02*
X311887Y121160D01*
G01X311830Y121109D02*
X311861Y121128D01*
G01X311797Y121102D02*
X311830Y121109D01*
G01X312670Y121430D02*
X312644Y121399D01*
G01X312700Y121450D02*
X312670Y121430D01*
G01X312733Y121456D02*
X312700Y121450D01*
G01X311861Y124278D02*
X311887Y124309D01*
G01X311830Y124258D02*
X311861Y124278D01*
G01X311797Y124252D02*
X311830Y124258D01*
G01X312670Y124580D02*
X312644Y124548D01*
G01X312700Y124599D02*
X312670Y124580D01*
G01X312733Y124606D02*
X312700Y124599D01*
G01X311861Y127428D02*
X311887Y127459D01*
G01X311830Y127408D02*
X311861Y127428D01*
G01X311797Y127401D02*
X311830Y127408D01*
G01X312670Y127729D02*
X312644Y127698D01*
G01X312700Y127749D02*
X312670Y127729D01*
G01X312733Y127756D02*
X312700Y127749D01*
G01X317297Y112493D02*
X317323Y112462D01*
G01X317267Y112513D02*
X317297Y112493D01*
G01X317234Y112519D02*
X317267Y112513D01*
G01X312214Y114790D02*
X312188Y114821D01*
G01X312245Y114770D02*
X312214Y114790D01*
G01X312278Y114763D02*
X312245Y114770D01*
G01X312610Y115328D02*
X312637Y115296D01*
G01X312580Y115347D02*
X312610Y115328D01*
G01X312547Y115354D02*
X312580Y115347D01*
G01X318409Y116955D02*
X318383Y116987D01*
G01X318440Y116935D02*
X318409Y116955D01*
G01X318472Y116929D02*
X318440Y116935D01*
G01X317297Y117493D02*
X317323Y117462D01*
G01X317267Y117513D02*
X317297Y117493D01*
G01X317234Y117519D02*
X317267Y117513D01*
G01X312067Y119908D02*
X312041Y119939D01*
G01X312097Y119888D02*
X312067Y119908D01*
G01X312130Y119882D02*
X312097Y119888D01*
G01X312464Y120209D02*
X312490Y120178D01*
G01X312433Y120229D02*
X312464Y120209D01*
G01X312400Y120236D02*
X312433Y120229D01*
G01X312067Y123058D02*
X312041Y123089D01*
G01X312097Y123038D02*
X312067Y123058D01*
G01X312130Y123031D02*
X312097Y123038D01*
G01X319959Y121430D02*
X319985Y121399D01*
G01X319928Y121450D02*
X319959Y121430D01*
G01X319895Y121456D02*
X319928Y121450D01*
G01X312464Y123359D02*
X312490Y123328D01*
G01X312433Y123379D02*
X312464Y123359D01*
G01X312400Y123385D02*
X312433Y123379D01*
G01X312067Y126207D02*
X312041Y126239D01*
G01X312097Y126187D02*
X312067Y126207D01*
G01X312130Y126181D02*
X312097Y126187D01*
G01X312464Y126509D02*
X312490Y126478D01*
G01X312433Y126528D02*
X312464Y126509D01*
G01X312400Y126535D02*
X312433Y126528D01*
G01X311826Y115347D02*
X311793Y115354D01*
G01X311856Y115328D02*
X311826Y115347D01*
G01X311883Y115296D02*
X311856Y115328D01*
G01X312999Y114770D02*
X313032Y114763D01*
G01X312968Y114790D02*
X312999Y114770D01*
G01X312942Y114821D02*
X312968Y114790D01*
G01X318021Y112513D02*
X317988Y112519D01*
G01X318051Y112493D02*
X318021Y112513D01*
G01X318078Y112462D02*
X318051Y112493D01*
G01X311830Y120229D02*
X311797Y120236D01*
G01X311861Y120209D02*
X311830Y120229D01*
G01X311887Y120178D02*
X311861Y120209D01*
G01X312700Y119888D02*
X312733Y119882D01*
G01X312670Y119908D02*
X312700Y119888D01*
G01X312644Y119939D02*
X312670Y119908D01*
G01X311830Y123379D02*
X311797Y123385D01*
G01X311861Y123359D02*
X311830Y123379D01*
G01X311887Y123328D02*
X311861Y123359D01*
G01X317685Y116935D02*
X317719Y116929D01*
G01X317655Y116955D02*
X317685Y116935D01*
G01X317629Y116987D02*
X317655Y116955D01*
G01X312700Y123038D02*
X312733Y123031D01*
G01X312670Y123058D02*
X312700Y123038D01*
G01X312644Y123089D02*
X312670Y123058D01*
G01X318021Y117513D02*
X317988Y117519D01*
G01X318051Y117493D02*
X318021Y117513D01*
G01X318078Y117462D02*
X318051Y117493D01*
G01X311830Y126528D02*
X311797Y126535D01*
G01X311861Y126509D02*
X311830Y126528D01*
G01X311887Y126478D02*
X311861Y126509D01*
G01X312700Y126187D02*
X312733Y126181D01*
G01X312670Y126207D02*
X312700Y126187D01*
G01X312644Y126239D02*
X312670Y126207D01*
G01X320094Y121266D02*
X320127Y121259D01*
G01X320063Y121286D02*
X320094Y121266D01*
G01X320037Y121317D02*
X320063Y121286D01*
G01X312097Y127749D02*
X312130Y127756D01*
G01X312067Y127729D02*
X312097Y127749D01*
G01X312041Y127698D02*
X312067Y127729D01*
G01X312433Y127408D02*
X312400Y127401D01*
G01X312464Y127428D02*
X312433Y127408D01*
G01X312490Y127459D02*
X312464Y127428D01*
G01X312097Y124599D02*
X312130Y124606D01*
G01X312067Y124580D02*
X312097Y124599D01*
G01X312041Y124548D02*
X312067Y124580D01*
G01X312433Y124258D02*
X312400Y124252D01*
G01X312464Y124278D02*
X312433Y124258D01*
G01X312490Y124309D02*
X312464Y124278D01*
G01X312097Y121450D02*
X312130Y121456D01*
G01X312067Y121430D02*
X312097Y121450D01*
G01X312041Y121399D02*
X312067Y121430D01*
G01X312433Y121109D02*
X312400Y121102D01*
G01X312464Y121128D02*
X312433Y121109D01*
G01X312490Y121160D02*
X312464Y121128D01*
G01X312245Y117513D02*
X312278Y117519D01*
G01X312214Y117493D02*
X312245Y117513D01*
G01X312188Y117462D02*
X312214Y117493D01*
G01X312580Y116935D02*
X312547Y116929D01*
G01X312610Y116955D02*
X312580Y116935D01*
G01X312637Y116987D02*
X312610Y116955D01*
G01X312245Y112513D02*
X312278Y112519D01*
G01X312214Y112493D02*
X312245Y112513D01*
G01X312188Y112462D02*
X312214Y112493D01*
G01X319928Y119888D02*
X319895Y119882D01*
G01X319959Y119908D02*
X319928Y119888D01*
G01X319985Y119939D02*
X319959Y119908D01*
G01X317267Y114770D02*
X317234Y114763D01*
G01X317297Y114790D02*
X317267Y114770D01*
G01X317323Y114821D02*
X317297Y114790D01*
G01X318440Y115347D02*
X318472Y115354D01*
G01X318409Y115328D02*
X318440Y115347D01*
G01X318383Y115296D02*
X318409Y115328D01*
G01X318078Y114821D02*
X318383Y115296D01*
G01X317629D02*
X317323Y114821D01*
G01X320037Y120021D02*
X319985Y119939D01*
G01X320074Y123228D02*
X319948Y123031D01*
G01X309009Y115916D02*
X308970Y115876D01*
G01X309069Y115836D02*
X309128Y115916D01*
G01X320074Y126378D02*
X319948Y126181D01*
G01X312942Y117462D02*
X312637Y116987D01*
G01X311883D02*
X312188Y117462D01*
G01X312644Y121399D02*
X312490Y121160D01*
G01X311887D02*
X312041Y121399D01*
G01X312644Y124548D02*
X312490Y124309D01*
G01X311887D02*
X312041Y124548D01*
G01X312644Y127698D02*
X312490Y127459D01*
G01X311887D02*
X312041Y127698D01*
G01X309128Y115916D02*
X309147Y115976D01*
G01X309029D02*
X309009Y115916D01*
G01X319680Y116929D02*
Y115354D01*
G01X318926Y116929D02*
Y115354D01*
G01X318835Y119536D02*
Y119094D01*
G01Y122686D02*
Y121802D01*
G01Y125835D02*
Y124952D01*
G01Y128985D02*
Y128101D01*
G01X318637Y122913D02*
Y124724D01*
G01Y121574D02*
Y119763D01*
G01Y127874D02*
Y126063D01*
G01X318243D02*
Y127874D01*
G01Y121574D02*
Y119763D01*
G01Y124724D02*
Y122913D01*
G01X318172Y115354D02*
Y116929D01*
G01X317913Y137992D02*
Y119094D01*
G01X317772Y128208D02*
Y129074D01*
G01Y118759D02*
Y119626D01*
G01Y112460D02*
Y113326D01*
G01Y116476D02*
Y115610D01*
G01Y122775D02*
Y121909D01*
G01Y125925D02*
Y125059D01*
G01X312069Y115354D02*
Y116929D01*
G01X308990Y115775D02*
X309069Y115836D01*
G01X311315Y116929D02*
Y115354D01*
G01X311236Y126535D02*
Y127401D01*
G01Y123385D02*
Y124252D01*
G01Y120236D02*
Y121102D01*
G01X310633Y126535D02*
Y127401D01*
G01Y123385D02*
Y124252D01*
G01Y120236D02*
Y121102D01*
G01X310561Y116929D02*
Y115354D01*
G01X309879Y121102D02*
Y120236D01*
G01Y124252D02*
Y123385D01*
G01Y127401D02*
Y126535D01*
G01X309541Y115755D02*
Y116700D01*
G01X309423D02*
Y115916D01*
G01X309305Y116057D02*
Y115896D01*
G01X309147Y115976D02*
Y116057D01*
G01X309029Y116037D02*
Y115976D01*
G01X308537Y115856D02*
Y116158D01*
G01Y116278D02*
Y116700D01*
G01X308419D02*
Y115755D01*
G01X307806Y116929D02*
Y115354D01*
G01X307719Y126535D02*
Y127401D01*
G01Y123385D02*
Y124252D01*
G01Y120236D02*
Y121102D01*
G01X309147Y116057D02*
X309128Y116117D01*
G01X309009Y116097D02*
X309029Y116037D01*
G01X308970Y115876D02*
X308911Y115856D01*
G01X319393Y119763D02*
X318835Y119536D01*
G01X319393Y122913D02*
X318835Y122686D01*
G01X319393Y126063D02*
X318835Y125835D01*
G01X319948Y127756D02*
X320074Y127559D01*
G01X319948Y124606D02*
X320074Y124409D01*
G01X319985Y121399D02*
X320037Y121317D01*
G01X312490Y126478D02*
X312644Y126239D01*
G01X318383Y116987D02*
X318078Y117462D01*
G01X312041Y126239D02*
X311887Y126478D01*
G01X317323Y117462D02*
X317629Y116987D01*
G01X312490Y123328D02*
X312644Y123089D01*
G01X312041D02*
X311887Y123328D01*
G01X312490Y120178D02*
X312644Y119939D01*
G01X312041D02*
X311887Y120178D01*
G01X312637Y115296D02*
X312942Y114821D01*
G01X312188D02*
X311883Y115296D01*
G01X309128Y116117D02*
X309069Y116198D01*
G01X309423Y115916D02*
X309305Y116057D01*
G01Y115896D02*
X309423Y115755D01*
G01X308970Y116137D02*
X309009Y116097D01*
G01X309069Y116198D02*
X308990Y116258D01*
G01X318835Y128101D02*
X319393Y127874D01*
G01X318835Y124952D02*
X319393Y124724D01*
G01X318835Y121802D02*
X319393Y121574D01*
G01X308911Y116158D02*
X308970Y116137D01*
G01X308990Y116258D02*
X308891Y116278D01*
G01X322727Y128208D02*
X317772D01*
G01X318835Y128101D02*
X317913D01*
G01X321219Y127874D02*
X317913D01*
G01X312130Y127756D02*
X320551D01*
G01X312041Y127698D02*
X312644D01*
G01X320074Y127559D02*
X323245D01*
G01X312490Y127459D02*
X311887D01*
G01X307719Y127401D02*
X312400D01*
G01Y126535D02*
X307720D01*
G01X311887Y126478D02*
X312490D01*
G01X320074Y126378D02*
X323245D01*
G01X312644Y126239D02*
X312041D01*
G01X312130Y126181D02*
X320551D01*
G01X317913Y126063D02*
X321219D01*
G01X317772Y125925D02*
X322727D01*
G01X318835Y125835D02*
X317913D01*
G01X322727Y125059D02*
X317772D01*
G01X317913Y124952D02*
X318835D01*
G01X321219Y124724D02*
X317913D01*
G01X312130Y124606D02*
X320551D01*
G01X312041Y124548D02*
X312644D01*
G01X320074Y124409D02*
X323245D01*
G01X312490Y124309D02*
X311887D01*
G01X307719Y124252D02*
X312400D01*
G01Y123385D02*
X307720D01*
G01X311887Y123328D02*
X312490D01*
G01X320074Y123228D02*
X323245D01*
G01X312644Y123089D02*
X312041D01*
G01X312130Y123031D02*
X320551D01*
G01X317913Y122913D02*
X321219D01*
G01X317772Y122775D02*
X322727D01*
G01X318835Y122686D02*
X317913D01*
G01X322727Y121909D02*
X317772D01*
G01X317913Y121802D02*
X318835D01*
G01X321219Y121574D02*
X317913D01*
G01X312130Y121456D02*
X320499D01*
G01X312041Y121399D02*
X312644D01*
G01X320588D02*
X319985D01*
G01X320037Y121317D02*
X320641D01*
G01X320127Y121259D02*
X323245D01*
G01X312490Y121160D02*
X311887D01*
G01X307719Y121102D02*
X312400D01*
G01Y120236D02*
X307720D01*
G01X311887Y120178D02*
X312490D01*
G01X320127Y120078D02*
X323245D01*
G01X320641Y120021D02*
X320037D01*
G01X319985Y119939D02*
X320588D01*
G01X312644D02*
X312041D01*
G01X312130Y119882D02*
X320499D01*
G01X317913Y119763D02*
X321219D01*
G01X317772Y119626D02*
X322727D01*
G01X317913Y119536D02*
X318835D01*
G01X323819Y119094D02*
X317913D01*
G01X322727Y118759D02*
X317772D01*
G01X312278Y117519D02*
X317988D01*
G01X312942Y117462D02*
X312188D01*
G01X318078D02*
X317323D01*
G01X311883Y116987D02*
X312637D01*
G01X318383D02*
X317629D01*
G01X317719Y116929D02*
X320271D01*
G01X307806D02*
X312547D01*
G01X309541Y116700D02*
X309423D01*
G01X308537D02*
X308419D01*
G01X317772Y116476D02*
X322727D01*
G01X308891Y116278D02*
X308537D01*
G01Y116158D02*
X308911D01*
G01Y115856D02*
X308537D01*
G01X309423Y115755D02*
X309541D01*
G01X308419D02*
X308891D01*
G01X322727Y115610D02*
X317772D01*
G01X317719Y115354D02*
X320271D01*
G01X307806D02*
X312547D01*
G01X311883Y115296D02*
X312637D01*
G01X318383D02*
X317629D01*
G01X317323Y114821D02*
X318078D01*
G01X312942D02*
X312188D01*
G01X317988Y114763D02*
X312278D01*
G01X317772Y113326D02*
X322727D01*
G01X312278Y112519D02*
X317988D01*
G01X317323Y112462D02*
X317772Y112460D01*
G01X312942Y112462D02*
X312188D01*
G01X322727Y112460D02*
X317772D01*
G01X308891Y115755D02*
X308990Y115775D01*
G01X320063Y129501D02*
X320037Y129470D01*
G01X320094Y129520D02*
X320063Y129501D01*
G01X320127Y129527D02*
X320094Y129520D01*
G01X311861Y130577D02*
X311887Y130609D01*
G01X311830Y130558D02*
X311861Y130577D01*
G01X311797Y130551D02*
X311830Y130558D01*
G01X312670Y130879D02*
X312644Y130848D01*
G01X312700Y130898D02*
X312670Y130879D01*
G01X312733Y130905D02*
X312700Y130898D01*
G01X311861Y133727D02*
X311887Y133758D01*
G01X311830Y133707D02*
X311861Y133727D01*
G01X311797Y133700D02*
X311830Y133707D01*
G01X312670Y134028D02*
X312644Y133997D01*
G01X312700Y134048D02*
X312670Y134028D01*
G01X312733Y134055D02*
X312700Y134048D01*
G01X311861Y136876D02*
X311887Y136908D01*
G01X311830Y136857D02*
X311861Y136876D01*
G01X311797Y136850D02*
X311830Y136857D01*
G01X312670Y137178D02*
X312644Y137147D01*
G01X312700Y137198D02*
X312670Y137178D01*
G01X312733Y137204D02*
X312700Y137198D01*
G01X318051Y139790D02*
X318078Y139821D01*
G01X318021Y139770D02*
X318051Y139790D01*
G01X317988Y139763D02*
X318021Y139770D01*
G01X317655Y140328D02*
X317629Y140296D01*
G01X317685Y140347D02*
X317655Y140328D01*
G01X317719Y140354D02*
X317685Y140347D01*
G01X311856Y141955D02*
X311883Y141987D01*
G01X311826Y141935D02*
X311856Y141955D01*
G01X311793Y141929D02*
X311826Y141935D01*
G01X312968Y142493D02*
X312942Y142462D01*
G01X312999Y142513D02*
X312968Y142493D01*
G01X313032Y142519D02*
X312999Y142513D01*
G01X318051Y144790D02*
X318078Y144821D01*
G01X318021Y144770D02*
X318051Y144790D01*
G01X317988Y144763D02*
X318021Y144770D01*
G01X312067Y129357D02*
X312041Y129388D01*
G01X312097Y129337D02*
X312067Y129357D01*
G01X312130Y129330D02*
X312097Y129337D01*
G01X312464Y129658D02*
X312490Y129627D01*
G01X312433Y129678D02*
X312464Y129658D01*
G01X312400Y129685D02*
X312433Y129678D01*
G01X312067Y132506D02*
X312041Y132538D01*
G01X312097Y132487D02*
X312067Y132506D01*
G01X312130Y132480D02*
X312097Y132487D01*
G01X319959Y130879D02*
X319985Y130848D01*
G01X319928Y130898D02*
X319959Y130879D01*
G01X319895Y130905D02*
X319928Y130898D01*
G01X312464Y132808D02*
X312490Y132777D01*
G01X312433Y132828D02*
X312464Y132808D01*
G01X312400Y132834D02*
X312433Y132828D01*
G01X312067Y135656D02*
X312041Y135687D01*
G01X312097Y135636D02*
X312067Y135656D01*
G01X312130Y135630D02*
X312097Y135636D01*
G01X312464Y135958D02*
X312490Y135926D01*
G01X312433Y135977D02*
X312464Y135958D01*
G01X312400Y135984D02*
X312433Y135977D01*
G01X312214Y139790D02*
X312188Y139821D01*
G01X312245Y139770D02*
X312214Y139790D01*
G01X312278Y139763D02*
X312245Y139770D01*
G01X312610Y140328D02*
X312637Y140296D01*
G01X312580Y140347D02*
X312610Y140328D01*
G01X312547Y140354D02*
X312580Y140347D01*
G01X318409Y141955D02*
X318383Y141987D01*
G01X318440Y141935D02*
X318409Y141955D01*
G01X318472Y141929D02*
X318440Y141935D01*
G01X317297Y142493D02*
X317323Y142462D01*
G01X317267Y142513D02*
X317297Y142493D01*
G01X317234Y142519D02*
X317267Y142513D01*
G01X312214Y144790D02*
X312188Y144821D01*
G01X312245Y144770D02*
X312214Y144790D01*
G01X312278Y144763D02*
X312245Y144770D01*
G01X311830Y129678D02*
X311797Y129685D01*
G01X311861Y129658D02*
X311830Y129678D01*
G01X311887Y129627D02*
X311861Y129658D01*
G01X312700Y129337D02*
X312733Y129330D01*
G01X312670Y129357D02*
X312700Y129337D01*
G01X312644Y129388D02*
X312670Y129357D01*
G01X311830Y132828D02*
X311797Y132834D01*
G01X311861Y132808D02*
X311830Y132828D01*
G01X311887Y132777D02*
X311861Y132808D01*
G01X312700Y132487D02*
X312733Y132480D01*
G01X312670Y132506D02*
X312700Y132487D01*
G01X312644Y132538D02*
X312670Y132506D01*
G01X311830Y135977D02*
X311797Y135984D01*
G01X311861Y135958D02*
X311830Y135977D01*
G01X311887Y135926D02*
X311861Y135958D01*
G01X312700Y135636D02*
X312733Y135630D01*
G01X312670Y135656D02*
X312700Y135636D01*
G01X312644Y135687D02*
X312670Y135656D01*
G01X311826Y140347D02*
X311793Y140354D01*
G01X311856Y140328D02*
X311826Y140347D01*
G01X311883Y140296D02*
X311856Y140328D01*
G01X320094Y130715D02*
X320127Y130708D01*
G01X320063Y130735D02*
X320094Y130715D01*
G01X320037Y130766D02*
X320063Y130735D01*
G01X312999Y139770D02*
X313032Y139763D01*
G01X312968Y139790D02*
X312999Y139770D01*
G01X312942Y139821D02*
X312968Y139790D01*
G01X312999Y144770D02*
X313032Y144763D01*
G01X312968Y144790D02*
X312999Y144770D01*
G01X312942Y144821D02*
X312968Y144790D01*
G01X317685Y141935D02*
X317719Y141929D01*
G01X317655Y141955D02*
X317685Y141935D01*
G01X317629Y141987D02*
X317655Y141955D01*
G01X318021Y142513D02*
X317988Y142519D01*
G01X318051Y142493D02*
X318021Y142513D01*
G01X318078Y142462D02*
X318051Y142493D01*
G01X312245Y142513D02*
X312278Y142519D01*
G01X312214Y142493D02*
X312245Y142513D01*
G01X312188Y142462D02*
X312214Y142493D01*
G01X312580Y141935D02*
X312547Y141929D01*
G01X312610Y141955D02*
X312580Y141935D01*
G01X312637Y141987D02*
X312610Y141955D01*
G01X317267Y144770D02*
X317234Y144763D01*
G01X317297Y144790D02*
X317267Y144770D01*
G01X317323Y144821D02*
X317297Y144790D01*
G01X312097Y137198D02*
X312130Y137204D01*
G01X312067Y137178D02*
X312097Y137198D01*
G01X312041Y137147D02*
X312067Y137178D01*
G01X312433Y136857D02*
X312400Y136850D01*
G01X312464Y136876D02*
X312433Y136857D01*
G01X312490Y136908D02*
X312464Y136876D01*
G01X312097Y134048D02*
X312130Y134055D01*
G01X312067Y134028D02*
X312097Y134048D01*
G01X312041Y133997D02*
X312067Y134028D01*
G01X317267Y139770D02*
X317234Y139763D01*
G01X317297Y139790D02*
X317267Y139770D01*
G01X317323Y139821D02*
X317297Y139790D01*
G01X312433Y133707D02*
X312400Y133700D01*
G01X312464Y133727D02*
X312433Y133707D01*
G01X312490Y133758D02*
X312464Y133727D01*
G01X318440Y140347D02*
X318472Y140354D01*
G01X318409Y140328D02*
X318440Y140347D01*
G01X318383Y140296D02*
X318409Y140328D01*
G01X312097Y130898D02*
X312130Y130905D01*
G01X312067Y130879D02*
X312097Y130898D01*
G01X312041Y130848D02*
X312067Y130879D01*
G01X312433Y130558D02*
X312400Y130551D01*
G01X312464Y130577D02*
X312433Y130558D01*
G01X312490Y130609D02*
X312464Y130577D01*
G01X319928Y129337D02*
X319895Y129330D01*
G01X319959Y129357D02*
X319928Y129337D01*
G01X319985Y129388D02*
X319959Y129357D01*
G01X320037Y129470D02*
X319985Y129388D01*
G01X320074Y132677D02*
X319948Y132480D01*
G01X320074Y135826D02*
X319948Y135630D01*
G01X312644Y130848D02*
X312490Y130609D01*
G01X318078Y139821D02*
X318383Y140296D01*
G01X311887Y130609D02*
X312041Y130848D01*
G01X317629Y140296D02*
X317323Y139821D01*
G01X312644Y133997D02*
X312490Y133758D01*
G01X311887D02*
X312041Y133997D01*
G01X318078Y144821D02*
X318383Y145296D01*
G01X312644Y137147D02*
X312490Y136908D01*
G01X317629Y145296D02*
X317323Y144821D01*
G01X311887Y136908D02*
X312041Y137147D01*
G01X312942Y142462D02*
X312637Y141987D01*
G01X311883D02*
X312188Y142462D01*
G01X319680Y140354D02*
Y141929D01*
G01X318926D02*
Y140354D01*
G01X318835Y132135D02*
Y131251D01*
G01Y135284D02*
Y134400D01*
G01Y137992D02*
Y137550D01*
G01X318637Y135511D02*
Y137322D01*
G01Y132362D02*
Y134173D01*
G01Y131023D02*
Y129212D01*
G01X318243D02*
Y131023D01*
G01Y134173D02*
Y132362D01*
G01Y137322D02*
Y135511D01*
G01X318172Y141929D02*
Y140354D01*
G01X317772Y143956D02*
Y144822D01*
G01Y137657D02*
Y138523D01*
G01Y132224D02*
Y131358D01*
G01Y135374D02*
Y134508D01*
G01Y141673D02*
Y140807D01*
G01X312069Y140354D02*
Y141929D01*
G01X311315D02*
Y140354D01*
G01X311236Y135984D02*
Y136850D01*
G01Y132834D02*
Y133700D01*
G01Y129685D02*
Y130551D01*
G01X310633Y135984D02*
Y136850D01*
G01Y132834D02*
Y133700D01*
G01Y129685D02*
Y130551D01*
G01X310561Y141929D02*
Y140354D01*
G01X309879Y130551D02*
Y129685D01*
G01Y133700D02*
Y132834D01*
G01Y136850D02*
Y135984D01*
G01X308642Y136157D02*
Y136669D01*
G01X308578D02*
Y136244D01*
G01X308514Y136320D02*
Y136233D01*
G01X308428Y136157D02*
Y136222D01*
G01Y136603D02*
Y136669D01*
G01X308386Y136363D02*
Y136429D01*
G01X308109D02*
Y136603D01*
G01Y136222D02*
Y136363D01*
G01X308045Y136669D02*
Y136157D01*
G01X307806Y141929D02*
Y140354D01*
G01X307719Y135984D02*
Y136850D01*
G01Y132834D02*
Y133700D01*
G01Y129685D02*
Y130551D01*
G01X319393Y129212D02*
X318835Y128985D01*
G01X318383Y141987D02*
X318078Y142462D01*
G01X317323D02*
X317629Y141987D01*
G01X319948Y137204D02*
X320074Y137008D01*
G01X319948Y134055D02*
X320074Y133858D01*
G01X312637Y145296D02*
X312942Y144821D01*
G01X312188D02*
X311883Y145296D01*
G01X319985Y130848D02*
X320037Y130766D01*
G01X312637Y140296D02*
X312942Y139821D01*
G01X312188D02*
X311883Y140296D01*
G01X312490Y135926D02*
X312644Y135687D01*
G01X312041D02*
X311887Y135926D01*
G01X312490Y132777D02*
X312644Y132538D01*
G01X312041D02*
X311887Y132777D01*
G01X312490Y129627D02*
X312644Y129388D01*
G01X312041D02*
X311887Y129627D01*
G01X319393Y132362D02*
X318835Y132135D01*
G01X319393Y135511D02*
X318835Y135284D01*
G01X308578Y136244D02*
X308514Y136320D01*
G01Y136233D02*
X308578Y136157D01*
G01X318835Y137550D02*
X319393Y137322D01*
G01X318835Y134400D02*
X319393Y134173D01*
G01X318835Y131251D02*
X319393Y131023D01*
G01X317772Y144822D02*
X322727D01*
G01X317323Y144821D02*
X317772Y144822D01*
G01X312942Y144821D02*
X312188D01*
G01X317988Y144763D02*
X312278D01*
G01X322727Y143956D02*
X317772D01*
G01X312278Y142519D02*
X317988D01*
G01X317323Y142462D02*
X318078D01*
G01X312942D02*
X312188D01*
G01X312637Y141987D02*
X311883D01*
G01X318383D02*
X317629D01*
G01X317719Y141929D02*
X320271D01*
G01X307806D02*
X312547D01*
G01X317772Y141673D02*
X322727D01*
G01Y140807D02*
X317772D01*
G01X317719Y140354D02*
X320271D01*
G01X307806D02*
X312547D01*
G01X311883Y140296D02*
X312637D01*
G01X318383D02*
X317629D01*
G01X317323Y139821D02*
X318078D01*
G01X312942D02*
X312188D01*
G01X317988Y139763D02*
X312278D01*
G01X317772Y138523D02*
X322727D01*
G01X317913Y137992D02*
X323819D01*
G01X322727Y137657D02*
X317772D01*
G01X318835Y137550D02*
X317913D01*
G01X321219Y137322D02*
X317913D01*
G01X312130Y137204D02*
X320551D01*
G01X312041Y137147D02*
X312644D01*
G01X320074Y137008D02*
X323245D01*
G01X312490Y136908D02*
X311887D01*
G01X307719Y136850D02*
X312400D01*
G01X308428Y136669D02*
X308045D01*
G01X308642D02*
X308578D01*
G01X308109Y136603D02*
X308428D01*
G01X308386Y136429D02*
X308109D01*
G01Y136363D02*
X308386D01*
G01X308428Y136222D02*
X308109D01*
G01X308045Y136157D02*
X308428D01*
G01X308578D02*
X308642D01*
G01X312400Y135984D02*
X307720D01*
G01X311887Y135926D02*
X312490D01*
G01X320074Y135826D02*
X323245D01*
G01X312644Y135687D02*
X312041D01*
G01X312130Y135630D02*
X320551D01*
G01X317913Y135511D02*
X321219D01*
G01X317772Y135374D02*
X322727D01*
G01X317913Y135284D02*
X318835D01*
G01X322727Y134508D02*
X317772D01*
G01X317913Y134400D02*
X318835D01*
G01X321219Y134173D02*
X317913D01*
G01X312130Y134055D02*
X320551D01*
G01X312041Y133997D02*
X312644D01*
G01X320074Y133858D02*
X323245D01*
G01X312490Y133758D02*
X311887D01*
G01X307719Y133700D02*
X312400D01*
G01Y132834D02*
X307720D01*
G01X311887Y132777D02*
X312490D01*
G01X320074Y132677D02*
X323245D01*
G01X312644Y132538D02*
X312041D01*
G01X312130Y132480D02*
X320551D01*
G01X317913Y132362D02*
X321219D01*
G01X317772Y132224D02*
X322727D01*
G01X317913Y132135D02*
X318835D01*
G01X322727Y131358D02*
X317772D01*
G01X317913Y131251D02*
X318835D01*
G01X321219Y131023D02*
X317913D01*
G01X312130Y130905D02*
X320499D01*
G01X312041Y130848D02*
X312644D01*
G01X320588D02*
X319985D01*
G01X320037Y130766D02*
X320641D01*
G01X320127Y130708D02*
X323245D01*
G01X312490Y130609D02*
X311887D01*
G01X307719Y130551D02*
X312400D01*
G01Y129685D02*
X307720D01*
G01X311887Y129627D02*
X312490D01*
G01X320127Y129527D02*
X323245D01*
G01X320641Y129470D02*
X320037D01*
G01X319985Y129388D02*
X320588D01*
G01X312644D02*
X312041D01*
G01X312130Y129330D02*
X320499D01*
G01X317913Y129212D02*
X321219D01*
G01X317772Y129074D02*
X322727D01*
G01X317913Y128985D02*
X318835D01*
G01X317655Y145328D02*
X317629Y145296D01*
G01X317685Y145347D02*
X317655Y145328D01*
G01X317719Y145354D02*
X317685Y145347D01*
G01X311856Y146955D02*
X311883Y146987D01*
G01X311826Y146935D02*
X311856Y146955D01*
G01X311793Y146929D02*
X311826Y146935D01*
G01X312968Y147493D02*
X312942Y147462D01*
G01X312999Y147513D02*
X312968Y147493D01*
G01X313032Y147519D02*
X312999Y147513D01*
G01X318051Y149790D02*
X318078Y149821D01*
G01X318021Y149770D02*
X318051Y149790D01*
G01X317988Y149763D02*
X318021Y149770D01*
G01X317655Y150328D02*
X317629Y150296D01*
G01X317685Y150347D02*
X317655Y150328D01*
G01X317719Y150354D02*
X317685Y150347D01*
G01X311856Y151955D02*
X311883Y151987D01*
G01X311826Y151935D02*
X311856Y151955D01*
G01X311793Y151929D02*
X311826Y151935D01*
G01X312968Y152493D02*
X312942Y152462D01*
G01X312999Y152513D02*
X312968Y152493D01*
G01X313032Y152519D02*
X312999Y152513D01*
G01X318051Y154790D02*
X318078Y154821D01*
G01X318021Y154770D02*
X318051Y154790D01*
G01X317988Y154763D02*
X318021Y154770D01*
G01X317655Y155328D02*
X317629Y155296D01*
G01X317685Y155347D02*
X317655Y155328D01*
G01X317719Y155354D02*
X317685Y155347D01*
G01X311856Y156955D02*
X311883Y156987D01*
G01X311826Y156935D02*
X311856Y156955D01*
G01X311793Y156929D02*
X311826Y156935D01*
G01X312968Y157493D02*
X312942Y157462D01*
G01X312999Y157513D02*
X312968Y157493D01*
G01X313032Y157519D02*
X312999Y157513D01*
G01X318051Y159790D02*
X318078Y159821D01*
G01X318021Y159770D02*
X318051Y159790D01*
G01X317988Y159763D02*
X318021Y159770D01*
G01X317655Y160328D02*
X317629Y160296D01*
G01X317685Y160347D02*
X317655Y160328D01*
G01X317719Y160354D02*
X317685Y160347D01*
G01X312610Y145328D02*
X312637Y145296D01*
G01X312580Y145347D02*
X312610Y145328D01*
G01X312547Y145354D02*
X312580Y145347D01*
G01X318409Y146955D02*
X318383Y146987D01*
G01X318440Y146935D02*
X318409Y146955D01*
G01X318472Y146929D02*
X318440Y146935D01*
G01X317297Y147493D02*
X317323Y147462D01*
G01X317267Y147513D02*
X317297Y147493D01*
G01X317234Y147519D02*
X317267Y147513D01*
G01X312214Y149790D02*
X312188Y149821D01*
G01X312245Y149770D02*
X312214Y149790D01*
G01X312278Y149763D02*
X312245Y149770D01*
G01X312610Y150328D02*
X312637Y150296D01*
G01X312580Y150347D02*
X312610Y150328D01*
G01X312547Y150354D02*
X312580Y150347D01*
G01X318409Y151955D02*
X318383Y151987D01*
G01X318440Y151935D02*
X318409Y151955D01*
G01X318472Y151929D02*
X318440Y151935D01*
G01X317297Y152493D02*
X317323Y152462D01*
G01X317267Y152513D02*
X317297Y152493D01*
G01X317234Y152519D02*
X317267Y152513D01*
G01X312214Y154790D02*
X312188Y154821D01*
G01X312245Y154770D02*
X312214Y154790D01*
G01X312278Y154763D02*
X312245Y154770D01*
G01X312610Y155328D02*
X312637Y155296D01*
G01X312580Y155347D02*
X312610Y155328D01*
G01X312547Y155354D02*
X312580Y155347D01*
G01X318409Y156955D02*
X318383Y156987D01*
G01X318440Y156935D02*
X318409Y156955D01*
G01X318472Y156929D02*
X318440Y156935D01*
G01X317297Y157493D02*
X317323Y157462D01*
G01X317267Y157513D02*
X317297Y157493D01*
G01X317234Y157519D02*
X317267Y157513D01*
G01X312214Y159790D02*
X312188Y159821D01*
G01X312245Y159770D02*
X312214Y159790D01*
G01X312278Y159763D02*
X312245Y159770D01*
G01X312610Y160328D02*
X312637Y160296D01*
G01X312580Y160347D02*
X312610Y160328D01*
G01X312547Y160354D02*
X312580Y160347D01*
G01X311826Y145347D02*
X311793Y145354D01*
G01X311856Y145328D02*
X311826Y145347D01*
G01X311883Y145296D02*
X311856Y145328D01*
G01X311826Y150347D02*
X311793Y150354D01*
G01X311856Y150328D02*
X311826Y150347D01*
G01X311883Y150296D02*
X311856Y150328D01*
G01X312999Y149770D02*
X313032Y149763D01*
G01X312968Y149790D02*
X312999Y149770D01*
G01X312942Y149821D02*
X312968Y149790D01*
G01X317685Y146935D02*
X317719Y146929D01*
G01X317655Y146955D02*
X317685Y146935D01*
G01X317629Y146987D02*
X317655Y146955D01*
G01X318021Y147513D02*
X317988Y147519D01*
G01X318051Y147493D02*
X318021Y147513D01*
G01X318078Y147462D02*
X318051Y147493D01*
G01X311826Y155347D02*
X311793Y155354D01*
G01X311856Y155328D02*
X311826Y155347D01*
G01X311883Y155296D02*
X311856Y155328D01*
G01X312999Y154770D02*
X313032Y154763D01*
G01X312968Y154790D02*
X312999Y154770D01*
G01X312942Y154821D02*
X312968Y154790D01*
G01X317685Y151935D02*
X317719Y151929D01*
G01X317655Y151955D02*
X317685Y151935D01*
G01X317629Y151987D02*
X317655Y151955D01*
G01X318021Y152513D02*
X317988Y152519D01*
G01X318051Y152493D02*
X318021Y152513D01*
G01X318078Y152462D02*
X318051Y152493D01*
G01X311826Y160347D02*
X311793Y160354D01*
G01X311856Y160328D02*
X311826Y160347D01*
G01X311883Y160296D02*
X311856Y160328D01*
G01X312999Y159770D02*
X313032Y159763D01*
G01X312968Y159790D02*
X312999Y159770D01*
G01X312942Y159821D02*
X312968Y159790D01*
G01X317685Y156935D02*
X317719Y156929D01*
G01X317655Y156955D02*
X317685Y156935D01*
G01X317629Y156987D02*
X317655Y156955D01*
G01X318021Y157513D02*
X317988Y157519D01*
G01X318051Y157493D02*
X318021Y157513D01*
G01X318078Y157462D02*
X318051Y157493D01*
G01X312245Y157513D02*
X312278Y157519D01*
G01X312214Y157493D02*
X312245Y157513D01*
G01X312188Y157462D02*
X312214Y157493D01*
G01X312580Y156935D02*
X312547Y156929D01*
G01X312610Y156955D02*
X312580Y156935D01*
G01X312637Y156987D02*
X312610Y156955D01*
G01X317267Y159770D02*
X317234Y159763D01*
G01X317297Y159790D02*
X317267Y159770D01*
G01X317323Y159821D02*
X317297Y159790D01*
G01X318440Y160347D02*
X318472Y160354D01*
G01X318409Y160328D02*
X318440Y160347D01*
G01X318383Y160296D02*
X318409Y160328D01*
G01X312245Y152513D02*
X312278Y152519D01*
G01X312214Y152493D02*
X312245Y152513D01*
G01X312188Y152462D02*
X312214Y152493D01*
G01X312580Y151935D02*
X312547Y151929D01*
G01X312610Y151955D02*
X312580Y151935D01*
G01X312637Y151987D02*
X312610Y151955D01*
G01X317267Y154770D02*
X317234Y154763D01*
G01X317297Y154790D02*
X317267Y154770D01*
G01X317323Y154821D02*
X317297Y154790D01*
G01X318440Y155347D02*
X318472Y155354D01*
G01X318409Y155328D02*
X318440Y155347D01*
G01X318383Y155296D02*
X318409Y155328D01*
G01X312245Y147513D02*
X312278Y147519D01*
G01X312214Y147493D02*
X312245Y147513D01*
G01X312188Y147462D02*
X312214Y147493D01*
G01X312580Y146935D02*
X312547Y146929D01*
G01X312610Y146955D02*
X312580Y146935D01*
G01X312637Y146987D02*
X312610Y146955D01*
G01X317267Y149770D02*
X317234Y149763D01*
G01X317297Y149790D02*
X317267Y149770D01*
G01X317323Y149821D02*
X317297Y149790D01*
G01X318440Y150347D02*
X318472Y150354D01*
G01X318409Y150328D02*
X318440Y150347D01*
G01X318383Y150296D02*
X318409Y150328D01*
G01X318440Y145347D02*
X318472Y145354D01*
G01X318409Y145328D02*
X318440Y145347D01*
G01X318383Y145296D02*
X318409Y145328D01*
G01X318078Y149821D02*
X318383Y150296D01*
G01X317629D02*
X317323Y149821D01*
G01X319680Y155354D02*
Y156929D01*
G01Y146929D02*
Y145354D01*
G01Y151929D02*
Y150354D01*
G01Y161929D02*
Y160354D01*
G01X318926Y146929D02*
Y145354D01*
G01Y151929D02*
Y150354D01*
G01Y156929D02*
Y155354D01*
G01Y161929D02*
Y160354D01*
G01X318172D02*
Y161929D01*
G01Y155354D02*
Y156929D01*
G01Y150354D02*
Y151929D01*
G01Y145354D02*
Y146929D01*
G01X317772Y153405D02*
Y154271D01*
G01Y147972D02*
Y147106D01*
G01Y151122D02*
Y150256D01*
G01Y157421D02*
Y156555D01*
G01Y160570D02*
Y159704D01*
G01X312069Y160354D02*
Y161929D01*
G01Y155354D02*
Y156929D01*
G01Y150354D02*
Y151929D01*
G01Y145354D02*
Y146929D01*
G01X318078Y154821D02*
X318383Y155296D01*
G01X312942Y147462D02*
X312637Y146987D01*
G01X317629Y155296D02*
X317323Y154821D01*
G01X311883Y146987D02*
X312188Y147462D01*
G01X318078Y159821D02*
X318383Y160296D01*
G01X312942Y152462D02*
X312637Y151987D01*
G01X317629Y160296D02*
X317323Y159821D01*
G01X311883Y151987D02*
X312188Y152462D01*
G01X312942Y157462D02*
X312637Y156987D01*
G01X311883D02*
X312188Y157462D01*
G01X311315Y146929D02*
Y145354D01*
G01Y151929D02*
Y150354D01*
G01Y156929D02*
Y155354D01*
G01Y161929D02*
Y160354D01*
G01X310561Y146929D02*
Y145354D01*
G01Y151929D02*
Y150354D01*
G01Y156929D02*
Y155354D01*
G01Y161929D02*
Y160354D01*
G01X307806Y146929D02*
Y145354D01*
G01Y151929D02*
Y150354D01*
G01Y156929D02*
Y155354D01*
G01Y161929D02*
Y160354D01*
G01X318383Y156987D02*
X318078Y157462D01*
G01X317323D02*
X317629Y156987D01*
G01X318383Y151987D02*
X318078Y152462D01*
G01X312637Y160296D02*
X312942Y159821D01*
G01X317323Y152462D02*
X317629Y151987D01*
G01X312188Y159821D02*
X311883Y160296D01*
G01X318383Y146987D02*
X318078Y147462D01*
G01X312637Y155296D02*
X312942Y154821D01*
G01X317323Y147462D02*
X317629Y146987D01*
G01X312188Y154821D02*
X311883Y155296D01*
G01X312637Y150296D02*
X312942Y149821D01*
G01X312188D02*
X311883Y150296D01*
G01X317772Y160570D02*
X322727D01*
G01X317719Y160354D02*
X320271D01*
G01X307806D02*
X312547D01*
G01X311883Y160296D02*
X312637D01*
G01X318383D02*
X317629D01*
G01X317323Y159821D02*
X318078D01*
G01X312942D02*
X312188D01*
G01X317988Y159763D02*
X312278D01*
G01X322727Y159704D02*
X317772D01*
G01X312278Y157519D02*
X317988D01*
G01X312942Y157462D02*
X312188D01*
G01X318078D02*
X317323D01*
G01X317772Y157421D02*
X322727D01*
G01X311883Y156987D02*
X312637D01*
G01X318383D02*
X317629D01*
G01X317719Y156929D02*
X320271D01*
G01X307806D02*
X312547D01*
G01X322727Y156555D02*
X317772D01*
G01X317719Y155354D02*
X320271D01*
G01X307806D02*
X312547D01*
G01X311883Y155296D02*
X312637D01*
G01X318383D02*
X317629D01*
G01X317323Y154821D02*
X318078D01*
G01X312942D02*
X312188D01*
G01X317988Y154763D02*
X312278D01*
G01X317772Y154271D02*
X322727D01*
G01Y153405D02*
X317772D01*
G01X312278Y152519D02*
X317988D01*
G01X312942Y152462D02*
X312188D01*
G01X318078D02*
X317323D01*
G01X311883Y151987D02*
X312637D01*
G01X318383D02*
X317629D01*
G01X317719Y151929D02*
X320271D01*
G01X307806D02*
X312547D01*
G01X317772Y151122D02*
X322727D01*
G01X317719Y150354D02*
X320271D01*
G01X307806D02*
X312547D01*
G01X311883Y150296D02*
X312637D01*
G01X318383D02*
X317629D01*
G01X322727Y150256D02*
X317772D01*
G01X317323Y149821D02*
X318078D01*
G01X312942D02*
X312188D01*
G01X317988Y149763D02*
X312278D01*
G01X317772Y147972D02*
X322727D01*
G01X312278Y147519D02*
X317988D01*
G01X317323Y147462D02*
X318078D01*
G01X312942D02*
X312188D01*
G01X322727Y147106D02*
X317772D01*
G01X312637Y146987D02*
X311883D01*
G01X318383D02*
X317629D01*
G01X317719Y146929D02*
X320271D01*
G01X307806D02*
X312547D01*
G01X317719Y145354D02*
X320271D01*
G01X307806D02*
X312547D01*
G01X311883Y145296D02*
X312637D01*
G01X318383D02*
X317629D01*
G01X319094Y175256D02*
Y191988D01*
G01X319093Y175256D02*
G03X321063Y173287I1969J0D01*
G01X311856Y161955D02*
X311883Y161987D01*
G01X311826Y161935D02*
X311856Y161955D01*
G01X311793Y161929D02*
X311826Y161935D01*
G01X312968Y162493D02*
X312942Y162462D01*
G01X312999Y162513D02*
X312968Y162493D01*
G01X313032Y162519D02*
X312999Y162513D01*
G01X318051Y164790D02*
X318078Y164821D01*
G01X318021Y164770D02*
X318051Y164790D01*
G01X317988Y164763D02*
X318021Y164770D01*
G01X317655Y165328D02*
X317629Y165296D01*
G01X317685Y165347D02*
X317655Y165328D01*
G01X317719Y165354D02*
X317685Y165347D01*
G01X311856Y166955D02*
X311883Y166987D01*
G01X311826Y166935D02*
X311856Y166955D01*
G01X311793Y166929D02*
X311826Y166935D01*
G01X312968Y167493D02*
X312942Y167462D01*
G01X312999Y167513D02*
X312968Y167493D01*
G01X313032Y167519D02*
X312999Y167513D01*
G01X318051Y169790D02*
X318078Y169821D01*
G01X318021Y169770D02*
X318051Y169790D01*
G01X317988Y169763D02*
X318021Y169770D01*
G01X317655Y170328D02*
X317629Y170296D01*
G01X317685Y170347D02*
X317655Y170328D01*
G01X317719Y170354D02*
X317685Y170347D01*
G01X311856Y171955D02*
X311883Y171987D01*
G01X311826Y171935D02*
X311856Y171955D01*
G01X311793Y171929D02*
X311826Y171935D01*
G01X312968Y172493D02*
X312942Y172462D01*
G01X312999Y172513D02*
X312968Y172493D01*
G01X313032Y172519D02*
X312999Y172513D01*
G01X318409Y161955D02*
X318383Y161987D01*
G01X318440Y161935D02*
X318409Y161955D01*
G01X318472Y161929D02*
X318440Y161935D01*
G01X317297Y162493D02*
X317323Y162462D01*
G01X317267Y162513D02*
X317297Y162493D01*
G01X317234Y162519D02*
X317267Y162513D01*
G01X312214Y164790D02*
X312188Y164821D01*
G01X312245Y164770D02*
X312214Y164790D01*
G01X312278Y164763D02*
X312245Y164770D01*
G01X312610Y165328D02*
X312637Y165296D01*
G01X312580Y165347D02*
X312610Y165328D01*
G01X312547Y165354D02*
X312580Y165347D01*
G01X318409Y166955D02*
X318383Y166987D01*
G01X318440Y166935D02*
X318409Y166955D01*
G01X318472Y166929D02*
X318440Y166935D01*
G01X317297Y167493D02*
X317323Y167462D01*
G01X317267Y167513D02*
X317297Y167493D01*
G01X317234Y167519D02*
X317267Y167513D01*
G01X312214Y169790D02*
X312188Y169821D01*
G01X312245Y169770D02*
X312214Y169790D01*
G01X312278Y169763D02*
X312245Y169770D01*
G01X312610Y170328D02*
X312637Y170296D01*
G01X312580Y170347D02*
X312610Y170328D01*
G01X312547Y170354D02*
X312580Y170347D01*
G01X318409Y171955D02*
X318383Y171987D01*
G01X318440Y171935D02*
X318409Y171955D01*
G01X318472Y171929D02*
X318440Y171935D01*
G01X317297Y172493D02*
X317323Y172462D01*
G01X317267Y172513D02*
X317297Y172493D01*
G01X317234Y172519D02*
X317267Y172513D01*
G01X311826Y165347D02*
X311793Y165354D01*
G01X311856Y165328D02*
X311826Y165347D01*
G01X311883Y165296D02*
X311856Y165328D01*
G01X312999Y164770D02*
X313032Y164763D01*
G01X312968Y164790D02*
X312999Y164770D01*
G01X312942Y164821D02*
X312968Y164790D01*
G01X317685Y161935D02*
X317719Y161929D01*
G01X317655Y161955D02*
X317685Y161935D01*
G01X317629Y161987D02*
X317655Y161955D01*
G01X318021Y162513D02*
X317988Y162519D01*
G01X318051Y162493D02*
X318021Y162513D01*
G01X318078Y162462D02*
X318051Y162493D01*
G01X311826Y170347D02*
X311793Y170354D01*
G01X311856Y170328D02*
X311826Y170347D01*
G01X311883Y170296D02*
X311856Y170328D01*
G01X312999Y169770D02*
X313032Y169763D01*
G01X312968Y169790D02*
X312999Y169770D01*
G01X312942Y169821D02*
X312968Y169790D01*
G01X317685Y166935D02*
X317719Y166929D01*
G01X317655Y166955D02*
X317685Y166935D01*
G01X317629Y166987D02*
X317655Y166955D01*
G01X318021Y167513D02*
X317988Y167519D01*
G01X318051Y167493D02*
X318021Y167513D01*
G01X318078Y167462D02*
X318051Y167493D01*
G01X312245Y172513D02*
X312278Y172519D01*
G01X312214Y172493D02*
X312245Y172513D01*
G01X312188Y172462D02*
X312214Y172493D01*
G01X312580Y171935D02*
X312547Y171929D01*
G01X312610Y171955D02*
X312580Y171935D01*
G01X312637Y171987D02*
X312610Y171955D01*
G01X312245Y167513D02*
X312278Y167519D01*
G01X312214Y167493D02*
X312245Y167513D01*
G01X312188Y167462D02*
X312214Y167493D01*
G01X312580Y166935D02*
X312547Y166929D01*
G01X312610Y166955D02*
X312580Y166935D01*
G01X312637Y166987D02*
X312610Y166955D01*
G01X317267Y169770D02*
X317234Y169763D01*
G01X317297Y169790D02*
X317267Y169770D01*
G01X317323Y169821D02*
X317297Y169790D01*
G01X318440Y170347D02*
X318472Y170354D01*
G01X318409Y170328D02*
X318440Y170347D01*
G01X318383Y170296D02*
X318409Y170328D01*
G01X312245Y162513D02*
X312278Y162519D01*
G01X312214Y162493D02*
X312245Y162513D01*
G01X312188Y162462D02*
X312214Y162493D01*
G01X312580Y161935D02*
X312547Y161929D01*
G01X312610Y161955D02*
X312580Y161935D01*
G01X312637Y161987D02*
X312610Y161955D01*
G01X317685Y171935D02*
X317719Y171929D01*
G01X317655Y171955D02*
X317685Y171935D01*
G01X317629Y171987D02*
X317655Y171955D01*
G01X318021Y172513D02*
X317988Y172519D01*
G01X318051Y172493D02*
X318021Y172513D01*
G01X318078Y172462D02*
X318051Y172493D01*
G01X317267Y164770D02*
X317234Y164763D01*
G01X317297Y164790D02*
X317267Y164770D01*
G01X317323Y164821D02*
X317297Y164790D01*
G01X318440Y165347D02*
X318472Y165354D01*
G01X318409Y165328D02*
X318440Y165347D01*
G01X318383Y165296D02*
X318409Y165328D01*
G01X319094Y175256D02*
G03X321063Y173287I1969J0D01*
G01X319094Y175256D02*
G03X321063Y173287I1969J0D01*
G01X319094Y175256D02*
G03X321063Y173287I1969J0D01*
G01X319094Y175256D02*
G03X321063Y173287I1969J0D01*
G01X319680Y170354D02*
Y171929D01*
G01Y166929D02*
Y165354D01*
G01X319488Y174448D02*
Y192756D01*
G01X319094Y191988D02*
Y175256D01*
G01Y191988D02*
Y175256D01*
G01X318926Y166929D02*
Y165354D01*
G01Y171929D02*
Y170354D01*
G01X318172D02*
Y171929D01*
G01Y165354D02*
Y166929D01*
G01X317772Y162854D02*
Y163720D01*
G01Y166870D02*
Y166004D01*
G01Y170019D02*
Y169153D01*
G01X317519Y192756D02*
Y174448D01*
G01X312069Y170354D02*
Y171929D01*
G01Y165354D02*
Y166929D01*
G01X308340Y170827D02*
X308320Y170907D01*
G01X308438Y170928D02*
X308458Y170867D01*
G01X318078Y164821D02*
X318383Y165296D01*
G01X317629D02*
X317323Y164821D01*
G01X318078Y169821D02*
X318383Y170296D01*
G01X312942Y162462D02*
X312637Y161987D01*
G01X317629Y170296D02*
X317323Y169821D01*
G01X311883Y161987D02*
X312188Y162462D01*
G01X312942Y167462D02*
X312637Y166987D01*
G01X311883D02*
X312188Y167462D01*
G01X312942Y172462D02*
X312637Y171987D01*
G01X311883D02*
X312188Y172462D01*
G01X308281Y171450D02*
X308340Y171551D01*
G01X308793Y170867D02*
X308812Y170907D01*
G01X308989Y171309D02*
X308950Y171229D01*
G01X308930Y170907D02*
X308911Y170847D01*
G01X308458Y171028D02*
X308438Y170968D01*
G01X308399Y171430D02*
X308379Y171370D01*
G01X308320Y170988D02*
X308340Y171068D01*
G01X308261Y171370D02*
X308281Y171450D01*
G01X311315Y166929D02*
Y165354D01*
G01Y171929D02*
Y170354D01*
G01X310561Y166929D02*
Y165354D01*
G01Y171929D02*
Y170354D01*
G01X309383Y170686D02*
Y171631D01*
G01X309265D02*
Y170847D01*
G01X309147Y170988D02*
Y170827D01*
G01X308989Y171410D02*
Y171309D01*
G01X308871Y171330D02*
Y171390D01*
G01X308438Y170968D02*
Y170928D01*
G01X308320Y170907D02*
Y170988D01*
G01X307806Y166929D02*
Y165354D01*
G01Y171929D02*
Y170354D01*
G01X306889Y175236D02*
Y179173D01*
G01X308950Y171490D02*
X308989Y171410D01*
G01X318383Y171987D02*
X318078Y172462D01*
G01X317323D02*
X317629Y171987D01*
G01X318383Y166987D02*
X318078Y167462D01*
G01X317323D02*
X317629Y166987D01*
G01X318383Y161987D02*
X318078Y162462D01*
G01X312637Y170296D02*
X312942Y169821D01*
G01X317323Y162462D02*
X317629Y161987D01*
G01X312188Y169821D02*
X311883Y170296D01*
G01X312637Y165296D02*
X312942Y164821D01*
G01X312188D02*
X311883Y165296D01*
G01X308871Y171390D02*
X308832Y171450D01*
G01X308753Y170827D02*
X308793Y170867D01*
G01X308950Y171229D02*
X308871Y171148D01*
G01X308911Y170847D02*
X308852Y170767D01*
G01X308832Y171269D02*
X308871Y171330D01*
G01X309265Y170847D02*
X309147Y170988D01*
G01Y170827D02*
X309265Y170686D01*
G01X308871Y171571D02*
X308950Y171490D01*
G01X308419Y170746D02*
X308340Y170827D01*
G01X308852Y170767D02*
X308773Y170706D01*
G01X308340Y171068D02*
X308419Y171148D01*
G01X308458Y171490D02*
X308399Y171430D01*
G01X308871Y171148D02*
X308793Y171108D01*
G01X308419Y171148D02*
X308497Y171189D01*
G01X308340Y171551D02*
X308438Y171611D01*
G01X308773Y171229D02*
X308832Y171269D01*
G01X308517Y171068D02*
X308458Y171028D01*
G01X308832Y171450D02*
X308773Y171490D01*
G01X308458Y170867D02*
X308517Y170827D01*
G01X308694Y170807D02*
X308753Y170827D01*
G01X308576Y171088D02*
X308517Y171068D01*
G01X308793Y171611D02*
X308871Y171571D01*
G01X308497Y170706D02*
X308419Y170746D01*
G01X308517Y170827D02*
X308576Y170807D01*
G01X308773Y171490D02*
X308694Y171510D01*
G01X308576Y170686D02*
X308497Y170706D01*
G01X308694Y171631D02*
X308793Y171611D01*
G01X319280Y174448D02*
X348228D01*
G01X312278Y172519D02*
X317988D01*
G01X312942Y172462D02*
X312188D01*
G01X318078D02*
X317323D01*
G01X311883Y171987D02*
X312637D01*
G01X318383D02*
X317629D01*
G01X317719Y171929D02*
X320271D01*
G01X307806D02*
X312547D01*
G01X308537Y171631D02*
X308694D01*
G01X309383D02*
X309265D01*
G01X308694Y171510D02*
X308537D01*
G01X308379Y171370D02*
X308261D01*
G01X308576Y171209D02*
X308694D01*
G01Y171088D02*
X308576D01*
G01X308812Y170907D02*
X308930D01*
G01X308576Y170807D02*
X308694D01*
G01X309265Y170686D02*
X309383D01*
G01X308674D02*
X308576D01*
G01X317719Y170354D02*
X320271D01*
G01X307806D02*
X312547D01*
G01X311883Y170296D02*
X312637D01*
G01X318383D02*
X317629D01*
G01X317772Y170019D02*
X322727D01*
G01X317323Y169821D02*
X318078D01*
G01X312942D02*
X312188D01*
G01X317988Y169763D02*
X312278D01*
G01X322727Y169153D02*
X317772D01*
G01X312278Y167519D02*
X317988D01*
G01X312942Y167462D02*
X312188D01*
G01X318078D02*
X317323D01*
G01X311883Y166987D02*
X312637D01*
G01X318383D02*
X317629D01*
G01X317719Y166929D02*
X320271D01*
G01X307806D02*
X312547D01*
G01X317772Y166870D02*
X322727D01*
G01Y166004D02*
X317772D01*
G01X317719Y165354D02*
X320271D01*
G01X307806D02*
X312547D01*
G01X311883Y165296D02*
X312637D01*
G01X318383D02*
X317629D01*
G01X317323Y164821D02*
X318078D01*
G01X312942D02*
X312188D01*
G01X317988Y164763D02*
X312278D01*
G01X317772Y163720D02*
X322727D01*
G01Y162854D02*
X317772D01*
G01X312278Y162519D02*
X317988D01*
G01X317323Y162462D02*
X318078D01*
G01X312942D02*
X312188D01*
G01X312637Y161987D02*
X311883D01*
G01X318383D02*
X317629D01*
G01X317719Y161929D02*
X320271D01*
G01X307806D02*
X312547D01*
G01X308438Y171611D02*
X308537Y171631D01*
G01X308793Y171108D02*
X308694Y171088D01*
G01X308773Y170706D02*
X308674Y170686D01*
G01X308537Y171510D02*
X308458Y171490D01*
G01X308497Y171189D02*
X308576Y171209D01*
G01X308694D02*
X308773Y171229D01*
G01X319094Y191988D02*
Y175256D01*
G01X314173Y185413D02*
G03X309055I-2559J0D01*
G03X314173I2559J0D01*
G01X314567D02*
G03X308661I-2953J0D01*
G03X314567I2953J0D01*
G01X314833D02*
G03X308395I-3219J0D01*
G03X314833I3219J0D01*
G01X321063Y193957D02*
G03X319093Y191988I-1J-1969D01*
G01X321063Y193956D02*
G03X319094Y191988I-1J-1968D01*
G01X321063Y193956D02*
G03X319094Y191988I-1J-1968D01*
G01X321063Y193956D02*
G03X319094Y191988I-1J-1968D01*
G01X321063Y193956D02*
G03X319094Y191988I-1J-1968D01*
G01X319488Y193106D02*
Y203582D01*
G01Y192756D02*
Y193106D01*
G01X317126Y180689D02*
Y190137D01*
G01X307677Y180689D02*
Y190137D01*
G01X319488Y194724D02*
X349409D01*
G01X319254Y192756D02*
X349409D01*
G01X307677Y190137D02*
X317126D01*
G01X322637Y188819D02*
X319488D01*
G01X308395Y185413D02*
X309055D01*
G01X314833D02*
X314173D01*
G01X307677Y180689D02*
X317126D01*
G01X319488Y203582D02*
X329330D01*
G01Y200472D02*
X319488D01*
G01Y199882D02*
X329330D01*
G01X349409Y199291D02*
X319488D01*
G01Y198031D02*
X349409D01*
G01Y197441D02*
X319488D01*
G01X349409Y196850D02*
X319488D01*
G01X311614Y363425D02*
Y320118D01*
G01X312672Y381710D02*
Y384510D01*
G01X323818Y-65098D02*
G03Y-51122I0J6988D01*
G01X335817Y0D02*
G03Y-7874I1J-3937D01*
G01X329921Y10196D02*
G03X331102Y9015I1181J0D01*
G01X329921Y10196D02*
Y16960D01*
G01X337401Y9015D02*
X331102D01*
G01X347441Y23366D02*
X321063D01*
G01X330505Y19142D02*
X330510Y19115D01*
G01X330432Y19188D02*
X330505Y19142D01*
G01X330301Y19207D02*
X330432Y19188D01*
G01X330120Y19212D02*
X330301Y19207D01*
G01X330334Y18026D02*
X330153Y18031D01*
G01X330455Y18011D02*
X330334Y18026D01*
G01X330509Y17981D02*
X330455Y18011D01*
G01X330511Y17970D02*
X330509Y17981D01*
G01X329929Y16703D02*
X329940Y16741D01*
G01X329923Y16664D02*
X329929Y16703D01*
G01X329921Y16624D02*
X329923Y16664D01*
G01Y17023D02*
X329921Y16960D01*
G01X329929Y17085D02*
X329923Y17023D01*
G01X329940Y17146D02*
X329929Y17085D01*
G01X330308Y17671D02*
X330493Y17936D01*
G01X330124Y17260D02*
X330308Y17671D01*
G01X329940Y16741D02*
X330124Y17260D01*
G01Y17978D02*
X329940Y17146D01*
G01X330308Y18635D02*
X330124Y17978D01*
G01X330493Y19060D02*
X330308Y18635D01*
G01X327008Y17598D02*
X327401Y17992D01*
G01X330493Y17936D02*
X330511Y17970D01*
G01X330510Y19115D02*
X330493Y19060D01*
G01X336141Y19212D02*
Y18031D01*
G01X332362Y19212D02*
Y18031D01*
G01X331574Y19212D02*
Y18031D01*
G01X331181Y19212D02*
Y18031D01*
G01X330511Y17970D02*
Y19115D01*
G01X330493Y19060D02*
Y17936D01*
G01X329940Y16740D02*
Y17147D01*
G01X329921Y19212D02*
Y18031D01*
G01X329330Y17992D02*
Y13700D01*
G01X329133Y19212D02*
Y18031D01*
G01X329056D02*
Y19212D01*
G01X328053D02*
Y18031D01*
G01X327806D02*
Y19212D01*
G01X327721D02*
Y18031D01*
G01X327401Y17598D02*
Y19645D01*
G01X327244Y18031D02*
Y19212D01*
G01X327008Y19645D02*
Y17598D01*
G01X325945Y18031D02*
Y19212D01*
G01X325393Y23366D02*
Y13700D01*
G01Y24527D02*
Y23366D01*
G01X325354Y18031D02*
Y19212D01*
G01X322637Y39059D02*
Y27677D01*
G01X320275Y40078D02*
Y27283D01*
G01D02*
X323031Y24527D01*
G01X327008Y19645D02*
X327401Y19252D01*
G01X322637Y28858D02*
X349409D01*
G01X322637Y27677D02*
X347363D01*
G01X321063Y23366D02*
X347441D01*
G01X321063D02*
X347441D01*
G01X327401Y19645D02*
X327008D01*
G01X325354Y19212D02*
X343149D01*
G01X325354Y18031D02*
X343149D01*
G01X327008Y17598D02*
X327401D01*
G01X339173D02*
X329330D01*
G01X338582Y16063D02*
X329921D01*
G01X321063Y23366D02*
X347441D01*
G01X321063D02*
X347441D01*
G01X328150Y46004D02*
Y171319D01*
G01X326181Y44035D02*
G03X328150Y46004I0J1969D01*
G01X321063Y44035D02*
X326181D01*
G01X330511Y46063D02*
G03X330413Y46036I2J-197D01*
G01X325826Y46082D02*
G03X325449Y46161I-197J0D01*
G01X326181Y44035D02*
G03X328149Y46004I0J1968D01*
G01X326181Y44035D02*
G03X328149Y46004I0J1968D01*
G01X320467Y45157D02*
G03X320271Y45354I-197J0D01*
G01X331694Y44921D02*
G03X331643Y44914I1J-197D01*
G01X334506Y44863D02*
G03X334367Y44921I-139J-139D01*
G01X334785Y44585D02*
G03X334924Y44527I140J139D01*
G01X320636Y43950D02*
G03X320275Y42815I1608J-1136D01*
G01X322244Y44783D02*
G03X320636Y43950I0J-1968D01*
G01X326181Y44035D02*
G03X328149Y46004I0J1968D01*
G01X326181Y44035D02*
G03X328149Y46004I0J1968D01*
G01X322637Y39059D02*
X330118Y42547D01*
G01Y45866D02*
X330413Y46036D01*
G01X323031Y42834D02*
X320275Y40078D01*
G01X331299Y44291D02*
Y42834D01*
G01X330118Y179882D02*
Y37401D01*
G01X328149Y171319D02*
Y46004D01*
G01Y171319D02*
Y46004D01*
G01X326023Y44035D02*
Y173287D01*
G01Y42834D02*
Y44035D01*
G01X325826Y45554D02*
Y46082D01*
G01X325218Y47342D02*
Y46161D01*
G01X324366D02*
Y47342D01*
G01X323819Y44035D02*
Y173287D01*
G01Y44035D02*
Y42834D01*
G01X323684Y47342D02*
Y46161D01*
G01X320467Y44173D02*
Y45157D01*
G01X322727Y46319D02*
X322806Y46161D01*
G01X322124D02*
X322045Y46319D01*
G01X334429Y46063D02*
X334626Y45866D01*
G01X334506Y44863D02*
X334785Y44585D01*
G01X332086Y35433D02*
X330118Y37401D01*
G01X322124Y46161D02*
X325449D01*
G01X334429Y46063D02*
X330511D01*
G01X347047Y45866D02*
X334626D01*
G01X326023Y45554D02*
X325826D01*
G01X334367Y44921D02*
X331694D01*
G01X344398Y44527D02*
X334924D01*
G01X330118Y44291D02*
X331299D01*
G01X320467Y44173D02*
X323819D01*
G01X326181Y44035D02*
X321063D01*
G01X326181D02*
X321063D01*
G01X332086Y35433D02*
X347362D01*
G01X349409Y32795D02*
X322637D01*
G01X349409Y31614D02*
X322637D01*
G01X330118Y44506D02*
X331643Y44914D01*
G01X328149Y171319D02*
Y46004D01*
G01Y171319D02*
Y46004D01*
G01X326181Y44035D02*
X321063D01*
G01X326181D02*
X321063D01*
G01X330477Y61808D02*
X330511Y61811D01*
G01X330444Y61799D02*
X330477Y61808D01*
G01X330413Y61784D02*
X330444Y61799D01*
G01X330477Y58658D02*
X330511Y58661D01*
G01X330444Y58649D02*
X330477Y58658D01*
G01X330413Y58635D02*
X330444Y58649D01*
G01X330477Y52359D02*
X330511Y52362D01*
G01X330444Y52350D02*
X330477Y52359D01*
G01X330413Y52335D02*
X330444Y52350D01*
G01X330477Y49209D02*
X330511Y49212D01*
G01X330444Y49200D02*
X330477Y49209D01*
G01X330413Y49186D02*
X330444Y49200D01*
G01X334405Y61753D02*
G03X334266Y61811I-140J-139D01*
G01X334486Y61672D02*
G03X334626Y61614I140J139D01*
G01X334405Y58604D02*
G03X334266Y58661I-139J-140D01*
G01X334486Y58522D02*
G03X334626Y58464I140J139D01*
G01X334924Y57756D02*
G03X334785Y57698I1J-197D01*
G01X334367Y57362D02*
G03X334506Y57420I0J197D01*
G01Y59863D02*
G03X334367Y59921I-139J-139D01*
G01X334785Y59585D02*
G03X334924Y59527I140J139D01*
G01Y62756D02*
G03X334785Y62698I1J-197D01*
G01X334367Y62362D02*
G03X334506Y62420I0J197D01*
G01X334405Y52304D02*
G03X334266Y52362I-140J-139D01*
G01X334486Y52223D02*
G03X334626Y52165I140J139D01*
G01X334405Y49155D02*
G03X334266Y49212I-139J-140D01*
G01X334486Y49073D02*
G03X334626Y49015I140J139D01*
G01X334924Y47756D02*
G03X334785Y47698I1J-197D01*
G01X334367Y47362D02*
G03X334506Y47420I0J197D01*
G01Y49863D02*
G03X334367Y49921I-139J-139D01*
G01X334785Y49585D02*
G03X334924Y49527I140J139D01*
G01Y52756D02*
G03X334785Y52698I1J-197D01*
G01X334367Y52362D02*
G03X334506Y52420I0J197D01*
G01Y54863D02*
G03X334367Y54921I-139J-139D01*
G01X334785Y54585D02*
G03X334924Y54527I140J139D01*
G01X333526Y60236D02*
G03X333387Y60178I1J-197D01*
G01X333166Y60039D02*
G03X333305Y60097I0J197D01*
G01X330413Y60065D02*
G03X330511Y60039I98J171D01*
G01X330413Y56916D02*
G03X330511Y56889I100J170D01*
G01X331643Y57369D02*
G03X331694Y57362I52J190D01*
G01Y59921D02*
G03X331643Y59914I1J-197D01*
G01Y62369D02*
G03X331694Y62362I52J190D01*
G01X330511Y55511D02*
G03X330413Y55485I0J-197D01*
G01X333526Y53937D02*
G03X333387Y53879I1J-197D01*
G01X333166Y53740D02*
G03X333305Y53798I0J197D01*
G01X330413Y53766D02*
G03X330511Y53740I98J171D01*
G01X333526Y50787D02*
G03X333387Y50730I0J-197D01*
G01X333166Y50590D02*
G03X333305Y50648I-1J197D01*
G01X330413Y50617D02*
G03X330511Y50590I100J170D01*
G01X330413Y47467D02*
G03X330511Y47441I98J171D01*
G01X331643Y47369D02*
G03X331694Y47362I52J190D01*
G01Y49921D02*
G03X331643Y49914I1J-197D01*
G01Y52369D02*
G03X331694Y52362I52J190D01*
G01Y54921D02*
G03X331643Y54914I1J-197D01*
G01X325449Y59941D02*
G03X325826Y60020I180J79D01*
G01Y58681D02*
G03X325449Y58759I-197J-1D01*
G01X325826Y61830D02*
G03X325449Y61909I-197J0D01*
G01Y56791D02*
G03X325826Y56870I180J79D01*
G01X320271Y56929D02*
G03X320467Y57126I-1J197D01*
G01Y60157D02*
G03X320271Y60354I-197J0D01*
G01Y61929D02*
G03X320467Y62126I-1J197D01*
G01X325449Y50492D02*
G03X325826Y50571I180J79D01*
G01Y49232D02*
G03X325449Y49311I-197J0D01*
G01Y53641D02*
G03X325826Y53720I180J79D01*
G01Y52382D02*
G03X325449Y52460I-197J-1D01*
G01X325826Y55531D02*
G03X325449Y55610I-197J0D01*
G01Y47342D02*
G03X325826Y47421I180J79D01*
G01X320271Y46929D02*
G03X320467Y47126I-1J197D01*
G01Y50157D02*
G03X320271Y50354I-197J0D01*
G01Y51929D02*
G03X320467Y52126I-1J197D01*
G01Y55157D02*
G03X320271Y55354I-197J0D01*
G01X334785Y47698D02*
X334506Y47420D01*
G01X333445Y47637D02*
X333248Y47441D01*
G01X333387Y50730D02*
X333305Y50648D01*
G01X334785Y52698D02*
X334506Y52420D01*
G01X330118Y49015D02*
X330413Y49186D01*
G01X330118Y52165D02*
X330413Y52335D01*
G01X330118Y55315D02*
X330413Y55485D01*
G01X333387Y53879D02*
X333305Y53798D01*
G01X334785Y57698D02*
X334506Y57420D01*
G01X333445Y57086D02*
X333248Y56889D01*
G01X333387Y60178D02*
X333305Y60097D01*
G01X334785Y62698D02*
X334506Y62420D01*
G01X322806Y47342D02*
X322727Y47185D01*
G01X322045D02*
X322124Y47342D01*
G01X322806Y50492D02*
X322727Y50334D01*
G01X322045D02*
X322124Y50492D01*
G01X322806Y53641D02*
X322727Y53484D01*
G01X322045D02*
X322124Y53641D01*
G01X322806Y56791D02*
X322727Y56633D01*
G01X322045D02*
X322124Y56791D01*
G01X330118Y58464D02*
X330413Y58635D01*
G01X330118Y61614D02*
X330413Y61784D01*
G01X322806Y59941D02*
X322727Y59783D01*
G01X322045D02*
X322124Y59941D01*
G01X331299Y57992D02*
Y59291D01*
G01Y52992D02*
Y54291D01*
G01Y47992D02*
Y49291D01*
G01X325826Y61302D02*
Y61830D01*
G01Y60020D02*
Y60539D01*
G01Y58153D02*
Y58681D01*
G01Y56870D02*
Y57389D01*
G01Y53720D02*
Y54239D01*
G01Y51854D02*
Y52382D01*
G01Y50571D02*
Y51090D01*
G01Y48704D02*
Y49232D01*
G01Y47421D02*
Y47940D01*
G01Y55531D02*
Y55003D01*
G01X325218Y50492D02*
Y49311D01*
G01Y53641D02*
Y52460D01*
G01Y56791D02*
Y55610D01*
G01Y59941D02*
Y58759D01*
G01Y63090D02*
Y61909D01*
G01X324366D02*
Y63090D01*
G01Y58759D02*
Y59941D01*
G01Y55610D02*
Y56791D01*
G01Y52460D02*
Y53641D01*
G01Y49311D02*
Y50492D01*
G01X323838Y61102D02*
Y63189D01*
G01Y58267D02*
Y60472D01*
G01Y54370D02*
Y56574D01*
G01Y53031D02*
Y53307D01*
G01Y52441D02*
Y52834D01*
G01Y51141D02*
Y51968D01*
G01X323684Y50492D02*
Y49311D01*
G01Y53641D02*
Y52460D01*
G01Y56791D02*
Y55610D01*
G01Y59941D02*
Y58759D01*
G01Y63090D02*
Y61909D01*
G01X322062Y47185D02*
Y46319D01*
G01Y50334D02*
Y49468D01*
G01Y53484D02*
Y52618D01*
G01Y56633D02*
Y55767D01*
G01Y59783D02*
Y58917D01*
G01Y62933D02*
Y62067D01*
G01X321380D02*
Y62933D01*
G01Y58917D02*
Y59783D01*
G01Y55767D02*
Y56633D01*
G01Y52618D02*
Y53484D01*
G01Y49468D02*
Y50334D01*
G01Y46319D02*
Y47185D01*
G01X320528D02*
Y46319D01*
G01Y50334D02*
Y49468D01*
G01Y53484D02*
Y52618D01*
G01Y56633D02*
Y55767D01*
G01Y59783D02*
Y58917D01*
G01Y62933D02*
Y62067D01*
G01X320467Y62126D02*
Y63110D01*
G01Y57126D02*
Y58110D01*
G01Y52126D02*
Y53110D01*
G01Y49173D02*
Y50157D01*
G01Y47126D02*
Y48110D01*
G01Y55157D02*
Y54173D01*
G01Y60157D02*
Y59173D01*
G01X322727Y62067D02*
X322806Y61909D01*
G01X322124D02*
X322045Y62067D01*
G01X322727Y58917D02*
X322806Y58759D01*
G01X322124D02*
X322045Y58917D01*
G01X322727Y55767D02*
X322806Y55610D01*
G01X322124D02*
X322045Y55767D01*
G01X322727Y52618D02*
X322806Y52460D01*
G01X322124D02*
X322045Y52618D01*
G01X322727Y49468D02*
X322806Y49311D01*
G01X322124D02*
X322045Y49468D01*
G01X334405Y61753D02*
X334486Y61672D01*
G01X334506Y59863D02*
X334785Y59585D01*
G01X334405Y58604D02*
X334486Y58522D01*
G01X334429Y55511D02*
X334626Y55315D01*
G01X334506Y54863D02*
X334785Y54585D01*
G01X334405Y52304D02*
X334486Y52223D01*
G01X334506Y49863D02*
X334785Y49585D01*
G01X334405Y49155D02*
X334486Y49073D01*
G01X330413Y60065D02*
X330118Y60236D01*
G01X330413Y56916D02*
X330118Y57086D01*
G01X330413Y53766D02*
X330118Y53937D01*
G01X330413Y50617D02*
X330118Y50787D01*
G01X330413Y47467D02*
X330118Y47637D01*
G01X331643Y62369D02*
X330118Y62778D01*
G01X331643Y57369D02*
X330118Y57778D01*
G01X331643Y52369D02*
X330118Y52778D01*
G01X331643Y47369D02*
X330118Y47778D01*
G01X331694Y62362D02*
X334367D01*
G01X322124Y61909D02*
X325449D01*
G01X330511Y61811D02*
X334266D01*
G01X345078Y61614D02*
X334626D01*
G01X326023Y61302D02*
X325826D01*
G01Y60539D02*
X326023D01*
G01X333526Y60236D02*
X345078D01*
G01X330511Y60039D02*
X333166D01*
G01X322124Y59941D02*
X325449D01*
G01X334367Y59921D02*
X331694D01*
G01X344493Y59527D02*
X334924D01*
G01X330118Y59291D02*
X331299D01*
G01X323819Y59173D02*
X320467D01*
G01X322124Y58759D02*
X325449D01*
G01X330511Y58661D02*
X334266D01*
G01X345078Y58464D02*
X334626D01*
G01X326023Y58153D02*
X325826D01*
G01X320467Y58110D02*
X323819D01*
G01X330118Y57992D02*
X331299D01*
G01X334924Y57756D02*
X344493D01*
G01X326023Y57389D02*
X325826D01*
G01X331694Y57362D02*
X334367D01*
G01X333445Y57086D02*
X347047D01*
G01X330511Y56889D02*
X333248D01*
G01X322124Y56791D02*
X325449D01*
G01X322124Y55610D02*
X325449D01*
G01X334429Y55511D02*
X330511D01*
G01X347047Y55315D02*
X334626D01*
G01X325826Y55003D02*
X326023D01*
G01X334367Y54921D02*
X331694D01*
G01X344493Y54527D02*
X334924D01*
G01X330118Y54291D02*
X331299D01*
G01X325826Y54239D02*
X326023D01*
G01X323819Y54173D02*
X320467D01*
G01X333526Y53937D02*
X345078D01*
G01X330511Y53740D02*
X333166D01*
G01X322124Y53641D02*
X325449D01*
G01X320467Y53110D02*
X323819D01*
G01X331299Y52992D02*
X330118D01*
G01X334924Y52756D02*
X344398D01*
G01X322124Y52460D02*
X325449D01*
G01X334266Y52362D02*
X334367D01*
G01X330511D02*
X334266D01*
G01X345078Y52165D02*
X334626D01*
G01X326023Y51854D02*
X325826D01*
G01Y51090D02*
X326023D01*
G01X333526Y50787D02*
X345078D01*
G01X330511Y50590D02*
X333166D01*
G01X322124Y50492D02*
X325449D01*
G01X334367Y49921D02*
X331694D01*
G01X344398Y49527D02*
X334924D01*
G01X322124Y49311D02*
X325449D01*
G01X331299Y49291D02*
X330118D01*
G01X330511Y49212D02*
X334266D01*
G01X320467Y49173D02*
X323819D01*
G01X345078Y49015D02*
X334626D01*
G01X326023Y48704D02*
X325826D01*
G01X320467Y48110D02*
X323819D01*
G01X331299Y47992D02*
X330118D01*
G01X326023Y47940D02*
X325826D01*
G01X334924Y47756D02*
X344398D01*
G01X333445Y47637D02*
X347047D01*
G01X330511Y47441D02*
X333248D01*
G01X331694Y47362D02*
X334367D01*
G01X322124Y47342D02*
X325449D01*
G01X330118Y59506D02*
X331643Y59914D01*
G01X330118Y54506D02*
X331643Y54914D01*
G01X330118Y49506D02*
X331643Y49914D01*
G01X330477Y77556D02*
X330511Y77559D01*
G01X330444Y77547D02*
X330477Y77556D01*
G01X330413Y77532D02*
X330444Y77547D01*
G01X330477Y71257D02*
X330511Y71259D01*
G01X330444Y71248D02*
X330477Y71257D01*
G01X330413Y71233D02*
X330444Y71248D01*
G01X330477Y68107D02*
X330511Y68110D01*
G01X330444Y68098D02*
X330477Y68107D01*
G01X330413Y68083D02*
X330444Y68098D01*
G01X334405Y77501D02*
G03X334266Y77559I-140J-139D01*
G01X334486Y77420D02*
G03X334626Y77362I140J139D01*
G01X334405Y71202D02*
G03X334266Y71259I-138J-140D01*
G01X334486Y71120D02*
G03X334626Y71063I139J140D01*
G01X334405Y68052D02*
G03X334266Y68110I-140J-139D01*
G01X334486Y67971D02*
G03X334626Y67913I140J139D01*
G01X334924Y67756D02*
G03X334785Y67698I1J-197D01*
G01X334367Y67362D02*
G03X334506Y67420I0J197D01*
G01Y69863D02*
G03X334367Y69921I-139J-139D01*
G01X334785Y69585D02*
G03X334924Y69527I140J139D01*
G01Y72756D02*
G03X334785Y72698I1J-197D01*
G01X334367Y72362D02*
G03X334506Y72420I0J197D01*
G01Y74863D02*
G03X334367Y74921I-139J-139D01*
G01X334785Y74585D02*
G03X334924Y74527I140J139D01*
G01Y77756D02*
G03X334785Y77698I1J-197D01*
G01X334367Y77362D02*
G03X334506Y77420I0J197D01*
G01Y64863D02*
G03X334367Y64921I-139J-139D01*
G01X334785Y64585D02*
G03X334924Y64527I140J139D01*
G01X333526Y79133D02*
G03X333387Y79076I-1J-197D01*
G01X333166Y78937D02*
G03X333305Y78995I0J197D01*
G01X330413Y78963D02*
G03X330511Y78937I98J171D01*
G01X330413Y75813D02*
G03X330511Y75787I98J171D01*
G01Y74409D02*
G03X330413Y74383I0J-197D01*
G01X333526Y72834D02*
G03X333387Y72777I-1J-197D01*
G01X333166Y72637D02*
G03X333305Y72695I-1J197D01*
G01X330413Y72664D02*
G03X330511Y72637I100J170D01*
G01X333526Y69685D02*
G03X333387Y69627I1J-197D01*
G01X333166Y69488D02*
G03X333305Y69546I0J197D01*
G01X330413Y69514D02*
G03X330511Y69488I98J171D01*
G01X331643Y67369D02*
G03X331694Y67362I52J190D01*
G01Y69921D02*
G03X331643Y69914I1J-197D01*
G01Y72369D02*
G03X331694Y72362I52J190D01*
G01Y74921D02*
G03X331643Y74914I1J-197D01*
G01Y77369D02*
G03X331694Y77362I52J190D01*
G01X325449Y78838D02*
G03X325826Y78917I180J79D01*
G01X325449Y69389D02*
G03X325826Y69469I180J79D01*
G01Y68130D02*
G03X325449Y68208I-197J-1D01*
G01X325826Y77578D02*
G03X325449Y77657I-197J0D01*
G01Y72539D02*
G03X325826Y72618I180J79D01*
G01Y71279D02*
G03X325449Y71358I-197J0D01*
G01X325826Y74429D02*
G03X325449Y74508I-197J0D01*
G01Y75689D02*
G03X325826Y75767I180J79D01*
G01X320467Y75157D02*
G03X320271Y75354I-197J0D01*
G01Y76929D02*
G03X320467Y77126I-1J197D01*
G01Y70157D02*
G03X320271Y70354I-197J0D01*
G01Y71929D02*
G03X320467Y72126I-1J197D01*
G01X330413Y66365D02*
G03X330511Y66338I100J170D01*
G01Y64960D02*
G03X330413Y64934I0J-197D01*
G01X333526Y63385D02*
G03X333387Y63328I-1J-197D01*
G01X333166Y63189D02*
G03X333305Y63246I1J197D01*
G01X330413Y63215D02*
G03X330511Y63189I98J171D01*
G01X331694Y64921D02*
G03X331643Y64914I1J-197D01*
G01X325449Y63090D02*
G03X325826Y63169I180J79D01*
G01Y64980D02*
G03X325449Y65059I-197J0D01*
G01Y66240D02*
G03X325826Y66319I180J79D01*
G01X320467Y65157D02*
G03X320271Y65354I-197J0D01*
G01Y66929D02*
G03X320467Y67126I-1J197D01*
G01X333387Y63328D02*
X333305Y63246D01*
G01X334785Y67698D02*
X334506Y67420D01*
G01X333445Y66535D02*
X333248Y66338D01*
G01X333387Y69627D02*
X333305Y69546D01*
G01X334785Y72698D02*
X334506Y72420D01*
G01X333387Y72777D02*
X333305Y72695D01*
G01X330118Y64763D02*
X330413Y64934D01*
G01X330118Y67913D02*
X330413Y68083D01*
G01X330118Y71063D02*
X330413Y71233D01*
G01X330118Y74212D02*
X330413Y74383D01*
G01X333445Y75984D02*
X333248Y75787D01*
G01X334785Y77698D02*
X334506Y77420D01*
G01X333387Y79076D02*
X333305Y78995D01*
G01X322806Y63090D02*
X322727Y62933D01*
G01X322045D02*
X322124Y63090D01*
G01X322806Y66240D02*
X322727Y66082D01*
G01X322045D02*
X322124Y66240D01*
G01X322806Y69389D02*
X322727Y69232D01*
G01X322045D02*
X322124Y69389D01*
G01X322806Y72539D02*
X322727Y72382D01*
G01X322045D02*
X322124Y72539D01*
G01X322806Y75689D02*
X322727Y75531D01*
G01X322045D02*
X322124Y75689D01*
G01X322806Y78838D02*
X322727Y78681D01*
G01X322045D02*
X322124Y78838D01*
G01X330118Y77362D02*
X330413Y77532D01*
G01X331299Y72992D02*
Y74291D01*
G01Y67992D02*
Y69291D01*
G01Y62992D02*
Y64291D01*
G01Y79291D02*
Y77992D01*
G01X325826Y78917D02*
Y79436D01*
G01Y77050D02*
Y77578D01*
G01Y75767D02*
Y76287D01*
G01Y72618D02*
Y73137D01*
G01Y73901D02*
Y74429D01*
G01Y70751D02*
Y71279D01*
G01Y69469D02*
Y69987D01*
G01Y67602D02*
Y68130D01*
G01Y66319D02*
Y66838D01*
G01Y63169D02*
Y63688D01*
G01Y64980D02*
Y64452D01*
G01X325218Y66240D02*
Y65059D01*
G01Y69389D02*
Y68208D01*
G01Y72539D02*
Y71358D01*
G01Y75689D02*
Y74508D01*
G01Y78838D02*
Y77657D01*
G01X324366D02*
Y78838D01*
G01Y74508D02*
Y75689D01*
G01Y71358D02*
Y72539D01*
G01Y68208D02*
Y69389D01*
G01Y65059D02*
Y66240D01*
G01X323838Y74677D02*
Y76764D01*
G01X323684Y66240D02*
Y65059D01*
G01Y69389D02*
Y68208D01*
G01Y72539D02*
Y71358D01*
G01Y75689D02*
Y74508D01*
G01Y78838D02*
Y77657D01*
G01X322062Y66082D02*
Y65216D01*
G01Y69232D02*
Y68366D01*
G01Y72382D02*
Y71515D01*
G01Y75531D02*
Y74665D01*
G01Y78681D02*
Y77815D01*
G01X321380D02*
Y78681D01*
G01Y74665D02*
Y75531D01*
G01Y71515D02*
Y72382D01*
G01Y68366D02*
Y69232D01*
G01Y65216D02*
Y66082D01*
G01X320528D02*
Y65216D01*
G01Y69232D02*
Y68366D01*
G01Y72382D02*
Y71515D01*
G01Y75531D02*
Y74665D01*
G01Y78681D02*
Y77815D01*
G01X320467Y79173D02*
Y80157D01*
G01Y77126D02*
Y78110D01*
G01Y74173D02*
Y75157D01*
G01Y72126D02*
Y73110D01*
G01Y67126D02*
Y68110D01*
G01Y64173D02*
Y65157D01*
G01Y70157D02*
Y69173D01*
G01X322727Y77815D02*
X322806Y77657D01*
G01X322124D02*
X322045Y77815D01*
G01X322727Y74665D02*
X322806Y74508D01*
G01X322124D02*
X322045Y74665D01*
G01X322727Y71515D02*
X322806Y71358D01*
G01X322124D02*
X322045Y71515D01*
G01X322727Y68366D02*
X322806Y68208D01*
G01X322124D02*
X322045Y68366D01*
G01X322727Y65216D02*
X322806Y65059D01*
G01X322124D02*
X322045Y65216D01*
G01X334405Y77501D02*
X334486Y77420D01*
G01X334506Y74863D02*
X334785Y74585D01*
G01X334429Y74409D02*
X334626Y74212D01*
G01X334405Y71202D02*
X334486Y71120D01*
G01X334506Y69863D02*
X334785Y69585D01*
G01X334405Y68052D02*
X334486Y67971D01*
G01X334429Y64960D02*
X334626Y64763D01*
G01X334506Y64863D02*
X334785Y64585D01*
G01X330413Y78963D02*
X330118Y79133D01*
G01X330413Y75813D02*
X330118Y75984D01*
G01X330413Y72664D02*
X330118Y72834D01*
G01X330413Y69514D02*
X330118Y69685D01*
G01X330413Y66365D02*
X330118Y66535D01*
G01X330413Y63215D02*
X330118Y63385D01*
G01X331643Y77369D02*
X330118Y77778D01*
G01X331643Y72369D02*
X330118Y72778D01*
G01X331643Y67369D02*
X330118Y67778D01*
G01X323819Y79173D02*
X320467D01*
G01X333526Y79133D02*
X345078D01*
G01X330511Y78937D02*
X333166D01*
G01X322124Y78838D02*
X325449D01*
G01X320467Y78110D02*
X323819D01*
G01X330118Y77992D02*
X331299D01*
G01X334924Y77756D02*
X344398D01*
G01X322124Y77657D02*
X325449D01*
G01X330511Y77559D02*
X334266D01*
G01X331694Y77362D02*
X334367D01*
G01X345078D02*
X334626D01*
G01X326023Y77050D02*
X325826D01*
G01X326023Y76287D02*
X325826D01*
G01X333445Y75984D02*
X347047D01*
G01X330511Y75787D02*
X333248D01*
G01X322124Y75689D02*
X325449D01*
G01X334367Y74921D02*
X331694D01*
G01X344398Y74527D02*
X334924D01*
G01X322124Y74508D02*
X325449D01*
G01X334429Y74409D02*
X330511D01*
G01X331299Y74291D02*
X330118D01*
G01X347047Y74212D02*
X334626D01*
G01X323819Y74173D02*
X320467D01*
G01X326023Y73901D02*
X325826D01*
G01Y73137D02*
X326023D01*
G01X320467Y73110D02*
X323819D01*
G01X330118Y72992D02*
X331299D01*
G01X333526Y72834D02*
X345078D01*
G01X334924Y72756D02*
X344493D01*
G01X330511Y72637D02*
X333166D01*
G01X322124Y72539D02*
X325449D01*
G01X331694Y72362D02*
X334367D01*
G01X322124Y71358D02*
X325449D01*
G01X330511Y71259D02*
X334266D01*
G01X345078Y71063D02*
X334626D01*
G01X326023Y70751D02*
X325826D01*
G01Y69987D02*
X326023D01*
G01X334367Y69921D02*
X331694D01*
G01X333526Y69685D02*
X345078D01*
G01X344493Y69527D02*
X334924D01*
G01X330511Y69488D02*
X333166D01*
G01X322124Y69389D02*
X325449D01*
G01X330118Y69291D02*
X331299D01*
G01X323819Y69173D02*
X320467D01*
G01X322124Y68208D02*
X325449D01*
G01X330511Y68110D02*
X334266D01*
G01X320467D02*
X323819D01*
G01X330118Y67992D02*
X331299D01*
G01X345078Y67913D02*
X334626D01*
G01X334924Y67756D02*
X344398D01*
G01X326023Y67602D02*
X325826D01*
G01X331694Y67362D02*
X334367D01*
G01X326023Y66838D02*
X325826D01*
G01X333445Y66535D02*
X347047D01*
G01X330511Y66338D02*
X333248D01*
G01X322124Y66240D02*
X325449D01*
G01X322124Y65059D02*
X325449D01*
G01X334429Y64960D02*
X330511D01*
G01X334367Y64921D02*
X331694D01*
G01X347047Y64763D02*
X334626D01*
G01X344398Y64527D02*
X334924D01*
G01X325826Y64452D02*
X326023D01*
G01X330118Y64291D02*
X331299D01*
G01X323819Y64173D02*
X320467D01*
G01X325826Y63688D02*
X326023D01*
G01X333526Y63385D02*
X345078D01*
G01X330511Y63189D02*
X333166D01*
G01X320467Y63110D02*
X323819D01*
G01X322124Y63090D02*
X325449D01*
G01X330118Y62992D02*
X331299D01*
G01X334924Y62756D02*
X344493D01*
G01X330118Y74506D02*
X331643Y74914D01*
G01X330118Y69506D02*
X331643Y69914D01*
G01X330118Y64506D02*
X331643Y64914D01*
G01X330477Y90154D02*
X330511Y90157D01*
G01X330444Y90145D02*
X330477Y90154D01*
G01X330413Y90131D02*
X330444Y90145D01*
G01X330477Y87005D02*
X330511Y87008D01*
G01X330444Y86996D02*
X330477Y87005D01*
G01X330413Y86981D02*
X330444Y86996D01*
G01X330477Y80706D02*
X330511Y80708D01*
G01X330444Y80696D02*
X330477Y80706D01*
G01X330413Y80682D02*
X330444Y80696D01*
G01X330413Y94711D02*
G03X330511Y94685I98J171D01*
G01Y93307D02*
G03X330413Y93280I2J-197D01*
G01X334405Y90100D02*
G03X334266Y90157I-139J-140D01*
G01X334486Y90018D02*
G03X334626Y89960I140J139D01*
G01X333526Y91732D02*
G03X333387Y91674I0J-197D01*
G01X333166Y91535D02*
G03X333305Y91593I-1J197D01*
G01X330413Y91561D02*
G03X330511Y91535I98J171D01*
G01X331694Y89921D02*
G03X331643Y89914I1J-197D01*
G01X334506Y89863D02*
G03X334367Y89921I-139J-139D01*
G01X334785Y89585D02*
G03X334924Y89527I140J139D01*
G01Y92756D02*
G03X334785Y92698I1J-197D01*
G01X334367Y92362D02*
G03X334506Y92420I0J197D01*
G01X331643Y92369D02*
G03X331694Y92362I52J190D01*
G01Y94921D02*
G03X331643Y94914I1J-197D01*
G01X334506Y94863D02*
G03X334367Y94921I-139J-139D01*
G01X334785Y94585D02*
G03X334924Y94527I140J139D01*
G01X325449Y91437D02*
G03X325826Y91516I180J79D01*
G01Y90177D02*
G03X325449Y90256I-197J0D01*
G01X325826Y93326D02*
G03X325449Y93405I-197J0D01*
G01Y94586D02*
G03X325826Y94665I180J79D01*
G01X320467Y90157D02*
G03X320271Y90354I-197J0D01*
G01Y91929D02*
G03X320467Y92126I-1J197D01*
G01Y95157D02*
G03X320271Y95354I-197J0D01*
G01X334405Y86950D02*
G03X334266Y87008I-140J-139D01*
G01X334486Y86869D02*
G03X334626Y86811I139J139D01*
G01X334405Y80651D02*
G03X334266Y80708I-139J-140D01*
G01X334486Y80569D02*
G03X334626Y80511I140J139D01*
G01X334506Y79863D02*
G03X334367Y79921I-139J-139D01*
G01X334785Y79585D02*
G03X334924Y79527I140J139D01*
G01Y82756D02*
G03X334785Y82698I1J-197D01*
G01X334367Y82362D02*
G03X334506Y82420I0J197D01*
G01Y84863D02*
G03X334367Y84921I-139J-139D01*
G01X334785Y84585D02*
G03X334924Y84527I140J139D01*
G01Y87756D02*
G03X334785Y87698I1J-197D01*
G01X334367Y87362D02*
G03X334506Y87420I0J197D01*
G01X333526Y88582D02*
G03X333387Y88525I-1J-197D01*
G01X333166Y88385D02*
G03X333305Y88443I-1J197D01*
G01X330413Y88412D02*
G03X330511Y88385I100J170D01*
G01X330413Y85262D02*
G03X330511Y85236I98J171D01*
G01Y83858D02*
G03X330413Y83832I0J-197D01*
G01X333526Y82283D02*
G03X333387Y82226I0J-197D01*
G01X333166Y82086D02*
G03X333305Y82144I-1J197D01*
G01X330413Y82113D02*
G03X330511Y82086I100J170D01*
G01X331694Y79921D02*
G03X331643Y79914I1J-197D01*
G01Y82369D02*
G03X331694Y82362I52J190D01*
G01Y84921D02*
G03X331643Y84914I1J-197D01*
G01Y87369D02*
G03X331694Y87362I52J190D01*
G01X325449Y88287D02*
G03X325826Y88366I180J79D01*
G01Y87027D02*
G03X325449Y87106I-197J0D01*
G01Y81988D02*
G03X325826Y82067I180J79D01*
G01Y80728D02*
G03X325449Y80807I-197J0D01*
G01X325826Y83878D02*
G03X325449Y83956I-197J-1D01*
G01Y85137D02*
G03X325826Y85216I180J79D01*
G01X320467Y80157D02*
G03X320271Y80354I-197J0D01*
G01Y81929D02*
G03X320467Y82126I-1J197D01*
G01Y85157D02*
G03X320271Y85354I-197J0D01*
G01Y86929D02*
G03X320467Y87126I-1J197D01*
G01X334785Y82698D02*
X334506Y82420D01*
G01X333387Y82226D02*
X333305Y82144D01*
G01X333445Y85433D02*
X333248Y85236D01*
G01X334785Y87698D02*
X334506Y87420D01*
G01X333387Y88525D02*
X333305Y88443D01*
G01X334785Y92698D02*
X334506Y92420D01*
G01X333387Y91674D02*
X333305Y91593D01*
G01X333445Y94882D02*
X333248Y94685D01*
G01X322806Y81988D02*
X322727Y81830D01*
G01X322045D02*
X322124Y81988D01*
G01X322806Y85137D02*
X322727Y84980D01*
G01X322045D02*
X322124Y85137D01*
G01X322806Y88287D02*
X322727Y88130D01*
G01X322045D02*
X322124Y88287D01*
G01X322806Y91437D02*
X322727Y91279D01*
G01X322045D02*
X322124Y91437D01*
G01X322806Y94586D02*
X322727Y94429D01*
G01X322045D02*
X322124Y94586D01*
G01X330118Y80511D02*
X330413Y80682D01*
G01X330118Y83661D02*
X330413Y83832D01*
G01X330118Y86811D02*
X330413Y86981D01*
G01X330118Y89960D02*
X330413Y90131D01*
G01X330118Y93110D02*
X330413Y93280D01*
G01X331299Y87992D02*
Y89291D01*
G01Y82992D02*
Y84291D01*
G01Y94291D02*
Y92992D01*
G01X325826Y94665D02*
Y95184D01*
G01Y91516D02*
Y92035D01*
G01Y92798D02*
Y93326D01*
G01Y89649D02*
Y90177D01*
G01Y88366D02*
Y88885D01*
G01Y86499D02*
Y87027D01*
G01Y85216D02*
Y85735D01*
G01Y82067D02*
Y82586D01*
G01Y83350D02*
Y83878D01*
G01Y80200D02*
Y80728D01*
G01X325218Y81988D02*
Y80807D01*
G01Y85137D02*
Y83956D01*
G01Y88287D02*
Y87106D01*
G01Y91437D02*
Y90256D01*
G01Y94586D02*
Y93405D01*
G01X324366D02*
Y94586D01*
G01Y90256D02*
Y91437D01*
G01Y87106D02*
Y88287D01*
G01Y83956D02*
Y85137D01*
G01Y80807D02*
Y81988D01*
G01X323684D02*
Y80807D01*
G01Y85137D02*
Y83956D01*
G01Y88287D02*
Y87106D01*
G01Y91437D02*
Y90256D01*
G01Y94586D02*
Y93405D01*
G01X322062Y81830D02*
Y80964D01*
G01Y84980D02*
Y84114D01*
G01Y88130D02*
Y87263D01*
G01Y91279D02*
Y90413D01*
G01Y94429D02*
Y93563D01*
G01X321380D02*
Y94429D01*
G01Y90413D02*
Y91279D01*
G01Y87263D02*
Y88130D01*
G01Y84114D02*
Y84980D01*
G01Y80964D02*
Y81830D01*
G01X320528D02*
Y80964D01*
G01Y84980D02*
Y84114D01*
G01Y88130D02*
Y87263D01*
G01Y91279D02*
Y90413D01*
G01Y94429D02*
Y93563D01*
G01X320467Y92126D02*
Y93110D01*
G01Y84173D02*
Y85157D01*
G01Y82126D02*
Y83110D01*
G01Y88110D02*
Y87126D01*
G01Y90157D02*
Y89173D01*
G01Y95157D02*
Y94173D01*
G01X322727Y93563D02*
X322806Y93405D01*
G01X322124D02*
X322045Y93563D01*
G01X322727Y90413D02*
X322806Y90256D01*
G01X322124D02*
X322045Y90413D01*
G01X322727Y87263D02*
X322806Y87106D01*
G01X322124D02*
X322045Y87263D01*
G01X322727Y84114D02*
X322806Y83956D01*
G01X322124D02*
X322045Y84114D01*
G01X322727Y80964D02*
X322806Y80807D01*
G01X322124D02*
X322045Y80964D01*
G01X334506Y94863D02*
X334785Y94585D01*
G01X334429Y93307D02*
X334626Y93110D01*
G01X334405Y90100D02*
X334486Y90018D01*
G01X334506Y89863D02*
X334785Y89585D01*
G01X334405Y86950D02*
X334486Y86869D01*
G01X334506Y84863D02*
X334785Y84585D01*
G01X334429Y83858D02*
X334626Y83661D01*
G01X334405Y80651D02*
X334486Y80569D01*
G01X334506Y79863D02*
X334785Y79585D01*
G01X330413Y94711D02*
X330118Y94882D01*
G01X330413Y91561D02*
X330118Y91732D01*
G01X330413Y88412D02*
X330118Y88582D01*
G01X330413Y85262D02*
X330118Y85433D01*
G01X330413Y82113D02*
X330118Y82283D01*
G01X331643Y92369D02*
X330118Y92778D01*
G01X331643Y87369D02*
X330118Y87778D01*
G01X331643Y82369D02*
X330118Y82778D01*
G01X326023Y95184D02*
X325826D01*
G01X334367Y94921D02*
X331694D01*
G01X333445Y94882D02*
X347047D01*
G01X330511Y94685D02*
X333248D01*
G01X322124Y94586D02*
X325449D01*
G01X344493Y94527D02*
X334924D01*
G01X331299Y94291D02*
X330118D01*
G01X323819Y94173D02*
X320467D01*
G01X322124Y93405D02*
X325449D01*
G01X334429Y93307D02*
X330511D01*
G01X320467Y93110D02*
X323819D01*
G01X347047D02*
X334626D01*
G01X330118Y92992D02*
X331299D01*
G01X326023Y92798D02*
X325826D01*
G01X334924Y92756D02*
X344493D01*
G01X331694Y92362D02*
X334367D01*
G01X325826Y92035D02*
X326023D01*
G01X333526Y91732D02*
X345078D01*
G01X330511Y91535D02*
X333166D01*
G01X322124Y91437D02*
X325449D01*
G01X322124Y90256D02*
X325449D01*
G01X330511Y90157D02*
X334266D01*
G01X345078Y89960D02*
X334626D01*
G01X334367Y89921D02*
X331694D01*
G01X326023Y89649D02*
X325826D01*
G01X344493Y89527D02*
X334924D01*
G01X331299Y89291D02*
X330118D01*
G01X323819Y89173D02*
X320467D01*
G01X325826Y88885D02*
X326023D01*
G01X345078Y88582D02*
X333526D01*
G01X333166Y88385D02*
X330511D01*
G01X322124Y88287D02*
X325449D01*
G01X320467Y88110D02*
X323819D01*
G01X330118Y87992D02*
X331299D01*
G01X334924Y87756D02*
X344493D01*
G01X331694Y87362D02*
X334367D01*
G01X322124Y87106D02*
X325449D01*
G01X334266Y87008D02*
X330511D01*
G01X345078Y86811D02*
X334626D01*
G01X326023Y86499D02*
X325826D01*
G01X326023Y85735D02*
X325826D01*
G01X333445Y85433D02*
X347047D01*
G01X330511Y85236D02*
X333248D01*
G01X322124Y85137D02*
X325449D01*
G01X334367Y84921D02*
X331694D01*
G01X344493Y84527D02*
X334924D01*
G01X331299Y84291D02*
X330118D01*
G01X323819Y84173D02*
X320467D01*
G01X322124Y83956D02*
X325449D01*
G01X334429Y83858D02*
X330511D01*
G01X347047Y83661D02*
X334626D01*
G01X326023Y83350D02*
X325826D01*
G01X320467Y83110D02*
X323819D01*
G01X331299Y82992D02*
X330118D01*
G01X334924Y82756D02*
X344398D01*
G01X325826Y82586D02*
X326023D01*
G01X331694Y82362D02*
X334367D01*
G01X333526Y82283D02*
X345078D01*
G01X330511Y82086D02*
X333166D01*
G01X322124Y81988D02*
X325449D01*
G01X322124Y80807D02*
X325449D01*
G01X330511Y80708D02*
X334266D01*
G01X345078Y80511D02*
X334626D01*
G01X326023Y80200D02*
X325826D01*
G01X334367Y79921D02*
X331694D01*
G01X344398Y79527D02*
X334924D01*
G01X325826Y79436D02*
X326023D01*
G01X331299Y79291D02*
X330118D01*
G01Y94506D02*
X331643Y94914D01*
G01X330118Y89506D02*
X331643Y89914D01*
G01X330118Y84506D02*
X331643Y84914D01*
G01X330118Y79506D02*
X331643Y79914D01*
G01X330477Y109052D02*
X330511Y109055D01*
G01X330444Y109043D02*
X330477Y109052D01*
G01X330413Y109028D02*
X330444Y109043D01*
G01X330477Y105902D02*
X330511Y105905D01*
G01X330444Y105893D02*
X330477Y105902D01*
G01X330413Y105879D02*
X330444Y105893D01*
G01X330477Y99603D02*
X330511Y99606D01*
G01X330444Y99594D02*
X330477Y99603D01*
G01X330413Y99580D02*
X330444Y99594D01*
G01X330477Y96454D02*
X330511Y96456D01*
G01X330444Y96445D02*
X330477Y96454D01*
G01X330413Y96430D02*
X330444Y96445D01*
G01X330511Y112204D02*
G03X330413Y112178I0J-197D01*
G01X325826Y112224D02*
G03X325449Y112303I-197J0D01*
G01X334405Y108997D02*
G03X334266Y109055I-140J-139D01*
G01X334486Y108916D02*
G03X334626Y108858I140J139D01*
G01X333526Y110630D02*
G03X333387Y110572I1J-197D01*
G01X333166Y110433D02*
G03X333305Y110491I0J197D01*
G01X330413Y110459D02*
G03X330511Y110433I98J171D01*
G01X334405Y105848D02*
G03X334266Y105905I-139J-140D01*
G01X334486Y105766D02*
G03X334626Y105708I140J139D01*
G01X333526Y107480D02*
G03X333387Y107422I0J-197D01*
G01X333166Y107283D02*
G03X333305Y107341I-1J197D01*
G01X330413Y107309D02*
G03X330511Y107283I98J171D01*
G01X330413Y104160D02*
G03X330511Y104133I100J170D01*
G01Y102756D02*
G03X330413Y102729I2J-197D01*
G01X333526Y101181D02*
G03X333387Y101123I1J-197D01*
G01X333166Y100984D02*
G03X333305Y101042I0J197D01*
G01X330413Y101010D02*
G03X330511Y100984I98J171D01*
G01X331694Y109921D02*
G03X331643Y109914I1J-197D01*
G01X334506Y109863D02*
G03X334367Y109921I-139J-139D01*
G01X334785Y109585D02*
G03X334924Y109527I140J139D01*
G01Y102756D02*
G03X334785Y102698I1J-197D01*
G01X334367Y102362D02*
G03X334506Y102420I0J197D01*
G01X331643Y102369D02*
G03X331694Y102362I52J190D01*
G01Y104921D02*
G03X331643Y104914I1J-197D01*
G01X334506Y104863D02*
G03X334367Y104921I-139J-139D01*
G01X334785Y104585D02*
G03X334924Y104527I140J139D01*
G01Y107756D02*
G03X334785Y107698I1J-197D01*
G01X334367Y107362D02*
G03X334506Y107420I0J197D01*
G01X331643Y107369D02*
G03X331694Y107362I52J190D01*
G01X334405Y99548D02*
G03X334266Y99606I-140J-139D01*
G01X334486Y99467D02*
G03X334626Y99409I140J139D01*
G01X334405Y96399D02*
G03X334266Y96456I-139J-140D01*
G01X334486Y96317D02*
G03X334626Y96259I140J139D01*
G01X333526Y98031D02*
G03X333387Y97974I0J-197D01*
G01X333166Y97834D02*
G03X333305Y97892I-1J197D01*
G01X330413Y97861D02*
G03X330511Y97834I100J170D01*
G01X334924Y97756D02*
G03X334785Y97698I1J-197D01*
G01X334367Y97362D02*
G03X334506Y97420I0J197D01*
G01X331643Y97369D02*
G03X331694Y97362I52J190D01*
G01Y99921D02*
G03X331643Y99914I1J-197D01*
G01X334506Y99863D02*
G03X334367Y99921I-139J-139D01*
G01X334785Y99585D02*
G03X334924Y99527I140J139D01*
G01X325449Y107185D02*
G03X325826Y107264I180J79D01*
G01Y105925D02*
G03X325449Y106004I-197J0D01*
G01Y100885D02*
G03X325826Y100965I180J79D01*
G01X325449Y110334D02*
G03X325826Y110413I180J79D01*
G01Y109074D02*
G03X325449Y109153I-197J0D01*
G01X325826Y102775D02*
G03X325449Y102854I-197J0D01*
G01Y104035D02*
G03X325826Y104114I180J79D01*
G01X325449Y97736D02*
G03X325826Y97815I180J79D01*
G01Y96476D02*
G03X325449Y96555I-197J0D01*
G01X325826Y99626D02*
G03X325449Y99704I-197J-1D01*
G01X320467Y110157D02*
G03X320271Y110354I-197J0D01*
G01Y111929D02*
G03X320467Y112126I-1J197D01*
G01Y100157D02*
G03X320271Y100354I-197J0D01*
G01Y101929D02*
G03X320467Y102126I-1J197D01*
G01Y105157D02*
G03X320271Y105354I-197J0D01*
G01Y106929D02*
G03X320467Y107126I-1J197D01*
G01X320271Y96929D02*
G03X320467Y97126I-1J197D01*
G01X334785Y97698D02*
X334506Y97420D01*
G01X333387Y97974D02*
X333305Y97892D01*
G01X333387Y101123D02*
X333305Y101042D01*
G01X334785Y102698D02*
X334506Y102420D01*
G01X333445Y104330D02*
X333248Y104133D01*
G01X334785Y107698D02*
X334506Y107420D01*
G01X333387Y107422D02*
X333305Y107341D01*
G01X333387Y110572D02*
X333305Y110491D01*
G01X322806Y97736D02*
X322727Y97578D01*
G01X322045D02*
X322124Y97736D01*
G01X322806Y100885D02*
X322727Y100728D01*
G01X322045D02*
X322124Y100885D01*
G01X322806Y104035D02*
X322727Y103878D01*
G01X322045D02*
X322124Y104035D01*
G01X322806Y107185D02*
X322727Y107027D01*
G01X322045D02*
X322124Y107185D01*
G01X322806Y110334D02*
X322727Y110177D01*
G01X322045D02*
X322124Y110334D01*
G01X331299Y107992D02*
Y109291D01*
G01Y97992D02*
Y99291D01*
G01Y104291D02*
Y102992D01*
G01X330118Y96259D02*
X330413Y96430D01*
G01X330118Y99409D02*
X330413Y99580D01*
G01X330118Y102559D02*
X330413Y102729D01*
G01X330118Y105708D02*
X330413Y105879D01*
G01X330118Y108858D02*
X330413Y109028D01*
G01X330118Y112008D02*
X330413Y112178D01*
G01X325826Y110413D02*
Y110932D01*
G01Y111696D02*
Y112224D01*
G01Y108546D02*
Y109074D01*
G01Y107264D02*
Y107783D01*
G01Y105397D02*
Y105925D01*
G01Y104114D02*
Y104633D01*
G01Y100965D02*
Y101483D01*
G01Y102247D02*
Y102775D01*
G01Y99098D02*
Y99626D01*
G01Y97815D02*
Y98334D01*
G01Y95948D02*
Y96476D01*
G01X325218Y97736D02*
Y96555D01*
G01Y100885D02*
Y99704D01*
G01Y104035D02*
Y102854D01*
G01Y107185D02*
Y106004D01*
G01Y110334D02*
Y109153D01*
G01X324366D02*
Y110334D01*
G01Y106004D02*
Y107185D01*
G01Y102854D02*
Y104035D01*
G01Y99704D02*
Y100885D01*
G01Y96555D02*
Y97736D01*
G01X323684D02*
Y96555D01*
G01Y100885D02*
Y99704D01*
G01Y104035D02*
Y102854D01*
G01Y107185D02*
Y106004D01*
G01Y110334D02*
Y109153D01*
G01X322062Y97578D02*
Y96712D01*
G01Y100728D02*
Y99862D01*
G01Y103878D02*
Y103011D01*
G01Y107027D02*
Y106161D01*
G01Y110177D02*
Y109311D01*
G01X321380D02*
Y110177D01*
G01Y106161D02*
Y107027D01*
G01Y103011D02*
Y103878D01*
G01Y99862D02*
Y100728D01*
G01Y96712D02*
Y97578D01*
G01X320528D02*
Y96712D01*
G01Y100728D02*
Y99862D01*
G01Y103878D02*
Y103011D01*
G01Y107027D02*
Y106161D01*
G01Y110177D02*
Y109311D01*
G01X320467Y112126D02*
Y113110D01*
G01Y109173D02*
Y110157D01*
G01Y104173D02*
Y105157D01*
G01Y102126D02*
Y103110D01*
G01Y97126D02*
Y98110D01*
G01Y100157D02*
Y99173D01*
G01Y108110D02*
Y107126D01*
G01X322727Y109311D02*
X322806Y109153D01*
G01X322124D02*
X322045Y109311D01*
G01X322727Y106161D02*
X322806Y106004D01*
G01X322124D02*
X322045Y106161D01*
G01X322727Y103011D02*
X322806Y102854D01*
G01X322124D02*
X322045Y103011D01*
G01X322727Y99862D02*
X322806Y99704D01*
G01X322124D02*
X322045Y99862D01*
G01X322727Y96712D02*
X322806Y96555D01*
G01X322124D02*
X322045Y96712D01*
G01X334429Y112204D02*
X334626Y112008D01*
G01X334506Y109863D02*
X334785Y109585D01*
G01X334405Y108997D02*
X334486Y108916D01*
G01X334405Y105848D02*
X334486Y105766D01*
G01X334506Y104863D02*
X334785Y104585D01*
G01X334429Y102756D02*
X334626Y102559D01*
G01X334506Y99863D02*
X334785Y99585D01*
G01X334405Y99548D02*
X334486Y99467D01*
G01X334405Y96399D02*
X334486Y96317D01*
G01X330413Y110459D02*
X330118Y110630D01*
G01X330413Y107309D02*
X330118Y107480D01*
G01X330413Y104160D02*
X330118Y104330D01*
G01X330413Y101010D02*
X330118Y101181D01*
G01X330413Y97861D02*
X330118Y98031D01*
G01X331643Y107369D02*
X330118Y107778D01*
G01X331643Y102369D02*
X330118Y102778D01*
G01X331643Y97369D02*
X330118Y97778D01*
G01X334429Y112204D02*
X330511D01*
G01X347047Y112008D02*
X334626D01*
G01X326023Y111696D02*
X325826D01*
G01Y110932D02*
X326023D01*
G01X333526Y110630D02*
X345078D01*
G01X330511Y110433D02*
X333166D01*
G01X322124Y110334D02*
X325449D01*
G01X334367Y109921D02*
X331694D01*
G01X344398Y109527D02*
X334924D01*
G01X331299Y109291D02*
X330118D01*
G01X323819Y109173D02*
X320467D01*
G01X322124Y109153D02*
X325449D01*
G01X330511Y109055D02*
X334266D01*
G01X345078Y108858D02*
X334626D01*
G01X326023Y108546D02*
X325826D01*
G01X320467Y108110D02*
X323819D01*
G01X331299Y107992D02*
X330118D01*
G01X325826Y107783D02*
X326023D01*
G01X334924Y107756D02*
X344493D01*
G01X333526Y107480D02*
X345078D01*
G01X331694Y107362D02*
X334367D01*
G01X330511Y107283D02*
X333166D01*
G01X322124Y107185D02*
X325449D01*
G01X322124Y106004D02*
X325449D01*
G01X330511Y105905D02*
X334266D01*
G01X345078Y105708D02*
X334626D01*
G01X326023Y105397D02*
X325826D01*
G01X334367Y104921D02*
X331694D01*
G01X326023Y104633D02*
X325826D01*
G01X344493Y104527D02*
X334924D01*
G01X333445Y104330D02*
X347047D01*
G01X331299Y104291D02*
X330118D01*
G01X323819Y104173D02*
X320467D01*
G01X330511Y104133D02*
X333248D01*
G01X322124Y104035D02*
X325449D01*
G01X320467Y103110D02*
X323819D01*
G01X331299Y102992D02*
X330118D01*
G01X322124Y102854D02*
X325449D01*
G01X334924Y102756D02*
X344493D01*
G01X334429D02*
X330511D01*
G01X347047Y102559D02*
X334626D01*
G01X331694Y102362D02*
X334367D01*
G01X326023Y102247D02*
X325826D01*
G01Y101483D02*
X326023D01*
G01X333526Y101181D02*
X345078D01*
G01X330511Y100984D02*
X333166D01*
G01X322124Y100885D02*
X325449D01*
G01X334367Y99921D02*
X331694D01*
G01X322124Y99704D02*
X325449D01*
G01X330511Y99606D02*
X334266D01*
G01X344493Y99527D02*
X334924D01*
G01X345078Y99409D02*
X334626D01*
G01X330118Y99291D02*
X331299D01*
G01X323819Y99173D02*
X320467D01*
G01X326023Y99098D02*
X325826D01*
G01Y98334D02*
X326023D01*
G01X320467Y98110D02*
X323819D01*
G01X333526Y98031D02*
X345078D01*
G01X331299Y97992D02*
X330118D01*
G01X330511Y97834D02*
X333166D01*
G01X334924Y97756D02*
X344493D01*
G01X322124Y97736D02*
X325449D01*
G01X331694Y97362D02*
X334367D01*
G01X322124Y96555D02*
X325449D01*
G01X330511Y96456D02*
X334266D01*
G01X345078Y96259D02*
X334626D01*
G01X326023Y95948D02*
X325826D01*
G01X330118Y109506D02*
X331643Y109914D01*
G01X330118Y104506D02*
X331643Y104914D01*
G01X330477Y99603D02*
X331643Y99914D01*
G01X330118Y99506D02*
X330444Y99594D01*
G01X320562Y119908D02*
X320588Y119939D01*
G01X320532Y119888D02*
X320562Y119908D01*
G01X320499Y119882D02*
X320532Y119888D01*
G01X320667Y121286D02*
X320641Y121317D01*
G01X320697Y121266D02*
X320667Y121286D01*
G01X320730Y121259D02*
X320697Y121266D01*
G01X320532Y121450D02*
X320499Y121456D01*
G01X320562Y121430D02*
X320532Y121450D01*
G01X320588Y121399D02*
X320562Y121430D01*
G01X330477Y124800D02*
X330511Y124803D01*
G01X330444Y124791D02*
X330477Y124800D01*
G01X330413Y124776D02*
X330444Y124791D01*
G01X330477Y121650D02*
X330511Y121653D01*
G01X330444Y121641D02*
X330477Y121650D01*
G01X330413Y121627D02*
X330444Y121641D01*
G01X330477Y115351D02*
X330511Y115354D01*
G01X330444Y115342D02*
X330477Y115351D01*
G01X330413Y115328D02*
X330444Y115342D01*
G01X320697Y120072D02*
X320730Y120078D01*
G01X320667Y120052D02*
X320697Y120072D01*
G01X320641Y120021D02*
X320667Y120052D01*
G01X330511Y127952D02*
G03X330413Y127926I0J-197D01*
G01X334405Y124745D02*
G03X334266Y124803I-140J-139D01*
G01X334486Y124664D02*
G03X334626Y124606I140J139D01*
G01X333526Y126378D02*
G03X333387Y126320I1J-197D01*
G01X333166Y126181D02*
G03X333305Y126239I0J197D01*
G01X330413Y126207D02*
G03X330511Y126181I98J171D01*
G01X333526Y123228D02*
G03X333387Y123170I0J-197D01*
G01X333166Y123031D02*
G03X333305Y123089I-1J197D01*
G01X330413Y123058D02*
G03X330511Y123031I100J170D01*
G01X334405Y121596D02*
G03X334266Y121653I-139J-140D01*
G01X334486Y121514D02*
G03X334626Y121456I140J139D01*
G01X330413Y119908D02*
G03X330511Y119882I98J171D01*
G01Y118504D02*
G03X330413Y118477I2J-197D01*
G01X334405Y115296D02*
G03X334266Y115354I-140J-139D01*
G01X334486Y115215D02*
G03X334626Y115157I140J139D01*
G01X333526Y116929D02*
G03X333387Y116871I1J-197D01*
G01X333166Y116732D02*
G03X333305Y116790I0J197D01*
G01X330413Y116758D02*
G03X330511Y116732I98J171D01*
G01X330413Y113609D02*
G03X330511Y113582I100J170D01*
G01X334924Y112756D02*
G03X334785Y112698I1J-197D01*
G01X334367Y112362D02*
G03X334506Y112420I0J197D01*
G01X331643Y112369D02*
G03X331694Y112362I52J190D01*
G01Y114921D02*
G03X331643Y114914I1J-197D01*
G01X334506Y114863D02*
G03X334367Y114921I-139J-139D01*
G01X334785Y114585D02*
G03X334924Y114527I140J139D01*
G01Y117756D02*
G03X334785Y117698I1J-197D01*
G01X334367Y117362D02*
G03X334506Y117420I0J197D01*
G01X331643Y117369D02*
G03X331694Y117362I52J190D01*
G01X325449Y122933D02*
G03X325826Y123012I180J79D01*
G01X325449Y126082D02*
G03X325826Y126161I180J79D01*
G01Y124822D02*
G03X325449Y124901I-197J0D01*
G01X325826Y127972D02*
G03X325449Y128051I-197J0D01*
G01X330171Y122933D02*
G03X330118Y122926I-1J-197D01*
G01Y124712D02*
G03X330171Y124704I56J189D01*
G01Y126082D02*
G03X330118Y126075I-1J-197D01*
G01Y127861D02*
G03X330171Y127854I52J190D01*
G01X325826Y121673D02*
G03X325449Y121752I-197J0D01*
G01Y116633D02*
G03X325826Y116713I180J79D01*
G01Y115374D02*
G03X325449Y115452I-197J-1D01*
G01Y113484D02*
G03X325826Y113563I180J79D01*
G01Y118523D02*
G03X325449Y118602I-197J0D01*
G01Y119783D02*
G03X325826Y119862I180J79D01*
G01X330171Y119783D02*
G03X330118Y119776I-1J-197D01*
G01Y121562D02*
G03X330171Y121555I52J190D01*
G01X323622Y120000D02*
G03X323245Y120078I-197J-1D01*
G01Y121259D02*
G03X323622Y121338I180J79D01*
G01X323245Y127559D02*
G03X323622Y127637I180J79D01*
G01Y126299D02*
G03X323245Y126378I-197J0D01*
G01Y124409D02*
G03X323622Y124488I180J79D01*
G01Y123149D02*
G03X323245Y123228I-197J0D01*
G01X320467Y115157D02*
G03X320271Y115354I-197J0D01*
G01Y116929D02*
G03X320467Y117126I-1J197D01*
G01X334785Y112698D02*
X334506Y112420D01*
G01X333445Y113779D02*
X333248Y113582D01*
G01X334785Y117698D02*
X334506Y117420D01*
G01X333387Y116871D02*
X333305Y116790D01*
G01X333445Y120078D02*
X333248Y119882D01*
G01X333387Y123170D02*
X333305Y123089D01*
G01X320588Y119939D02*
X320641Y120021D01*
G01X320551Y123031D02*
X320678Y123228D01*
G01X322806Y113484D02*
X322727Y113326D01*
G01X322045D02*
X322124Y113484D01*
G01X322806Y116633D02*
X322727Y116476D01*
G01X322045D02*
X322124Y116633D01*
G01X322806Y119783D02*
X322727Y119626D01*
G01X322045D02*
X322124Y119783D01*
G01X322806Y122933D02*
X322727Y122775D01*
G01X322045D02*
X322124Y122933D01*
G01X322806Y126082D02*
X322727Y125925D01*
G01X322045D02*
X322124Y126082D01*
G01X331299Y114291D02*
Y112992D01*
G01Y119094D02*
Y117992D01*
G01X333387Y126320D02*
X333305Y126239D01*
G01X320551Y126181D02*
X320678Y126378D01*
G01X325826Y126161D02*
Y126680D01*
G01Y124295D02*
Y124822D01*
G01Y123012D02*
Y123531D01*
G01Y121145D02*
Y121673D01*
G01Y119862D02*
Y120381D01*
G01Y116713D02*
Y117232D01*
G01Y114846D02*
Y115374D01*
G01Y113563D02*
Y114082D01*
G01Y118523D02*
Y117995D01*
G01Y127972D02*
Y127444D01*
G01X325590Y140295D02*
Y116988D01*
G01X325218Y113484D02*
Y112303D01*
G01Y116633D02*
Y115452D01*
G01Y119783D02*
Y118602D01*
G01Y122933D02*
Y121752D01*
G01Y126082D02*
Y124901D01*
G01Y129232D02*
Y128051D01*
G01X324366D02*
Y129232D01*
G01Y124901D02*
Y126082D01*
G01Y121752D02*
Y122933D01*
G01Y118602D02*
Y119783D01*
G01Y115452D02*
Y116633D01*
G01Y112303D02*
Y113484D01*
G01X323684D02*
Y112303D01*
G01Y116633D02*
Y115452D01*
G01Y119783D02*
Y118602D01*
G01Y122933D02*
Y121752D01*
G01Y126082D02*
Y124901D01*
G01Y129232D02*
Y128051D01*
G01X323622Y127637D02*
Y128166D01*
G01Y125780D02*
Y126299D01*
G01Y124488D02*
Y125016D01*
G01Y121338D02*
Y121867D01*
G01Y122630D02*
Y123149D01*
G01Y119480D02*
Y120000D01*
G01X322441Y121259D02*
Y120078D01*
G01Y124409D02*
Y123228D01*
G01Y127559D02*
Y126378D01*
G01X322062Y113326D02*
Y112460D01*
G01Y116476D02*
Y115610D01*
G01Y119626D02*
Y118759D01*
G01Y122775D02*
Y121909D01*
G01Y125925D02*
Y125059D01*
G01Y129074D02*
Y128208D01*
G01X321687Y121259D02*
Y120078D01*
G01Y124409D02*
Y123228D01*
G01Y127559D02*
Y126378D01*
G01X321380Y128208D02*
Y129074D01*
G01Y125059D02*
Y125925D01*
G01Y121909D02*
Y122775D01*
G01Y118759D02*
Y119626D01*
G01Y115610D02*
Y116476D01*
G01Y112460D02*
Y113326D01*
G01X321219Y121574D02*
Y119763D01*
G01Y124724D02*
Y122913D01*
G01Y127874D02*
Y126063D01*
G01X321083Y120078D02*
Y121259D01*
G01Y124409D02*
Y123228D01*
G01Y127559D02*
Y126378D01*
G01X320528Y113326D02*
Y112460D01*
G01Y116476D02*
Y115610D01*
G01Y119626D02*
Y118759D01*
G01Y122775D02*
Y121909D01*
G01Y125925D02*
Y125059D01*
G01Y129074D02*
Y128208D01*
G01X320467Y117126D02*
Y118110D01*
G01Y114173D02*
Y115157D01*
G01X330118D02*
X330413Y115328D01*
G01X330118Y118307D02*
X330413Y118477D01*
G01X330118Y121456D02*
X330413Y121627D01*
G01X330118Y124606D02*
X330413Y124776D01*
G01X330118Y127756D02*
X330413Y127926D01*
G01X322727Y128208D02*
X322806Y128051D01*
G01X322124D02*
X322045Y128208D01*
G01X322727Y125059D02*
X322806Y124901D01*
G01X322124D02*
X322045Y125059D01*
G01X322727Y121909D02*
X322806Y121752D01*
G01X322124D02*
X322045Y121909D01*
G01X322727Y118759D02*
X322806Y118602D01*
G01X322124D02*
X322045Y118759D01*
G01X322727Y115610D02*
X322806Y115452D01*
G01X322124D02*
X322045Y115610D01*
G01X322727Y112460D02*
X322806Y112303D01*
G01X322124D02*
X322045Y112460D01*
G01X320678Y127559D02*
X320551Y127756D01*
G01X320678Y124409D02*
X320551Y124606D01*
G01X320641Y121317D02*
X320588Y121399D01*
G01X334429Y127952D02*
X334626Y127756D01*
G01X334405Y124745D02*
X334486Y124664D01*
G01X334405Y121596D02*
X334486Y121514D01*
G01X334429Y118504D02*
X334626Y118307D01*
G01X334405Y115296D02*
X334486Y115215D01*
G01X334506Y114863D02*
X334785Y114585D01*
G01X330413Y126207D02*
X330118Y126378D01*
G01X330413Y123058D02*
X330118Y123228D01*
G01X330413Y119908D02*
X330118Y120078D01*
G01X330413Y116758D02*
X330118Y116929D01*
G01X330413Y113609D02*
X330118Y113779D01*
G01X331643Y117369D02*
X330118Y117778D01*
G01X331643Y112369D02*
X330118Y112778D01*
G01X323622Y128166D02*
X323819D01*
G01X322124Y128051D02*
X325449D01*
G01X334429Y127952D02*
X330511D01*
G01X330171Y127854D02*
X345078D01*
G01X347047Y127756D02*
X334626D01*
G01X325826Y127444D02*
X326023D01*
G01X325826Y126680D02*
X326023D01*
G01X333526Y126378D02*
X345078D01*
G01X330511Y126181D02*
X333166D01*
G01X322124Y126082D02*
X325449D01*
G01X345078D02*
X330171D01*
G01X323819Y125780D02*
X323622D01*
G01Y125016D02*
X323819D01*
G01X322124Y124901D02*
X325449D01*
G01X330511Y124803D02*
X334266D01*
G01X330171Y124704D02*
X345078D01*
G01Y124606D02*
X334626D01*
G01X326023Y124295D02*
X325826D01*
G01Y123531D02*
X326023D01*
G01X333526Y123228D02*
X345078D01*
G01X330511Y123031D02*
X333166D01*
G01X322124Y122933D02*
X325449D01*
G01X345078D02*
X330171D01*
G01X323819Y122630D02*
X323622D01*
G01X323819Y121867D02*
X323622D01*
G01X322124Y121752D02*
X325449D01*
G01X330511Y121653D02*
X334266D01*
G01X330171Y121555D02*
X347047D01*
G01X345078Y121456D02*
X334626D01*
G01X326023Y121145D02*
X325826D01*
G01X326023Y120381D02*
X325826D01*
G01X333445Y120078D02*
X347047D01*
G01X330511Y119882D02*
X333248D01*
G01X322124Y119783D02*
X325449D01*
G01X347047D02*
X330171D01*
G01X323819Y119480D02*
X323622D01*
G01X347834Y119094D02*
X330118D01*
G01X322124Y118602D02*
X325449D01*
G01X334429Y118504D02*
X330511D01*
G01X347047Y118307D02*
X334626D01*
G01X320467Y118110D02*
X323819D01*
G01X325826Y117995D02*
X326023D01*
G01X330118Y117992D02*
X331299D01*
G01X334924Y117756D02*
X344398D01*
G01X331694Y117362D02*
X334367D01*
G01X325826Y117232D02*
X326023D01*
G01Y116988D02*
X325590D01*
G01X333526Y116929D02*
X345078D01*
G01X330511Y116732D02*
X333166D01*
G01X322124Y116633D02*
X325449D01*
G01X322124Y115452D02*
X325449D01*
G01X330511Y115354D02*
X334266D01*
G01X345078Y115157D02*
X334626D01*
G01X334367Y114921D02*
X331694D01*
G01X326023Y114846D02*
X325826D01*
G01X344398Y114527D02*
X334924D01*
G01X330118Y114291D02*
X331299D01*
G01X320467Y114173D02*
X323819D01*
G01X326023Y114082D02*
X325826D01*
G01X333445Y113779D02*
X347047D01*
G01X330511Y113582D02*
X333248D01*
G01X322124Y113484D02*
X325449D01*
G01X320467Y113110D02*
X323819D01*
G01X331299Y112992D02*
X330118D01*
G01X334924Y112756D02*
X344398D01*
G01X331694Y112362D02*
X334367D01*
G01X322124Y112303D02*
X325449D01*
G01X330118Y114506D02*
X331643Y114914D01*
G01X320562Y129357D02*
X320588Y129388D01*
G01X320532Y129337D02*
X320562Y129357D01*
G01X320499Y129330D02*
X320532Y129337D01*
G01X320667Y130735D02*
X320641Y130766D01*
G01X320697Y130715D02*
X320667Y130735D01*
G01X320730Y130708D02*
X320697Y130715D01*
G01X320532Y130898D02*
X320499Y130905D01*
G01X320562Y130879D02*
X320532Y130898D01*
G01X320588Y130848D02*
X320562Y130879D01*
G01X330477Y140548D02*
X330511Y140551D01*
G01X330444Y140539D02*
X330477Y140548D01*
G01X330413Y140524D02*
X330444Y140539D01*
G01X330477Y134249D02*
X330511Y134252D01*
G01X330444Y134240D02*
X330477Y134249D01*
G01X330413Y134225D02*
X330444Y134240D01*
G01X330477Y131099D02*
X330511Y131102D01*
G01X330444Y131090D02*
X330477Y131099D01*
G01X330413Y131076D02*
X330444Y131090D01*
G01X320697Y129520D02*
X320730Y129527D01*
G01X320667Y129501D02*
X320697Y129520D01*
G01X320641Y129470D02*
X320667Y129501D01*
G01X330511Y143700D02*
G03X330413Y143674I0J-197D01*
G01Y145105D02*
G03X330511Y145078I100J170D01*
G01X331694Y144921D02*
G03X331643Y144914I1J-197D01*
G01X334506Y144863D02*
G03X334367Y144921I-139J-139D01*
G01X334785Y144585D02*
G03X334924Y144527I140J139D01*
G01X334486Y134113D02*
G03X334626Y134055I140J139D01*
G01X333526Y135826D02*
G03X333387Y135769I-1J-197D01*
G01X333166Y135630D02*
G03X333305Y135687I1J197D01*
G01X330413Y135656D02*
G03X330511Y135630I98J171D01*
G01X334405Y134194D02*
G03X334266Y134252I-140J-139D01*
G01X330511Y137401D02*
G03X330413Y137375I0J-197D01*
G01Y138806D02*
G03X330511Y138779I100J170D01*
G01X333166Y132480D02*
G03X333305Y132538I0J197D01*
G01X330413Y132506D02*
G03X330511Y132480I98J171D01*
G01X330413Y141955D02*
G03X330511Y141929I98J171D01*
G01X333166D02*
G03X333305Y141987I0J197D01*
G01X333526Y142126D02*
G03X333387Y142068I1J-197D01*
G01X334486Y140412D02*
G03X334626Y140354I140J139D01*
G01X334405Y140493D02*
G03X334266Y140551I-140J-139D01*
G01X331694Y139921D02*
G03X331643Y139914I1J-197D01*
G01X334506Y139863D02*
G03X334367Y139921I-139J-139D01*
G01X334785Y139585D02*
G03X334924Y139527I140J139D01*
G01Y142756D02*
G03X334785Y142698I1J-197D01*
G01X334367Y142362D02*
G03X334506Y142420I0J197D01*
G01X331643Y142369D02*
G03X331694Y142362I52J190D01*
G01X325826Y143720D02*
G03X325449Y143799I-197J0D01*
G01Y144980D02*
G03X325826Y145059I180J79D01*
G01X325449Y141830D02*
G03X325826Y141909I180J79D01*
G01Y140570D02*
G03X325449Y140649I-197J0D01*
G01Y135531D02*
G03X325826Y135610I180J79D01*
G01Y134271D02*
G03X325449Y134350I-197J0D01*
G01X325826Y137421D02*
G03X325449Y137500I-197J0D01*
G01Y138681D02*
G03X325826Y138759I180J79D01*
G01X330118Y134161D02*
G03X330171Y134153I56J189D01*
G01Y135531D02*
G03X330118Y135524I-1J-197D01*
G01Y137310D02*
G03X330171Y137303I52J190D01*
G01X334405Y131045D02*
G03X334266Y131102I-139J-140D01*
G01X334486Y130963D02*
G03X334626Y130905I140J139D01*
G01X333526Y132677D02*
G03X333387Y132619I1J-197D01*
G01X330413Y129357D02*
G03X330511Y129330I100J170D01*
G01X325449Y132382D02*
G03X325826Y132461I180J79D01*
G01Y131122D02*
G03X325449Y131200I-197J-1D01*
G01Y129232D02*
G03X325826Y129311I180J79D01*
G01X330171Y129232D02*
G03X330118Y129225I-1J-197D01*
G01Y131011D02*
G03X330171Y131004I52J190D01*
G01Y132382D02*
G03X330118Y132374I3J-197D01*
G01X323245Y137008D02*
G03X323622Y137086I180J79D01*
G01Y135748D02*
G03X323245Y135826I-197J-1D01*
G01Y133858D02*
G03X323622Y133937I180J79D01*
G01Y132598D02*
G03X323245Y132677I-197J0D01*
G01X320467Y145157D02*
G03X320271Y145354I-197J0D01*
G01X320467Y140157D02*
G03X320271Y140354I-197J0D01*
G01Y141929D02*
G03X320467Y142126I-1J197D01*
G01X323622Y129448D02*
G03X323245Y129527I-197J0D01*
G01Y130708D02*
G03X323622Y130787I180J79D01*
G01X322806Y129232D02*
X322727Y129074D01*
G01X322045D02*
X322124Y129232D01*
G01X322806Y132382D02*
X322727Y132224D01*
G01X322045D02*
X322124Y132382D01*
G01X331299Y142992D02*
Y144291D01*
G01Y138189D02*
Y139291D01*
G01X333445Y129527D02*
X333248Y129330D01*
G01X333387Y132619D02*
X333305Y132538D01*
G01X333387Y135769D02*
X333305Y135687D01*
G01X333445Y138976D02*
X333248Y138779D01*
G01X334785Y142698D02*
X334506Y142420D01*
G01X333387Y142068D02*
X333305Y141987D01*
G01X333445Y145275D02*
X333248Y145078D01*
G01X320588Y129388D02*
X320641Y129470D01*
G01X320551Y132480D02*
X320678Y132677D01*
G01X320551Y135630D02*
X320678Y135826D01*
G01X322806Y135531D02*
X322727Y135374D01*
G01X322045D02*
X322124Y135531D01*
G01X322806Y138681D02*
X322727Y138523D01*
G01X322045D02*
X322124Y138681D01*
G01X322806Y141830D02*
X322727Y141673D01*
G01X322045D02*
X322124Y141830D01*
G01X322806Y144980D02*
X322727Y144822D01*
G01X322045D02*
X322124Y144980D01*
G01X325826Y145059D02*
Y145578D01*
G01Y143192D02*
Y143720D01*
G01Y141909D02*
Y142428D01*
G01Y140043D02*
Y140570D01*
G01Y138759D02*
Y139279D01*
G01Y135610D02*
Y136129D01*
G01Y133743D02*
Y134271D01*
G01Y132461D02*
Y132980D01*
G01Y130594D02*
Y131122D01*
G01Y129311D02*
Y129830D01*
G01Y137421D02*
Y136893D01*
G01X325218Y132382D02*
Y131200D01*
G01Y135531D02*
Y134350D01*
G01Y138681D02*
Y137500D01*
G01Y141830D02*
Y140649D01*
G01Y144980D02*
Y143799D01*
G01X324366D02*
Y144980D01*
G01Y140649D02*
Y141830D01*
G01Y137500D02*
Y138681D01*
G01Y134350D02*
Y135531D01*
G01Y131200D02*
Y132382D01*
G01X323684D02*
Y131200D01*
G01Y135531D02*
Y134350D01*
G01Y138681D02*
Y137500D01*
G01Y141830D02*
Y140649D01*
G01Y144980D02*
Y143799D01*
G01X323622Y137086D02*
Y137615D01*
G01Y135228D02*
Y135748D01*
G01Y133937D02*
Y134465D01*
G01Y132079D02*
Y132598D01*
G01Y130787D02*
Y131315D01*
G01Y128929D02*
Y129448D01*
G01X322441Y130708D02*
Y129527D01*
G01Y133858D02*
Y132677D01*
G01Y137008D02*
Y135826D01*
G01X322062Y132224D02*
Y131358D01*
G01Y135374D02*
Y134508D01*
G01Y138523D02*
Y137657D01*
G01Y141673D02*
Y140807D01*
G01Y144822D02*
Y143956D01*
G01X321687Y130708D02*
Y129527D01*
G01Y133858D02*
Y132677D01*
G01Y137008D02*
Y135826D01*
G01X321380Y143956D02*
Y144822D01*
G01Y140807D02*
Y141673D01*
G01Y137657D02*
Y138523D01*
G01Y134508D02*
Y135374D01*
G01Y131358D02*
Y132224D01*
G01X321219Y131023D02*
Y129212D01*
G01Y134173D02*
Y132362D01*
G01Y137322D02*
Y135511D01*
G01X321083Y129527D02*
Y130708D01*
G01Y133858D02*
Y132677D01*
G01Y137008D02*
Y135826D01*
G01X320528Y132224D02*
Y131358D01*
G01Y135374D02*
Y134508D01*
G01Y138523D02*
Y137657D01*
G01Y141673D02*
Y140807D01*
G01Y144822D02*
Y143956D01*
G01X320467Y144173D02*
Y145157D01*
G01Y142126D02*
Y143110D01*
G01Y140157D02*
Y139173D01*
G01X330118Y130905D02*
X330413Y131076D01*
G01X322727Y143956D02*
X322806Y143799D01*
G01X322124D02*
X322045Y143956D01*
G01X322727Y140807D02*
X322806Y140649D01*
G01X322124D02*
X322045Y140807D01*
G01X322727Y137657D02*
X322806Y137500D01*
G01X322124D02*
X322045Y137657D01*
G01X322727Y134508D02*
X322806Y134350D01*
G01X322124D02*
X322045Y134508D01*
G01X322727Y131358D02*
X322806Y131200D01*
G01X322124D02*
X322045Y131358D01*
G01X330118Y134055D02*
X330413Y134225D01*
G01X330118Y137204D02*
X330413Y137375D01*
G01X330118Y140354D02*
X330413Y140524D01*
G01X330118Y143504D02*
X330413Y143674D01*
G01X320678Y137008D02*
X320551Y137204D01*
G01X320678Y133858D02*
X320551Y134055D01*
G01X320641Y130766D02*
X320588Y130848D01*
G01X334506Y144863D02*
X334785Y144585D01*
G01X334429Y143700D02*
X334626Y143504D01*
G01X334405Y140493D02*
X334486Y140412D01*
G01X334506Y139863D02*
X334785Y139585D01*
G01X334429Y137401D02*
X334626Y137204D01*
G01X334405Y134194D02*
X334486Y134113D01*
G01X334405Y131045D02*
X334486Y130963D01*
G01X330413Y145105D02*
X330118Y145275D01*
G01X330413Y141955D02*
X330118Y142126D01*
G01X330413Y138806D02*
X330118Y138976D01*
G01X330413Y135656D02*
X330118Y135826D01*
G01X330413Y132506D02*
X330118Y132677D01*
G01X330413Y129357D02*
X330118Y129527D01*
G01X331643Y142369D02*
X330118Y142778D01*
G01X330511Y145078D02*
X333248D01*
G01X322124Y144980D02*
X325449D01*
G01X334367Y144921D02*
X331694D01*
G01X344398Y144527D02*
X334924D01*
G01X331299Y144291D02*
X330118D01*
G01X323819Y144173D02*
X320467D01*
G01X322124Y143799D02*
X325449D01*
G01X334429Y143700D02*
X330511D01*
G01X347047Y143504D02*
X334626D01*
G01X326023Y143192D02*
X325826D01*
G01X320467Y143110D02*
X323819D01*
G01X331299Y142992D02*
X330118D01*
G01X334924Y142756D02*
X344493D01*
G01X325826Y142428D02*
X326023D01*
G01X331694Y142362D02*
X334367D01*
G01X333526Y142126D02*
X345078D01*
G01X330511Y141929D02*
X333166D01*
G01X322124Y141830D02*
X325449D01*
G01X322124Y140649D02*
X325449D01*
G01X330511Y140551D02*
X334266D01*
G01X345078Y140354D02*
X334626D01*
G01X326023Y140295D02*
X325590D01*
G01X326023Y140043D02*
X325826D01*
G01X334367Y139921D02*
X331694D01*
G01X344493Y139527D02*
X334924D01*
G01X330118Y139291D02*
X331299D01*
G01X326023Y139279D02*
X325826D01*
G01X323819Y139173D02*
X320467D01*
G01X333445Y138976D02*
X347047D01*
G01X330511Y138779D02*
X333248D01*
G01X322124Y138681D02*
X325449D01*
G01X330118Y138189D02*
X347834D01*
G01X323622Y137615D02*
X323819D01*
G01X322124Y137500D02*
X325449D01*
G01X334429Y137401D02*
X330511D01*
G01X330171Y137303D02*
X345078D01*
G01X347047Y137204D02*
X334626D01*
G01X325826Y136893D02*
X326023D01*
G01X325826Y136129D02*
X326023D01*
G01X333526Y135826D02*
X345078D01*
G01X330511Y135630D02*
X333166D01*
G01X322124Y135531D02*
X325449D01*
G01X345078D02*
X330171D01*
G01X323819Y135228D02*
X323622D01*
G01Y134465D02*
X323819D01*
G01X322124Y134350D02*
X325449D01*
G01X330511Y134252D02*
X334266D01*
G01X330171Y134153D02*
X345078D01*
G01Y134055D02*
X334626D01*
G01X326023Y133743D02*
X325826D01*
G01Y132980D02*
X326023D01*
G01X333526Y132677D02*
X345078D01*
G01X330511Y132480D02*
X333166D01*
G01X322124Y132382D02*
X325449D01*
G01X345078D02*
X330171D01*
G01X323819Y132079D02*
X323622D01*
G01X323819Y131315D02*
X323622D01*
G01X322124Y131200D02*
X325449D01*
G01X330511Y131102D02*
X334266D01*
G01X330171Y131004D02*
X347047D01*
G01X345078Y130905D02*
X334626D01*
G01X326023Y130594D02*
X325826D01*
G01X326023Y129830D02*
X325826D01*
G01X333445Y129527D02*
X347047D01*
G01X330511Y129330D02*
X333248D01*
G01X322124Y129232D02*
X325449D01*
G01X347047D02*
X330171D01*
G01X323819Y128929D02*
X323622D01*
G01X330118Y144506D02*
X331643Y144914D01*
G01X330118Y139506D02*
X331643Y139914D01*
G01X330477Y159446D02*
X330511Y159448D01*
G01X330444Y159437D02*
X330477Y159446D01*
G01X330413Y159422D02*
X330444Y159437D01*
G01X330477Y156296D02*
X330511Y156299D01*
G01X330444Y156287D02*
X330477Y156296D01*
G01X330413Y156272D02*
X330444Y156287D01*
G01X330477Y149997D02*
X330511Y150000D01*
G01X330444Y149988D02*
X330477Y149997D01*
G01X330413Y149973D02*
X330444Y149988D01*
G01X330477Y146847D02*
X330511Y146850D01*
G01X330444Y146838D02*
X330477Y146847D01*
G01X330413Y146824D02*
X330444Y146838D01*
G01X330511Y153149D02*
G03X330413Y153123I0J-197D01*
G01Y154554D02*
G03X330511Y154527I100J170D01*
G01X330413Y157703D02*
G03X330511Y157677I98J171D01*
G01X333166D02*
G03X333305Y157735I0J197D01*
G01X333526Y157874D02*
G03X333387Y157816I1J-197D01*
G01X334486Y156160D02*
G03X334626Y156102I140J139D01*
G01X334405Y156241D02*
G03X334266Y156299I-140J-139D01*
G01X330413Y160853D02*
G03X330511Y160826I100J170D01*
G01X333166D02*
G03X333305Y160884I-1J197D01*
G01X333526Y161023D02*
G03X333387Y160966I0J-197D01*
G01X334486Y159309D02*
G03X334626Y159252I139J140D01*
G01X334405Y159391D02*
G03X334266Y159448I-138J-140D01*
G01X331694Y154921D02*
G03X331643Y154914I1J-197D01*
G01X334506Y154863D02*
G03X334367Y154921I-139J-139D01*
G01X334785Y154585D02*
G03X334924Y154527I140J139D01*
G01Y157756D02*
G03X334785Y157698I1J-197D01*
G01X334367Y157362D02*
G03X334506Y157420I0J197D01*
G01X331643Y157369D02*
G03X331694Y157362I52J190D01*
G01Y159921D02*
G03X331643Y159914I1J-197D01*
G01X334506Y159863D02*
G03X334367Y159921I-139J-139D01*
G01X334785Y159585D02*
G03X334924Y159527I140J139D01*
G01X325449Y157578D02*
G03X325826Y157658I180J79D01*
G01Y156319D02*
G03X325449Y156397I-197J-1D01*
G01Y160728D02*
G03X325826Y160807I180J79D01*
G01Y159468D02*
G03X325449Y159547I-197J0D01*
G01X325826Y153169D02*
G03X325449Y153248I-197J0D01*
G01Y154429D02*
G03X325826Y154508I180J79D01*
G01X330413Y148254D02*
G03X330511Y148228I98J171D01*
G01X333166D02*
G03X333305Y148286I0J197D01*
G01X333526Y148425D02*
G03X333387Y148367I1J-197D01*
G01X334486Y146711D02*
G03X334626Y146653I140J139D01*
G01X334405Y146793D02*
G03X334266Y146850I-139J-140D01*
G01X330413Y151404D02*
G03X330511Y151378I98J171D01*
G01X333166D02*
G03X333305Y151435I1J197D01*
G01X333526Y151574D02*
G03X333387Y151517I-1J-197D01*
G01X334486Y149861D02*
G03X334626Y149803I140J139D01*
G01X334405Y149942D02*
G03X334266Y150000I-140J-139D01*
G01X334924Y147756D02*
G03X334785Y147698I1J-197D01*
G01X334367Y147362D02*
G03X334506Y147420I0J197D01*
G01X331643Y147369D02*
G03X331694Y147362I52J190D01*
G01Y149921D02*
G03X331643Y149914I1J-197D01*
G01X334506Y149863D02*
G03X334367Y149921I-139J-139D01*
G01X334785Y149585D02*
G03X334924Y149527I140J139D01*
G01Y152756D02*
G03X334785Y152698I1J-197D01*
G01X334367Y152362D02*
G03X334506Y152420I0J197D01*
G01X331643Y152369D02*
G03X331694Y152362I52J190D01*
G01X325449Y148130D02*
G03X325826Y148209I180J79D01*
G01Y146870D02*
G03X325449Y146948I-197J-1D01*
G01Y151279D02*
G03X325826Y151358I180J79D01*
G01Y150019D02*
G03X325449Y150098I-197J0D01*
G01X320467Y150157D02*
G03X320271Y150354I-197J0D01*
G01Y151929D02*
G03X320467Y152126I-1J197D01*
G01X320271Y146929D02*
G03X320467Y147126I-1J197D01*
G01Y160157D02*
G03X320271Y160354I-197J0D01*
G01X320467Y155157D02*
G03X320271Y155354I-197J0D01*
G01Y156929D02*
G03X320467Y157126I-1J197D01*
G01X331299Y147992D02*
Y149291D01*
G01Y154291D02*
Y152992D01*
G01Y159291D02*
Y157992D01*
G01X334785Y147698D02*
X334506Y147420D01*
G01X322806Y148130D02*
X322727Y147972D01*
G01X322045D02*
X322124Y148130D01*
G01X322806Y151279D02*
X322727Y151122D01*
G01X322045D02*
X322124Y151279D01*
G01X322806Y154429D02*
X322727Y154271D01*
G01X322045D02*
X322124Y154429D01*
G01X322806Y157578D02*
X322727Y157421D01*
G01X322045D02*
X322124Y157578D01*
G01X322806Y160728D02*
X322727Y160570D01*
G01X322045D02*
X322124Y160728D01*
G01X325826Y160807D02*
Y161326D01*
G01Y158940D02*
Y159468D01*
G01Y157658D02*
Y158176D01*
G01Y155791D02*
Y156319D01*
G01Y154508D02*
Y155027D01*
G01Y151358D02*
Y151877D01*
G01Y149491D02*
Y150019D01*
G01Y148209D02*
Y148728D01*
G01Y146342D02*
Y146870D01*
G01Y153169D02*
Y152641D01*
G01X325218Y148130D02*
Y146948D01*
G01Y151279D02*
Y150098D01*
G01Y154429D02*
Y153248D01*
G01Y157578D02*
Y156397D01*
G01Y160728D02*
Y159547D01*
G01X324366D02*
Y160728D01*
G01Y156397D02*
Y157578D01*
G01Y153248D02*
Y154429D01*
G01Y150098D02*
Y151279D01*
G01Y146948D02*
Y148130D01*
G01X323684D02*
Y146948D01*
G01Y151279D02*
Y150098D01*
G01Y154429D02*
Y153248D01*
G01Y157578D02*
Y156397D01*
G01Y160728D02*
Y159547D01*
G01X322062Y147972D02*
Y147106D01*
G01Y151122D02*
Y150256D01*
G01Y154271D02*
Y153405D01*
G01Y157421D02*
Y156555D01*
G01Y160570D02*
Y159704D01*
G01X321380D02*
Y160570D01*
G01Y156555D02*
Y157421D01*
G01Y153405D02*
Y154271D01*
G01Y150256D02*
Y151122D01*
G01Y147106D02*
Y147972D01*
G01X320528D02*
Y147106D01*
G01Y151122D02*
Y150256D01*
G01Y154271D02*
Y153405D01*
G01Y157421D02*
Y156555D01*
G01Y160570D02*
Y159704D01*
G01X320467Y159173D02*
Y160157D01*
G01Y154173D02*
Y155157D01*
G01Y152126D02*
Y153110D01*
G01Y149173D02*
Y150157D01*
G01Y147126D02*
Y148110D01*
G01Y158110D02*
Y157126D01*
G01X322727Y159704D02*
X322806Y159547D01*
G01X322124D02*
X322045Y159704D01*
G01X322727Y156555D02*
X322806Y156397D01*
G01X322124D02*
X322045Y156555D01*
G01X333387Y148367D02*
X333305Y148286D01*
G01X334785Y152698D02*
X334506Y152420D01*
G01X333387Y151517D02*
X333305Y151435D01*
G01X333445Y154724D02*
X333248Y154527D01*
G01X334785Y157698D02*
X334506Y157420D01*
G01X333387Y157816D02*
X333305Y157735D01*
G01X333387Y160966D02*
X333305Y160884D01*
G01X322727Y153405D02*
X322806Y153248D01*
G01X322124D02*
X322045Y153405D01*
G01X322727Y150256D02*
X322806Y150098D01*
G01X322124D02*
X322045Y150256D01*
G01X322727Y147106D02*
X322806Y146948D01*
G01X322124D02*
X322045Y147106D01*
G01X330118Y146653D02*
X330413Y146824D01*
G01X330118Y149803D02*
X330413Y149973D01*
G01X334506Y159863D02*
X334785Y159585D01*
G01X334405Y159391D02*
X334486Y159309D01*
G01X334405Y156241D02*
X334486Y156160D01*
G01X334506Y154863D02*
X334785Y154585D01*
G01X334429Y153149D02*
X334626Y152952D01*
G01X334506Y149863D02*
X334785Y149585D01*
G01X334405Y149942D02*
X334486Y149861D01*
G01X334405Y146793D02*
X334486Y146711D01*
G01X330118Y152952D02*
X330413Y153123D01*
G01X330118Y156102D02*
X330413Y156272D01*
G01X330118Y159252D02*
X330413Y159422D01*
G01Y160853D02*
X330118Y161023D01*
G01X330413Y157703D02*
X330118Y157874D01*
G01X330413Y154554D02*
X330118Y154724D01*
G01X330413Y151404D02*
X330118Y151574D01*
G01X330413Y148254D02*
X330118Y148425D01*
G01X331643Y157369D02*
X330118Y157778D01*
G01X331643Y152369D02*
X330118Y152778D01*
G01X331643Y147369D02*
X330118Y147778D01*
G01X325826Y161326D02*
X326023D01*
G01X333526Y161023D02*
X345078D01*
G01X330511Y160826D02*
X333166D01*
G01X322124Y160728D02*
X325449D01*
G01X334367Y159921D02*
X331694D01*
G01X322124Y159547D02*
X325449D01*
G01X344398Y159527D02*
X334924D01*
G01X330511Y159448D02*
X334266D01*
G01X330118Y159291D02*
X331299D01*
G01X345078Y159252D02*
X334626D01*
G01X323819Y159173D02*
X320467D01*
G01X326023Y158940D02*
X325826D01*
G01Y158176D02*
X326023D01*
G01X320467Y158110D02*
X323819D01*
G01X331299Y157992D02*
X330118D01*
G01X333526Y157874D02*
X345078D01*
G01X334924Y157756D02*
X344493D01*
G01X330511Y157677D02*
X333166D01*
G01X322124Y157578D02*
X325449D01*
G01X331694Y157362D02*
X334367D01*
G01X322124Y156397D02*
X325449D01*
G01X330511Y156299D02*
X334266D01*
G01X345078Y156102D02*
X334626D01*
G01X326023Y155791D02*
X325826D01*
G01X326023Y155027D02*
X325826D01*
G01X334367Y154921D02*
X331694D01*
G01X333445Y154724D02*
X347047D01*
G01X330511Y154527D02*
X333248D01*
G01X344493D02*
X334924D01*
G01X322124Y154429D02*
X325449D01*
G01X331299Y154291D02*
X330118D01*
G01X323819Y154173D02*
X320467D01*
G01X322124Y153248D02*
X325449D01*
G01X334429Y153149D02*
X330511D01*
G01X320467Y153110D02*
X323819D01*
G01X331299Y152992D02*
X330118D01*
G01X347047Y152952D02*
X334626D01*
G01X334924Y152756D02*
X344398D01*
G01X325826Y152641D02*
X326023D01*
G01X331694Y152362D02*
X334367D01*
G01X325826Y151877D02*
X326023D01*
G01X333526Y151574D02*
X345078D01*
G01X330511Y151378D02*
X333166D01*
G01X322124Y151279D02*
X325449D01*
G01X322124Y150098D02*
X325449D01*
G01X330511Y150000D02*
X334266D01*
G01X334367Y149921D02*
X331694D01*
G01X345078Y149803D02*
X334626D01*
G01X344398Y149527D02*
X334924D01*
G01X326023Y149491D02*
X325826D01*
G01X331299Y149291D02*
X330118D01*
G01X320467Y149173D02*
X323819D01*
G01X325826Y148728D02*
X326023D01*
G01X333526Y148425D02*
X345078D01*
G01X330511Y148228D02*
X333166D01*
G01X322124Y148130D02*
X325449D01*
G01X320467Y148110D02*
X323819D01*
G01X330118Y147992D02*
X331299D01*
G01X334924Y147756D02*
X344398D01*
G01X331694Y147362D02*
X334367D01*
G01X322124Y146948D02*
X325449D01*
G01X330511Y146850D02*
X334266D01*
G01X345078Y146653D02*
X334626D01*
G01X326023Y146342D02*
X325826D01*
G01X326023Y145578D02*
X325826D01*
G01X333445Y145275D02*
X347047D01*
G01X330118Y159506D02*
X331643Y159914D01*
G01X330118Y154506D02*
X331643Y154914D01*
G01X330118Y149506D02*
X331643Y149914D01*
G01X326181Y173287D02*
X321063D01*
G01X328150Y171319D02*
G03X326181Y173287I-1969J-1D01*
G01X330477Y168895D02*
X330511Y168897D01*
G01X330444Y168885D02*
X330477Y168895D01*
G01X330413Y168871D02*
X330444Y168885D01*
G01X330477Y165745D02*
X330511Y165748D01*
G01X330444Y165736D02*
X330477Y165745D01*
G01X330413Y165721D02*
X330444Y165736D01*
G01X330413Y164002D02*
G03X330511Y163976I98J171D01*
G01X330413Y167152D02*
G03X330511Y167126I98J171D01*
G01X333166D02*
G03X333305Y167183I0J197D01*
G01X333526Y167322D02*
G03X333387Y167265I-1J-197D01*
G01X334486Y165609D02*
G03X334626Y165551I140J139D01*
G01X334405Y165690D02*
G03X334266Y165748I-140J-139D01*
G01X330413Y170302D02*
G03X330511Y170275I100J170D01*
G01X333166D02*
G03X333305Y170333I-1J197D01*
G01X333526Y170472D02*
G03X333387Y170415I0J-197D01*
G01X334486Y168758D02*
G03X334626Y168700I140J139D01*
G01X334405Y168840D02*
G03X334266Y168897I-139J-140D01*
G01X331694Y164921D02*
G03X331643Y164914I1J-197D01*
G01X334506Y164863D02*
G03X334367Y164921I-139J-139D01*
G01X334785Y164585D02*
G03X334924Y164527I140J139D01*
G01Y167756D02*
G03X334785Y167698I1J-197D01*
G01X334367Y167362D02*
G03X334506Y167420I0J197D01*
G01X331643Y167369D02*
G03X331694Y167362I52J190D01*
G01Y169921D02*
G03X331643Y169914I1J-197D01*
G01X334506Y169863D02*
G03X334367Y169921I-139J-139D01*
G01X334785Y169585D02*
G03X334924Y169527I140J139D01*
G01Y172756D02*
G03X334785Y172698I1J-197D01*
G01X334367Y172362D02*
G03X334506Y172420I0J197D01*
G01X331643Y172369D02*
G03X331694Y172362I52J190D01*
G01X330511Y162598D02*
G03X330413Y162572I0J-197D01*
G01X334924Y162756D02*
G03X334785Y162698I1J-197D01*
G01X334367Y162362D02*
G03X334506Y162420I0J197D01*
G01X331643Y162369D02*
G03X331694Y162362I52J190D01*
G01X325449Y170177D02*
G03X325826Y170256I180J79D01*
G01Y168917D02*
G03X325449Y168996I-197J0D01*
G01Y167027D02*
G03X325826Y167106I180J79D01*
G01Y165767D02*
G03X325449Y165846I-197J0D01*
G01Y163878D02*
G03X325826Y163956I180J79D01*
G01X328149Y171319D02*
G03X326181Y173287I-1968J0D01*
G01X328149Y171319D02*
G03X326181Y173287I-1968J0D01*
G01X325826Y162618D02*
G03X325449Y162696I-197J-1D01*
G01X320271Y161929D02*
G03X320467Y162126I-1J197D01*
G01Y165157D02*
G03X320271Y165354I-197J0D01*
G01Y166929D02*
G03X320467Y167126I-1J197D01*
G01Y170157D02*
G03X320271Y170354I-197J0D01*
G01Y171929D02*
G03X320467Y172126I-1J197D01*
G01X328149Y171319D02*
G03X326181Y173287I-1968J0D01*
G01X328149Y171319D02*
G03X326181Y173287I-1968J0D01*
G01X331299Y162992D02*
Y164291D01*
G01Y169291D02*
Y167992D01*
G01Y174448D02*
Y172992D01*
G01X322806Y163878D02*
X322727Y163720D01*
G01X322045D02*
X322124Y163878D01*
G01X322806Y167027D02*
X322727Y166870D01*
G01X322045D02*
X322124Y167027D01*
G01X322806Y170177D02*
X322727Y170019D01*
G01X322045D02*
X322124Y170177D01*
G01X326023Y173287D02*
Y174448D01*
G01X325826Y170256D02*
Y170775D01*
G01Y168389D02*
Y168917D01*
G01Y167106D02*
Y167625D01*
G01Y165239D02*
Y165767D01*
G01Y163956D02*
Y164476D01*
G01Y162090D02*
Y162618D01*
G01X325218Y163878D02*
Y162696D01*
G01Y167027D02*
Y165846D01*
G01Y170177D02*
Y168996D01*
G01X324366D02*
Y170177D01*
G01Y165846D02*
Y167027D01*
G01Y162696D02*
Y163878D01*
G01X323819Y174448D02*
Y173287D01*
G01X323684Y163878D02*
Y162696D01*
G01Y167027D02*
Y165846D01*
G01Y170177D02*
Y168996D01*
G01X322637Y178224D02*
Y189606D01*
G01X322062Y163720D02*
Y162854D01*
G01Y166870D02*
Y166004D01*
G01Y170019D02*
Y169153D01*
G01X321380D02*
Y170019D01*
G01Y166004D02*
Y166870D01*
G01Y162854D02*
Y163720D01*
G01X320528D02*
Y162854D01*
G01Y166870D02*
Y166004D01*
G01Y170019D02*
Y169153D01*
G01X320467Y169173D02*
Y170157D01*
G01Y167126D02*
Y168110D01*
G01Y164173D02*
Y165157D01*
G01Y162126D02*
Y163110D01*
G01Y173110D02*
Y172126D01*
G01X320275Y190000D02*
Y177204D01*
G01X322727Y169153D02*
X322806Y168996D01*
G01X322124D02*
X322045Y169153D01*
G01X322727Y166004D02*
X322806Y165846D01*
G01X322124D02*
X322045Y166004D01*
G01X322727Y162854D02*
X322806Y162696D01*
G01X322124D02*
X322045Y162854D01*
G01X334785Y162698D02*
X334506Y162420D01*
G01X333445Y164173D02*
X333248Y163976D01*
G01X334785Y167698D02*
X334506Y167420D01*
G01X333387Y167265D02*
X333305Y167183D01*
G01X333387Y170415D02*
X333305Y170333D01*
G01X334506Y169863D02*
X334785Y169585D01*
G01X334405Y168840D02*
X334486Y168758D01*
G01X334785Y172698D02*
X334506Y172420D01*
G01X334405Y165690D02*
X334486Y165609D01*
G01X334506Y164863D02*
X334785Y164585D01*
G01X320275Y177204D02*
X323031Y174448D01*
G01X334429Y162598D02*
X334626Y162401D01*
G01X330118D02*
X330413Y162572D01*
G01X330118Y165551D02*
X330413Y165721D01*
G01X330118Y168700D02*
X330413Y168871D01*
G01Y170302D02*
X330118Y170472D01*
G01X330413Y167152D02*
X330118Y167322D01*
G01X330413Y164002D02*
X330118Y164173D01*
G01Y174736D02*
X322637Y178224D01*
G01X331643Y172369D02*
X330118Y172778D01*
G01X331643Y167369D02*
X330118Y167778D01*
G01X331643Y162369D02*
X330118Y162778D01*
G01X321063Y173287D02*
X326181D01*
G01X321063D02*
X326181D01*
G01X320467Y173110D02*
X323819D01*
G01X331299Y172992D02*
X330118D01*
G01X334924Y172756D02*
X344493D01*
G01X331694Y172362D02*
X334367D01*
G01X325826Y170775D02*
X326023D01*
G01X345078Y170472D02*
X333526D01*
G01X333166Y170275D02*
X330511D01*
G01X322124Y170177D02*
X325449D01*
G01X334367Y169921D02*
X331694D01*
G01X344493Y169527D02*
X334924D01*
G01X330118Y169291D02*
X331299D01*
G01X323819Y169173D02*
X320467D01*
G01X322124Y168996D02*
X325449D01*
G01X334266Y168897D02*
X330511D01*
G01X345078Y168700D02*
X334626D01*
G01X326023Y168389D02*
X325826D01*
G01X320467Y168110D02*
X323819D01*
G01X330118Y167992D02*
X331299D01*
G01X334924Y167756D02*
X344398D01*
G01X325826Y167625D02*
X326023D01*
G01X331694Y167362D02*
X334367D01*
G01X333526Y167322D02*
X345078D01*
G01X330511Y167126D02*
X333166D01*
G01X322124Y167027D02*
X325449D01*
G01X322124Y165846D02*
X325449D01*
G01X330511Y165748D02*
X334266D01*
G01X345078Y165551D02*
X334626D01*
G01X326023Y165239D02*
X325826D01*
G01X334367Y164921D02*
X331694D01*
G01X344398Y164527D02*
X334924D01*
G01X326023Y164476D02*
X325826D01*
G01X330118Y164291D02*
X331299D01*
G01X333445Y164173D02*
X347047D01*
G01X320467D02*
X323819D01*
G01X330511Y163976D02*
X333248D01*
G01X322124Y163878D02*
X325449D01*
G01X320467Y163110D02*
X323819D01*
G01X330118Y162992D02*
X331299D01*
G01X334924Y162756D02*
X344398D01*
G01X322124Y162696D02*
X325449D01*
G01X334429Y162598D02*
X330511D01*
G01X347047Y162401D02*
X334626D01*
G01X331694Y162362D02*
X334367D01*
G01X326023Y162090D02*
X325826D01*
G01X330118Y169506D02*
X331643Y169914D01*
G01X330118Y164506D02*
X331643Y164914D01*
G01X321063Y173287D02*
X326181D01*
G01X321063D02*
X326181D01*
G01X321063Y193957D02*
X347441D01*
G01X325393Y193956D02*
Y192756D01*
G01Y203582D02*
Y193956D01*
G01X330118Y179882D02*
X332086Y181850D01*
G01X323031Y192756D02*
X320275Y190000D01*
G01X347441Y193956D02*
X321063D01*
G01X347441D02*
X321063D01*
G01X347363Y189606D02*
X322637D01*
G01X349409Y188425D02*
X322637D01*
G01X349409Y185669D02*
X322637D01*
G01X349409Y184488D02*
X322637D01*
G01X332086Y181850D02*
X347362D01*
G01X347441Y193956D02*
X321063D01*
G01X347441D02*
X321063D01*
G01X330503Y199294D02*
X330512Y199313D01*
G01X330404Y199263D02*
X330503Y199294D01*
G01X330200Y199253D02*
X330404Y199263D01*
G01X330220Y198072D02*
X330122Y198071D01*
G01X330312Y198077D02*
X330220Y198072D01*
G01X330394Y198086D02*
X330312Y198077D01*
G01X330458Y198104D02*
X330394Y198086D01*
G01X330499Y198133D02*
X330458Y198104D01*
G01X330511Y198169D02*
X330499Y198133D01*
G01X330124Y200023D02*
X329940Y200542D01*
G01X330308Y199612D02*
X330124Y200023D01*
G01X330493Y199347D02*
X330308Y199612D01*
G01X330511Y198174D02*
Y198169D01*
G01X330493Y198223D02*
X330511Y198174D01*
G01X329929Y200198D02*
X329940Y200136D01*
G01X329923Y200260D02*
X329929Y200198D01*
G01X329921Y200323D02*
X329923Y200260D01*
G01Y200619D02*
X329921Y200659D01*
G01X329929Y200580D02*
X329923Y200619D01*
G01X329940Y200542D02*
X329929Y200580D01*
G01X330308Y198647D02*
X330493Y198223D01*
G01X330124Y199305D02*
X330308Y198647D01*
G01X329940Y200136D02*
X330124Y199305D01*
G01X331102Y208267D02*
G03X329921Y207086I0J-1181D01*
G01X336141Y198070D02*
Y199252D01*
G01X332362Y198070D02*
Y199252D01*
G01X331574D02*
Y198070D01*
G01X331181Y199252D02*
Y198070D01*
G01X330511Y198169D02*
Y199313D01*
G01X330493Y199347D02*
Y198223D01*
G01X329940Y200136D02*
Y200543D01*
G01X329921Y200323D02*
Y207086D01*
G01Y198070D02*
Y199252D01*
G01X329330Y199291D02*
Y203582D01*
G01X329133Y199252D02*
Y198070D01*
G01X329056D02*
Y199252D01*
G01X330512Y199313D02*
X330493Y199347D01*
G01X328053Y199252D02*
Y198070D01*
G01X327806D02*
Y199252D01*
G01X327721D02*
Y198070D01*
G01X327401Y197637D02*
Y199685D01*
G01X327244Y199252D02*
Y198070D01*
G01X327008Y197637D02*
Y199685D01*
G01X325945Y199252D02*
Y198070D01*
G01X325354Y199252D02*
Y198070D01*
G01X327401Y199291D02*
X327008Y199685D01*
G01X327401Y198031D02*
X327008Y197637D01*
G01X331102Y208267D02*
X337401D01*
G01X338582Y201220D02*
X329921D01*
G01X327008Y199685D02*
X327401D01*
G01X339173D02*
X329330D01*
G01X325354Y199252D02*
X343149D01*
G01X325354Y198070D02*
X343149D01*
G01X327401Y197637D02*
X327008D01*
G01X341535Y-105354D02*
G03X349409Y-97480I0J7874D01*
G01X341535Y-105354D02*
G03X349409Y-97480I0J7874D01*
G01X341535Y-105354D02*
G03X349409Y-97480I0J7874D01*
G01X341535Y-105354D02*
G03X349409Y-97480I0J7874D01*
G01X341535Y-105354D02*
G03X349409Y-97480I0J7874D01*
G01D02*
Y-15748D01*
G01Y-97480D02*
Y-15748D01*
G01Y-97480D02*
Y-15748D01*
G01Y-97480D02*
Y-15748D01*
G01Y-97480D02*
Y-15748D01*
G01X353346Y-47481D02*
G03X349409Y-51418I0J-3937D01*
G01Y-20709D02*
G03X353346Y-24646I3937J0D01*
G01X349409Y-15748D02*
G03X341535Y-7874I-7874J0D01*
G01X349409Y-15748D02*
G03X341535Y-7874I-7874J0D01*
G01X349409Y-15748D02*
G03X341535Y-7874I-7874J0D01*
G01X349409Y-15748D02*
G03X341535Y-7874I-7874J0D01*
G01X349409Y-15748D02*
G03X341535Y-7874I-7874J0D01*
G01X349409Y1969D02*
Y21398D01*
G01X347441Y0D02*
G03X349409Y1969I0J1968D01*
G01X337401Y9015D02*
G03X338582Y10196I0J1181D01*
G01X347441Y0D02*
G03X349409Y1968I0J1968D01*
G01X347441Y0D02*
G03X349409Y1968I0J1968D01*
G01X347441Y0D02*
G03X349409Y1968I0J1968D01*
G01X347441Y0D02*
G03X349409Y1968I0J1968D01*
G01D02*
Y21397D01*
G01Y1968D02*
Y21397D01*
G01X338582Y16960D02*
Y10196D01*
G01X349409Y1968D02*
Y21397D01*
G01Y1968D02*
Y21397D01*
G01X349408Y21398D02*
G03X347441Y23366I-1968J0D01*
G01X338000Y17989D02*
X337991Y17970D01*
G01X338100Y18020D02*
X338000Y17989D01*
G01X338304Y18030D02*
X338100Y18020D01*
G01X338379Y17260D02*
X338564Y16741D01*
G01X338195Y17671D02*
X338379Y17260D01*
G01X338011Y17936D02*
X338195Y17671D01*
G01X337992Y19109D02*
Y19115D01*
G01X338011Y19060D02*
X337992Y19109D01*
G01X338580Y16664D02*
X338582Y16624D01*
G01X338574Y16703D02*
X338580Y16664D01*
G01X338564Y16741D02*
X338574Y16703D01*
G01X338195Y18635D02*
X338011Y19060D01*
G01X338379Y17978D02*
X338195Y18635D01*
G01X338564Y17146D02*
X338379Y17978D01*
G01X338574Y17085D02*
X338564Y17146D01*
G01X338580Y17023D02*
X338574Y17085D01*
G01X338582Y16960D02*
X338580Y17023D01*
G01X338284Y19211D02*
X338382Y19212D01*
G01X338192Y19206D02*
X338284Y19211D01*
G01X338110Y19196D02*
X338192Y19206D01*
G01X338045Y19179D02*
X338110Y19196D01*
G01X338004Y19150D02*
X338045Y19179D01*
G01X337992Y19115D02*
X338004Y19150D01*
G01X349409Y21397D02*
G03X347441Y23366I-1968J1D01*
G01X349409Y21397D02*
G03X347441Y23366I-1968J1D01*
G01X349409Y21397D02*
G03X347441Y23366I-1968J1D01*
G01X349409Y21397D02*
G03X347441Y23366I-1968J1D01*
G01X347363Y27677D02*
X347680Y28858D01*
G01X349409Y21397D02*
Y33385D01*
G01Y13700D02*
Y21397D01*
G01X347363Y27677D02*
X347362Y35433D01*
G01X343149Y18031D02*
Y19212D01*
G01X343110Y23366D02*
Y24527D01*
G01Y13700D02*
Y23366D01*
G01X342559Y18031D02*
Y19212D01*
G01X341535Y27677D02*
Y24527D01*
G01X341259Y18031D02*
Y19212D01*
G01X340782Y18031D02*
Y19212D01*
G01X340698D02*
Y18031D01*
G01X340451D02*
Y19212D01*
G01X339447D02*
Y18031D01*
G01X339370D02*
Y19212D01*
G01X339173Y13700D02*
Y17992D01*
G01X338582Y18031D02*
Y19212D01*
G01X338564Y17147D02*
Y16740D01*
G01X338011Y17936D02*
Y19060D01*
G01X337992Y19115D02*
Y17970D01*
G01X337322Y18031D02*
Y19212D01*
G01X336929D02*
Y18031D01*
G01X337991Y17970D02*
X338011Y17936D01*
G01X349409Y27859D02*
X347680Y28858D01*
G01X349409Y26496D02*
X347363Y27677D01*
G01X339173Y17401D02*
X349409D01*
G01Y16811D02*
X339173D01*
G01Y13700D02*
X349409D01*
G01X347396Y46052D02*
X347342Y46006D01*
G01X347429Y46110D02*
X347396Y46052D01*
G01X347441Y46176D02*
X347429Y46110D01*
G01X347047Y45866D02*
G03X347145Y45892I0J197D01*
G01X344398Y44527D02*
G03X344463Y44538I0J197D01*
G01X344634Y44586D02*
G03X344569Y44575I0J-197D01*
G01X344998Y44586D02*
G03X345136Y44643I-1J197D01*
G01X349409Y44015D02*
X348228Y42834D01*
G01X345136Y44643D02*
X345315Y44817D01*
G01X347145Y45892D02*
X347342Y46006D01*
G01X344569Y44575D02*
X344463Y44538D01*
G01X349409Y44015D02*
Y173267D01*
G01X348228Y42834D02*
Y174448D01*
G01X347441Y46176D02*
Y47327D01*
G01X347174Y45909D02*
Y47595D01*
G01X347069Y47636D02*
Y45867D01*
G01X345315Y47465D02*
Y44817D01*
G01X344768Y47696D02*
Y44586D01*
G01X344592Y44582D02*
Y47701D01*
G01X349409Y33385D02*
X347362Y35433D01*
G01X344998Y44586D02*
X344634D01*
G01X347430Y47392D02*
X347441Y47327D01*
G01X347397Y47451D02*
X347430Y47392D01*
G01X347342Y47498D02*
X347397Y47451D01*
G01X347430Y56841D02*
X347441Y56776D01*
G01X347397Y56900D02*
X347430Y56841D01*
G01X347342Y56946D02*
X347397Y56900D01*
G01X345428Y50602D02*
X345374Y50647D01*
G01X345461Y50543D02*
X345428Y50602D01*
G01X345472Y50477D02*
X345461Y50543D01*
G01X345428Y53751D02*
X345374Y53797D01*
G01X345461Y53693D02*
X345428Y53751D01*
G01X345472Y53626D02*
X345461Y53693D01*
G01X345428Y60050D02*
X345374Y60096D01*
G01X345461Y59992D02*
X345428Y60050D01*
G01X345472Y59926D02*
X345461Y59992D01*
G01X347396Y55500D02*
X347342Y55455D01*
G01X347429Y55559D02*
X347396Y55500D01*
G01X347441Y55625D02*
X347429Y55559D01*
G01X345461Y61859D02*
X345472Y61924D01*
G01X345428Y61800D02*
X345461Y61859D01*
G01X345374Y61754D02*
X345428Y61800D01*
G01X345461Y58710D02*
X345472Y58775D01*
G01X345428Y58651D02*
X345461Y58710D01*
G01X345374Y58604D02*
X345428Y58651D01*
G01X345461Y52411D02*
X345472Y52476D01*
G01X345428Y52352D02*
X345461Y52411D01*
G01X345374Y52305D02*
X345428Y52352D01*
G01X345461Y49261D02*
X345472Y49326D01*
G01X345428Y49202D02*
X345461Y49261D01*
G01X345374Y49156D02*
X345428Y49202D01*
G01X345078Y61614D02*
G03X345177Y61640I1J197D01*
G01X345078Y58464D02*
G03X345177Y58491I-1J197D01*
G01Y60209D02*
G03X345078Y60236I-99J-170D01*
G01X347145Y57060D02*
G03X347047Y57086I-98J-171D01*
G01X347104Y57641D02*
G03X346967Y57696I-136J-142D01*
G01X344493Y57756D02*
G03X344634Y57696I142J137D01*
G01Y59586D02*
G03X344493Y59527I-1J-197D01*
G01X346967Y59586D02*
G03X347104Y59643I-1J197D01*
G01Y62641D02*
G03X346967Y62696I-136J-142D01*
G01X344493Y62756D02*
G03X344634Y62696I142J137D01*
G01X347047Y55315D02*
G03X347145Y55341I0J197D01*
G01X345078Y52165D02*
G03X345177Y52191I1J197D01*
G01Y53910D02*
G03X345078Y53937I-99J-170D01*
G01Y49015D02*
G03X345177Y49042I-1J197D01*
G01Y50761D02*
G03X345078Y50787I-98J-171D01*
G01X347145Y47611D02*
G03X347047Y47637I-98J-171D01*
G01X345136Y47641D02*
G03X344998Y47696I-136J-142D01*
G01X344569Y47708D02*
G03X344634Y47696I68J185D01*
G01X344463Y47745D02*
G03X344398Y47756I-65J-186D01*
G01Y49527D02*
G03X344463Y49538I0J197D01*
G01X344634Y49586D02*
G03X344569Y49575I0J-197D01*
G01X344998Y49586D02*
G03X345136Y49643I-1J197D01*
G01Y52641D02*
G03X344998Y52696I-136J-142D01*
G01X344569Y52708D02*
G03X344634Y52696I68J185D01*
G01X344463Y52745D02*
G03X344398Y52756I-65J-186D01*
G01X344634Y54586D02*
G03X344493Y54527I-1J-197D01*
G01X346967Y54586D02*
G03X347104Y54643I-1J197D01*
G01X345136Y49643D02*
X345315Y49817D01*
G01X347104Y54643D02*
X347283Y54817D01*
G01X347104Y59643D02*
X347283Y59817D01*
G01X345177Y49042D02*
X345374Y49156D01*
G01X345177Y52191D02*
X345374Y52305D01*
G01X347145Y55341D02*
X347342Y55455D01*
G01X345177Y58491D02*
X345374Y58604D01*
G01X345177Y61640D02*
X345374Y61754D01*
G01X344569Y49575D02*
X344463Y49538D01*
G01X347441Y55625D02*
Y56776D01*
G01X347283Y57465D02*
Y54817D01*
G01Y62465D02*
Y59817D01*
G01X347174Y55358D02*
Y57044D01*
G01X347069Y57085D02*
Y55316D01*
G01X346736Y59586D02*
Y62696D01*
G01Y54586D02*
Y57696D01*
G01X346560Y59586D02*
Y62696D01*
G01Y54586D02*
Y57696D01*
G01X345472Y50477D02*
Y49326D01*
G01Y53626D02*
Y52476D01*
G01Y59926D02*
Y58775D01*
G01Y63075D02*
Y61924D01*
G01X345315Y52465D02*
Y49817D01*
G01X345205Y61657D02*
Y63343D01*
G01Y58507D02*
Y60193D01*
G01Y52208D02*
Y53894D01*
G01Y49058D02*
Y50745D01*
G01X345101Y50786D02*
Y49017D01*
G01Y53935D02*
Y52167D01*
G01Y60235D02*
Y58466D01*
G01Y63384D02*
Y61615D01*
G01X344768Y52696D02*
Y49586D01*
G01X344592Y49582D02*
Y52701D01*
G01X347283Y62465D02*
X347104Y62641D01*
G01X347283Y57465D02*
X347104Y57641D01*
G01X345315Y52465D02*
X345136Y52641D01*
G01X345315Y47465D02*
X345136Y47641D01*
G01X345177Y60209D02*
X345374Y60096D01*
G01X347342Y56946D02*
X347145Y57060D01*
G01X345177Y53910D02*
X345374Y53797D01*
G01X345177Y50761D02*
X345374Y50647D01*
G01X347342Y47498D02*
X347145Y47611D01*
G01X344463Y52745D02*
X344569Y52708D01*
G01X344463Y47745D02*
X344569Y47708D01*
G01X344634Y62696D02*
X346967D01*
G01Y59586D02*
X344634D01*
G01Y57696D02*
X346967D01*
G01Y54586D02*
X344634D01*
G01Y52696D02*
X344998D01*
G01Y49586D02*
X344634D01*
G01Y47696D02*
X344998D01*
G01X347430Y66290D02*
X347441Y66225D01*
G01X347397Y66348D02*
X347430Y66290D01*
G01X347342Y66395D02*
X347397Y66348D01*
G01X347430Y75739D02*
X347441Y75674D01*
G01X347397Y75797D02*
X347430Y75739D01*
G01X347342Y75844D02*
X347397Y75797D01*
G01X345428Y63200D02*
X345374Y63246D01*
G01X345461Y63141D02*
X345428Y63200D01*
G01X345472Y63075D02*
X345461Y63141D01*
G01X345428Y69499D02*
X345374Y69545D01*
G01X345461Y69441D02*
X345428Y69499D01*
G01X345472Y69374D02*
X345461Y69441D01*
G01X345428Y72649D02*
X345374Y72695D01*
G01X345461Y72590D02*
X345428Y72649D01*
G01X345472Y72524D02*
X345461Y72590D01*
G01X345428Y78948D02*
X345374Y78994D01*
G01X345461Y78889D02*
X345428Y78948D01*
G01X345472Y78823D02*
X345461Y78889D01*
G01X347396Y74398D02*
X347342Y74352D01*
G01X347429Y74457D02*
X347396Y74398D01*
G01X347441Y74523D02*
X347429Y74457D01*
G01X347396Y64949D02*
X347342Y64904D01*
G01X347429Y65008D02*
X347396Y64949D01*
G01X347441Y65074D02*
X347429Y65008D01*
G01X345461Y77608D02*
X345472Y77672D01*
G01X345428Y77548D02*
X345461Y77608D01*
G01X345374Y77502D02*
X345428Y77548D01*
G01X345461Y71308D02*
X345472Y71373D01*
G01X345428Y71249D02*
X345461Y71308D01*
G01X345374Y71203D02*
X345428Y71249D01*
G01X345461Y68159D02*
X345472Y68224D01*
G01X345428Y68100D02*
X345461Y68159D01*
G01X345374Y68053D02*
X345428Y68100D01*
G01X345177Y79107D02*
G03X345078Y79133I-98J-171D01*
G01Y77362D02*
G03X345177Y77388I1J197D01*
G01X347047Y74212D02*
G03X347145Y74239I-1J197D01*
G01Y75958D02*
G03X347047Y75984I-98J-171D01*
G01X345078Y71063D02*
G03X345177Y71089I1J197D01*
G01Y72808D02*
G03X345078Y72834I-98J-171D01*
G01Y67913D02*
G03X345177Y67939I1J197D01*
G01Y69658D02*
G03X345078Y69685I-99J-170D01*
G01X345136Y67641D02*
G03X344998Y67696I-136J-142D01*
G01X344569Y67708D02*
G03X344634Y67696I68J185D01*
G01X344463Y67745D02*
G03X344398Y67756I-65J-186D01*
G01X344634Y69586D02*
G03X344493Y69527I-1J-197D01*
G01X346967Y69586D02*
G03X347104Y69643I-1J197D01*
G01Y72641D02*
G03X346967Y72696I-136J-142D01*
G01X344493Y72756D02*
G03X344634Y72696I142J137D01*
G01X344398Y74527D02*
G03X344463Y74538I0J197D01*
G01X344634Y74586D02*
G03X344569Y74575I0J-197D01*
G01X344998Y74586D02*
G03X345136Y74643I-1J197D01*
G01Y77641D02*
G03X344998Y77696I-136J-142D01*
G01X344569Y77708D02*
G03X344634Y77696I68J185D01*
G01X344463Y77745D02*
G03X344398Y77756I-65J-186D01*
G01X347047Y64763D02*
G03X347145Y64790I-2J197D01*
G01Y66509D02*
G03X347047Y66535I-98J-171D01*
G01X345177Y63359D02*
G03X345078Y63385I-98J-171D01*
G01X344398Y64527D02*
G03X344463Y64538I0J197D01*
G01X344634Y64586D02*
G03X344569Y64575I0J-197D01*
G01X344998Y64586D02*
G03X345136Y64643I-1J197D01*
G01X347145Y64790D02*
X347342Y64904D01*
G01X345136Y64643D02*
X345315Y64817D01*
G01X347104Y69643D02*
X347283Y69817D01*
G01X345136Y74643D02*
X345315Y74817D01*
G01X345177Y67939D02*
X345374Y68053D01*
G01X345177Y71089D02*
X345374Y71203D01*
G01X347145Y74239D02*
X347342Y74352D01*
G01X345177Y77388D02*
X345374Y77502D01*
G01X347441Y74523D02*
Y75674D01*
G01Y65074D02*
Y66225D01*
G01X347283Y72465D02*
Y69817D01*
G01X347174Y74255D02*
Y75941D01*
G01Y64806D02*
Y66493D01*
G01X347069Y66534D02*
Y64765D01*
G01Y75983D02*
Y74214D01*
G01X346736Y69586D02*
Y72696D01*
G01X346560Y69586D02*
Y72696D01*
G01X345472Y69374D02*
Y68224D01*
G01Y72524D02*
Y71373D01*
G01Y78823D02*
Y77672D01*
G01X345315Y67465D02*
Y64817D01*
G01Y77465D02*
Y74817D01*
G01X345205Y77405D02*
Y79091D01*
G01Y71106D02*
Y72792D01*
G01Y67956D02*
Y69642D01*
G01X345101Y69683D02*
Y67915D01*
G01Y72833D02*
Y71064D01*
G01Y79132D02*
Y77363D01*
G01X344569Y64575D02*
X344463Y64538D01*
G01X344569Y74575D02*
X344463Y74538D01*
G01X344768Y67696D02*
Y64586D01*
G01Y77696D02*
Y74586D01*
G01X344592Y74582D02*
Y77701D01*
G01Y64582D02*
Y67701D01*
G01X345315Y77465D02*
X345136Y77641D01*
G01X347283Y72465D02*
X347104Y72641D01*
G01X345315Y67465D02*
X345136Y67641D01*
G01X345177Y79107D02*
X345374Y78994D01*
G01X347342Y75844D02*
X347145Y75958D01*
G01X345177Y72808D02*
X345374Y72695D01*
G01X345177Y69658D02*
X345374Y69545D01*
G01X347342Y66395D02*
X347145Y66509D01*
G01X345177Y63359D02*
X345374Y63246D01*
G01X344463Y77745D02*
X344569Y77708D01*
G01X344463Y67745D02*
X344569Y67708D01*
G01X344634Y77696D02*
X344998D01*
G01Y74586D02*
X344634D01*
G01Y72696D02*
X346967D01*
G01Y69586D02*
X344634D01*
G01Y67696D02*
X344998D01*
G01Y64586D02*
X344634D01*
G01X347430Y85187D02*
X347441Y85122D01*
G01X347397Y85246D02*
X347430Y85187D01*
G01X347342Y85293D02*
X347397Y85246D01*
G01X347430Y94636D02*
X347441Y94571D01*
G01X347397Y94695D02*
X347430Y94636D01*
G01X347342Y94742D02*
X347397Y94695D01*
G01X345428Y82098D02*
X345374Y82143D01*
G01X345461Y82039D02*
X345428Y82098D01*
G01X345472Y81973D02*
X345461Y82039D01*
G01X345428Y88397D02*
X345374Y88443D01*
G01X345461Y88338D02*
X345428Y88397D01*
G01X345472Y88272D02*
X345461Y88338D01*
G01X345428Y91546D02*
X345374Y91592D01*
G01X345461Y91488D02*
X345428Y91546D01*
G01X345472Y91422D02*
X345461Y91488D01*
G01X347396Y93296D02*
X347342Y93250D01*
G01X347429Y93354D02*
X347396Y93296D01*
G01X347441Y93420D02*
X347429Y93354D01*
G01X347396Y83847D02*
X347342Y83801D01*
G01X347429Y83906D02*
X347396Y83847D01*
G01X347441Y83972D02*
X347429Y83906D01*
G01X345461Y90206D02*
X345472Y90271D01*
G01X345428Y90147D02*
X345461Y90206D01*
G01X345374Y90100D02*
X345428Y90147D01*
G01X345461Y87056D02*
X345472Y87121D01*
G01X345428Y86997D02*
X345461Y87056D01*
G01X345374Y86951D02*
X345428Y86997D01*
G01X345461Y80757D02*
X345472Y80822D01*
G01X345428Y80698D02*
X345461Y80757D01*
G01X345374Y80652D02*
X345428Y80698D01*
G01X347047Y93110D02*
G03X347145Y93136I0J197D01*
G01Y94855D02*
G03X347047Y94882I-100J-170D01*
G01X346967Y89586D02*
G03X347104Y89643I-1J197D01*
G01Y92641D02*
G03X346967Y92696I-136J-142D01*
G01Y94586D02*
G03X347104Y94643I-1J197D01*
G01X345078Y89960D02*
G03X345177Y89987I-1J197D01*
G01Y91706D02*
G03X345078Y91732I-98J-171D01*
G01X344634Y89586D02*
G03X344493Y89527I-1J-197D01*
G01Y92756D02*
G03X344634Y92696I142J137D01*
G01Y94586D02*
G03X344493Y94527I-1J-197D01*
G01X345078Y86811D02*
G03X345177Y86837I1J197D01*
G01Y88556D02*
G03X345078Y88582I-98J-171D01*
G01X347047Y83661D02*
G03X347145Y83687I0J197D01*
G01Y85406D02*
G03X347047Y85433I-99J-170D01*
G01X345078Y80511D02*
G03X345177Y80538I-1J197D01*
G01Y82257D02*
G03X345078Y82283I-98J-171D01*
G01X344398Y79527D02*
G03X344463Y79538I0J197D01*
G01X344634Y79586D02*
G03X344569Y79575I0J-197D01*
G01X344998Y79586D02*
G03X345136Y79643I-1J197D01*
G01Y82641D02*
G03X344998Y82696I-136J-142D01*
G01X344569Y82708D02*
G03X344634Y82696I68J185D01*
G01X344463Y82745D02*
G03X344398Y82756I-65J-186D01*
G01X344634Y84586D02*
G03X344493Y84527I-1J-197D01*
G01X346967Y84586D02*
G03X347104Y84643I-1J197D01*
G01Y87641D02*
G03X346967Y87696I-136J-142D01*
G01X344493Y87756D02*
G03X344634Y87696I142J137D01*
G01X345136Y79643D02*
X345315Y79817D01*
G01X347104Y84643D02*
X347283Y84817D01*
G01X345177Y80538D02*
X345374Y80652D01*
G01X347145Y83687D02*
X347342Y83801D01*
G01X347104Y89643D02*
X347283Y89817D01*
G01X347104Y94643D02*
X347283Y94817D01*
G01X347441Y93420D02*
Y94571D01*
G01Y83972D02*
Y85122D01*
G01X347283Y87465D02*
Y84817D01*
G01Y92465D02*
Y89817D01*
G01Y97465D02*
Y94817D01*
G01X347174Y93153D02*
Y94839D01*
G01Y83704D02*
Y85390D01*
G01X347069Y85432D02*
Y83663D01*
G01Y94880D02*
Y93111D01*
G01X346736Y94586D02*
Y97696D01*
G01Y89586D02*
Y92696D01*
G01Y84586D02*
Y87696D01*
G01X346560Y94586D02*
Y97696D01*
G01Y89586D02*
Y92696D01*
G01Y84586D02*
Y87696D01*
G01X345472Y81973D02*
Y80822D01*
G01Y88272D02*
Y87121D01*
G01Y91422D02*
Y90271D01*
G01X345315Y82465D02*
Y79817D01*
G01X345205Y90003D02*
Y91689D01*
G01Y86854D02*
Y88540D01*
G01Y80554D02*
Y82241D01*
G01X345101Y82282D02*
Y80513D01*
G01Y88581D02*
Y86812D01*
G01Y91731D02*
Y89962D01*
G01X345177Y86837D02*
X345374Y86951D01*
G01X345177Y89987D02*
X345374Y90100D01*
G01X347145Y93136D02*
X347342Y93250D01*
G01X344768Y82696D02*
Y79586D01*
G01X344592Y79582D02*
Y82701D01*
G01X344569Y79575D02*
X344463Y79538D01*
G01X347283Y92465D02*
X347104Y92641D01*
G01X347283Y87465D02*
X347104Y87641D01*
G01X345315Y82465D02*
X345136Y82641D01*
G01X347342Y94742D02*
X347145Y94855D01*
G01X345177Y91706D02*
X345374Y91592D01*
G01X345177Y88556D02*
X345374Y88443D01*
G01X347342Y85293D02*
X347145Y85406D01*
G01X345177Y82257D02*
X345374Y82143D01*
G01X344463Y82745D02*
X344569Y82708D01*
G01X346967Y94586D02*
X344634D01*
G01Y92696D02*
X346967D01*
G01Y89586D02*
X344634D01*
G01Y87696D02*
X346967D01*
G01Y84586D02*
X344634D01*
G01Y82696D02*
X344998D01*
G01Y79586D02*
X344634D01*
G01X347430Y104085D02*
X347441Y104020D01*
G01X347397Y104144D02*
X347430Y104085D01*
G01X347342Y104191D02*
X347397Y104144D01*
G01X345461Y109104D02*
X345472Y109169D01*
G01X345428Y109045D02*
X345461Y109104D01*
G01X345374Y108998D02*
X345428Y109045D01*
G01X345461Y105954D02*
X345472Y106019D01*
G01X345428Y105895D02*
X345461Y105954D01*
G01X345374Y105848D02*
X345428Y105895D01*
G01Y97846D02*
X345374Y97891D01*
G01X345461Y97787D02*
X345428Y97846D01*
G01X345472Y97721D02*
X345461Y97787D01*
G01X345428Y100995D02*
X345374Y101041D01*
G01X345461Y100937D02*
X345428Y100995D01*
G01X345472Y100870D02*
X345461Y100937D01*
G01X345428Y107295D02*
X345374Y107340D01*
G01X345461Y107236D02*
X345428Y107295D01*
G01X345472Y107170D02*
X345461Y107236D01*
G01X345428Y110444D02*
X345374Y110490D01*
G01X345461Y110385D02*
X345428Y110444D01*
G01X345472Y110319D02*
X345461Y110385D01*
G01X347396Y112193D02*
X347342Y112148D01*
G01X347429Y112252D02*
X347396Y112193D01*
G01X347441Y112318D02*
X347429Y112252D01*
G01X347396Y102745D02*
X347342Y102699D01*
G01X347429Y102803D02*
X347396Y102745D01*
G01X347441Y102869D02*
X347429Y102803D01*
G01X345461Y99655D02*
X345472Y99720D01*
G01X345428Y99596D02*
X345461Y99655D01*
G01X345374Y99549D02*
X345428Y99596D01*
G01X345461Y96505D02*
X345472Y96570D01*
G01X345428Y96446D02*
X345461Y96505D01*
G01X345374Y96400D02*
X345428Y96446D01*
G01X347047Y112008D02*
G03X347145Y112034I0J197D01*
G01X347047Y102559D02*
G03X347145Y102585I0J197D01*
G01Y104304D02*
G03X347047Y104330I-98J-171D01*
G01X347104Y102641D02*
G03X346967Y102696I-136J-142D01*
G01Y104586D02*
G03X347104Y104643I-1J197D01*
G01Y107641D02*
G03X346967Y107696I-136J-142D01*
G01X347104Y97641D02*
G03X346967Y97696I-136J-142D01*
G01Y99586D02*
G03X347104Y99643I-1J197D01*
G01X345078Y108858D02*
G03X345177Y108884I1J197D01*
G01Y110603D02*
G03X345078Y110630I-100J-170D01*
G01Y105708D02*
G03X345177Y105735I-1J197D01*
G01Y107454D02*
G03X345078Y107480I-98J-171D01*
G01X345177Y101154D02*
G03X345078Y101181I-99J-170D01*
G01X344398Y109527D02*
G03X344463Y109538I0J197D01*
G01X344634Y109586D02*
G03X344569Y109575I0J-197D01*
G01X344998Y109586D02*
G03X345136Y109643I-1J197D01*
G01X344493Y102756D02*
G03X344634Y102696I142J137D01*
G01Y104586D02*
G03X344493Y104527I-1J-197D01*
G01Y107756D02*
G03X344634Y107696I142J137D01*
G01X345078Y99409D02*
G03X345177Y99435I1J197D01*
G01X345078Y96259D02*
G03X345177Y96286I-1J197D01*
G01Y98005D02*
G03X345078Y98031I-98J-171D01*
G01X344493Y97756D02*
G03X344634Y97696I142J137D01*
G01Y99586D02*
G03X344493Y99527I-1J-197D01*
G01X347104Y99643D02*
X347283Y99817D01*
G01X347104Y104643D02*
X347283Y104817D01*
G01X345136Y109643D02*
X345315Y109817D01*
G01X347441Y102869D02*
Y104020D01*
G01X347283Y102465D02*
Y99817D01*
G01Y107465D02*
Y104817D01*
G01X347174Y112050D02*
Y113737D01*
G01Y102602D02*
Y104288D01*
G01X347069Y104329D02*
Y102560D01*
G01Y113778D02*
Y112009D01*
G01X346736Y104586D02*
Y107696D01*
G01Y99586D02*
Y102696D01*
G01X346560Y104586D02*
Y107696D01*
G01Y99586D02*
Y102696D01*
G01X345472Y97721D02*
Y96570D01*
G01Y100870D02*
Y99720D01*
G01Y107170D02*
Y106019D01*
G01Y110319D02*
Y109169D01*
G01X345315Y112465D02*
Y109817D01*
G01X345205Y108901D02*
Y110587D01*
G01Y105751D02*
Y107437D01*
G01Y99452D02*
Y101138D01*
G01Y96302D02*
Y97989D01*
G01X345101Y98030D02*
Y96261D01*
G01Y101180D02*
Y99411D01*
G01Y107479D02*
Y105710D01*
G01Y110628D02*
Y108859D01*
G01X345177Y96286D02*
X345374Y96400D01*
G01X345177Y99435D02*
X345374Y99549D01*
G01X347145Y102585D02*
X347342Y102699D01*
G01X344768Y109586D02*
Y112696D01*
G01X344592Y112701D02*
Y109582D01*
G01X345177Y105735D02*
X345374Y105848D01*
G01X345177Y108884D02*
X345374Y108998D01*
G01X347145Y112034D02*
X347342Y112148D01*
G01X344569Y109575D02*
X344463Y109538D01*
G01X347283Y107465D02*
X347104Y107641D01*
G01X347283Y102465D02*
X347104Y102641D01*
G01X347283Y97465D02*
X347104Y97641D01*
G01X345177Y110603D02*
X345374Y110490D01*
G01X345177Y107454D02*
X345374Y107340D01*
G01X347342Y104191D02*
X347145Y104304D01*
G01X345177Y101154D02*
X345374Y101041D01*
G01X345177Y98005D02*
X345374Y97891D01*
G01X344998Y109586D02*
X344634D01*
G01Y107696D02*
X346967D01*
G01Y104586D02*
X344634D01*
G01Y102696D02*
X346967D01*
G01Y99586D02*
X344634D01*
G01Y97696D02*
X346967D01*
G01X347430Y113534D02*
X347441Y113469D01*
G01X347397Y113593D02*
X347430Y113534D01*
G01X347342Y113639D02*
X347397Y113593D01*
G01X347430Y119833D02*
X347441Y119768D01*
G01X347397Y119892D02*
X347430Y119833D01*
G01X347342Y119939D02*
X347397Y119892D01*
G01X345460Y126326D02*
X345472Y126393D01*
G01X345426Y126267D02*
X345460Y126326D01*
G01X345374Y126222D02*
X345426Y126267D01*
G01X345461Y124852D02*
X345472Y124917D01*
G01X345428Y124793D02*
X345461Y124852D01*
G01X345374Y124746D02*
X345428Y124793D01*
G01X345461Y121702D02*
X345472Y121767D01*
G01X345428Y121643D02*
X345461Y121702D01*
G01X345374Y121596D02*
X345428Y121643D01*
G01X345461Y115403D02*
X345472Y115468D01*
G01X345428Y115344D02*
X345461Y115403D01*
G01X345374Y115297D02*
X345428Y115344D01*
G01X345460Y123176D02*
X345472Y123243D01*
G01X345426Y123117D02*
X345460Y123176D01*
G01X345374Y123073D02*
X345426Y123117D01*
G01X347429Y120026D02*
X347441Y120094D01*
G01X347395Y119967D02*
X347429Y120026D01*
G01X347342Y119923D02*
X347395Y119967D01*
G01X345426Y124520D02*
X345374Y124565D01*
G01X345460Y124461D02*
X345426Y124520D01*
G01X345472Y124394D02*
X345460Y124461D01*
G01X345426Y127670D02*
X345374Y127714D01*
G01X345460Y127611D02*
X345426Y127670D01*
G01X345472Y127544D02*
X345460Y127611D01*
G01X347395Y121371D02*
X347342Y121415D01*
G01X347429Y121312D02*
X347395Y121371D01*
G01X347441Y121245D02*
X347429Y121312D01*
G01X345428Y116743D02*
X345374Y116789D01*
G01X345461Y116685D02*
X345428Y116743D01*
G01X345472Y116619D02*
X345461Y116685D01*
G01X345428Y123043D02*
X345374Y123088D01*
G01X345461Y122984D02*
X345428Y123043D01*
G01X345472Y122918D02*
X345461Y122984D01*
G01X345428Y126192D02*
X345374Y126238D01*
G01X345461Y126133D02*
X345428Y126192D01*
G01X345472Y126067D02*
X345461Y126133D01*
G01X347396Y127941D02*
X347342Y127896D01*
G01X347429Y128000D02*
X347396Y127941D01*
G01X347441Y128066D02*
X347429Y128000D01*
G01X347396Y118493D02*
X347342Y118447D01*
G01X347429Y118551D02*
X347396Y118493D01*
G01X347441Y118617D02*
X347429Y118551D01*
G01X347047Y127756D02*
G03X347145Y127782I0J197D01*
G01X347047Y118307D02*
G03X347145Y118333I0J197D01*
G01Y120052D02*
G03X347047Y120078I-98J-171D01*
G01X347145Y113753D02*
G03X347047Y113779I-98J-171D01*
G01Y119783D02*
G03X347145Y119809I0J197D01*
G01Y121528D02*
G03X347047Y121555I-99J-170D01*
G01X345078Y124606D02*
G03X345177Y124632I1J197D01*
G01Y126351D02*
G03X345078Y126378I-100J-170D01*
G01X345177Y123202D02*
G03X345078Y123228I-98J-171D01*
G01Y122933D02*
G03X345177Y122959I1J197D01*
G01Y124678D02*
G03X345078Y124704I-98J-171D01*
G01Y126082D02*
G03X345177Y126109I-1J197D01*
G01Y127828D02*
G03X345078Y127854I-98J-171D01*
G01Y121456D02*
G03X345177Y121483I-1J197D01*
G01X345078Y115157D02*
G03X345177Y115183I1J197D01*
G01Y116902D02*
G03X345078Y116929I-99J-170D01*
G01X345136Y112641D02*
G03X344998Y112696I-136J-142D01*
G01X344569Y112708D02*
G03X344634Y112696I68J185D01*
G01X344463Y112745D02*
G03X344398Y112756I-65J-186D01*
G01Y114527D02*
G03X344463Y114538I0J197D01*
G01X344634Y114586D02*
G03X344569Y114575I0J-197D01*
G01X344998Y114586D02*
G03X345136Y114643I-1J197D01*
G01Y117641D02*
G03X344998Y117696I-136J-142D01*
G01X344569Y117708D02*
G03X344634Y117696I68J185D01*
G01X344463Y117745D02*
G03X344398Y117756I-65J-186D01*
G01X347834Y138189D02*
Y119094D01*
G01X347441Y128066D02*
Y129217D01*
G01Y118617D02*
Y119768D01*
G01Y112318D02*
Y113469D01*
G01Y121245D02*
Y120094D01*
G01X347174Y127798D02*
Y129485D01*
G01Y118350D02*
Y120036D01*
G01D02*
Y121512D01*
G01X347069Y120077D02*
Y121554D01*
G01Y120077D02*
Y118308D01*
G01Y129526D02*
Y127757D01*
G01X345472Y116619D02*
Y115468D01*
G01Y122918D02*
Y121767D01*
G01Y126067D02*
Y124917D01*
G01Y124394D02*
Y123243D01*
G01Y127544D02*
Y126393D01*
G01X345315Y117465D02*
Y114817D01*
G01X345205Y124649D02*
Y126335D01*
G01Y121499D02*
Y123185D01*
G01Y115200D02*
Y116886D01*
G01Y124649D02*
Y123185D01*
G01Y127811D02*
Y126335D01*
G01X345101Y126376D02*
Y127853D01*
G01Y123227D02*
Y124608D01*
G01Y116928D02*
Y115159D01*
G01Y123227D02*
Y121458D01*
G01Y126376D02*
Y124608D01*
G01X345136Y114643D02*
X345315Y114817D01*
G01X347834Y119094D02*
X349409Y120669D01*
G01X344768Y114586D02*
Y117696D01*
G01X344592Y117701D02*
Y114582D01*
G01X345177Y115183D02*
X345374Y115297D01*
G01X347145Y118333D02*
X347342Y118447D01*
G01X347145Y119809D02*
X347342Y119923D01*
G01X345177Y121483D02*
X345374Y121596D01*
G01X345177Y122959D02*
X345374Y123073D01*
G01X345177Y124632D02*
X345374Y124746D01*
G01X345177Y126109D02*
X345374Y126222D01*
G01X347145Y127782D02*
X347342Y127896D01*
G01X344569Y114575D02*
X344463Y114538D01*
G01X345315Y117465D02*
X345136Y117641D01*
G01X345315Y112465D02*
X345136Y112641D01*
G01X345374Y127714D02*
X345177Y127828D01*
G01Y126351D02*
X345374Y126238D01*
G01Y124565D02*
X345177Y124678D01*
G01Y123202D02*
X345374Y123088D01*
G01X347342Y121415D02*
X347145Y121528D01*
G01X347342Y119939D02*
X347145Y120052D01*
G01X345177Y116902D02*
X345374Y116789D01*
G01X347342Y113639D02*
X347145Y113753D01*
G01X344463Y117745D02*
X344569Y117708D01*
G01X344463Y112745D02*
X344569Y112708D01*
G01X344634Y117696D02*
X344998D01*
G01Y114586D02*
X344634D01*
G01Y112696D02*
X344998D01*
G01X347430Y129282D02*
X347441Y129217D01*
G01X347397Y129341D02*
X347430Y129282D01*
G01X347342Y129387D02*
X347397Y129341D01*
G01X347430Y138731D02*
X347441Y138666D01*
G01X347397Y138789D02*
X347430Y138731D01*
G01X347342Y138836D02*
X347397Y138789D01*
G01X347430Y145030D02*
X347441Y144965D01*
G01X347397Y145089D02*
X347430Y145030D01*
G01X347342Y145135D02*
X347397Y145089D01*
G01X345461Y140600D02*
X345472Y140665D01*
G01X345428Y140541D02*
X345461Y140600D01*
G01X345374Y140494D02*
X345428Y140541D01*
G01X345461Y134300D02*
X345472Y134365D01*
G01X345428Y134241D02*
X345461Y134300D01*
G01X345374Y134195D02*
X345428Y134241D01*
G01X345461Y131151D02*
X345472Y131216D01*
G01X345428Y131092D02*
X345461Y131151D01*
G01X345374Y131045D02*
X345428Y131092D01*
G01X345460Y135774D02*
X345472Y135842D01*
G01X345426Y135715D02*
X345460Y135774D01*
G01X345374Y135671D02*
X345426Y135715D01*
G01X345460Y132625D02*
X345472Y132692D01*
G01X345426Y132566D02*
X345460Y132625D01*
G01X345374Y132522D02*
X345426Y132566D01*
G01X347429Y129475D02*
X347441Y129543D01*
G01X347395Y129416D02*
X347429Y129475D01*
G01X347342Y129372D02*
X347395Y129416D01*
G01X345426Y133969D02*
X345374Y134013D01*
G01X345460Y133910D02*
X345426Y133969D01*
G01X345472Y133843D02*
X345460Y133910D01*
G01X345426Y137119D02*
X345374Y137163D01*
G01X345460Y137060D02*
X345426Y137119D01*
G01X345472Y136993D02*
X345460Y137060D01*
G01X347395Y130820D02*
X347342Y130864D01*
G01X347429Y130761D02*
X347395Y130820D01*
G01X347441Y130693D02*
X347429Y130761D01*
G01X345428Y132491D02*
X345374Y132537D01*
G01X345461Y132433D02*
X345428Y132491D01*
G01X345472Y132367D02*
X345461Y132433D01*
G01X345428Y135641D02*
X345374Y135687D01*
G01X345461Y135582D02*
X345428Y135641D01*
G01X345472Y135516D02*
X345461Y135582D01*
G01X345428Y141940D02*
X345374Y141986D01*
G01X345461Y141882D02*
X345428Y141940D01*
G01X345472Y141815D02*
X345461Y141882D01*
G01X347396Y143689D02*
X347342Y143644D01*
G01X347429Y143748D02*
X347396Y143689D01*
G01X347441Y143814D02*
X347429Y143748D01*
G01X347396Y137390D02*
X347342Y137345D01*
G01X347429Y137449D02*
X347396Y137390D01*
G01X347441Y137515D02*
X347429Y137449D01*
G01X347145Y145249D02*
G03X347047Y145275I-98J-171D01*
G01Y143504D02*
G03X347145Y143530I0J197D01*
G01Y138950D02*
G03X347047Y138976I-98J-171D01*
G01Y137204D02*
G03X347145Y137231I-2J197D01*
G01X346967Y139586D02*
G03X347104Y139643I-1J197D01*
G01Y142641D02*
G03X346967Y142696I-136J-142D01*
G01X344493Y142756D02*
G03X344634Y142696I142J137D01*
G01X344398Y144527D02*
G03X344463Y144538I0J197D01*
G01X344634Y144586D02*
G03X344569Y144575I0J-197D01*
G01X344998Y144586D02*
G03X345136Y144643I-1J197D01*
G01X345078Y134055D02*
G03X345177Y134081I1J197D01*
G01Y135800D02*
G03X345078Y135826I-98J-171D01*
G01X345177Y142099D02*
G03X345078Y142126I-100J-170D01*
G01Y140354D02*
G03X345177Y140380I1J197D01*
G01X345078Y132382D02*
G03X345177Y132408I1J197D01*
G01Y134127D02*
G03X345078Y134153I-98J-171D01*
G01Y135531D02*
G03X345177Y135558I0J197D01*
G01Y137276D02*
G03X345078Y137303I-99J-170D01*
G01X344634Y139586D02*
G03X344493Y139527I-1J-197D01*
G01X347145Y129501D02*
G03X347047Y129527I-98J-171D01*
G01Y129232D02*
G03X347145Y129258I0J197D01*
G01Y130977D02*
G03X347047Y131004I-100J-170D01*
G01X345078Y130905D02*
G03X345177Y130932I0J197D01*
G01Y132650D02*
G03X345078Y132677I-99J-170D01*
G01X347441Y143814D02*
Y144965D01*
G01Y137515D02*
Y138666D01*
G01Y130693D02*
Y129543D01*
G01X347283Y142465D02*
Y139817D01*
G01X347174Y143546D02*
Y145233D01*
G01Y137247D02*
Y138933D01*
G01Y129485D02*
Y130961D01*
G01X347069Y131002D02*
Y129526D01*
G01Y138975D02*
Y137206D01*
G01Y145274D02*
Y143505D01*
G01X346736Y142696D02*
Y139586D01*
G01X346560D02*
Y142696D01*
G01X345472Y132367D02*
Y131216D01*
G01Y135516D02*
Y134365D01*
G01Y133843D02*
Y132692D01*
G01Y136993D02*
Y135842D01*
G01Y141815D02*
Y140665D01*
G01X345315Y147465D02*
Y144817D01*
G01X345205Y140397D02*
Y142083D01*
G01Y134098D02*
Y135784D01*
G01Y130948D02*
Y132634D01*
G01Y134098D02*
Y132634D01*
G01Y137260D02*
Y135784D01*
G01X345101Y135825D02*
Y137302D01*
G01Y132676D02*
Y134056D01*
G01Y132676D02*
Y130907D01*
G01Y135825D02*
Y134056D01*
G01Y142124D02*
Y140356D01*
G01X344768Y144586D02*
Y147696D01*
G01X344592Y147701D02*
Y144582D01*
G01X347104Y139643D02*
X347283Y139817D01*
G01X345136Y144643D02*
X345315Y144817D01*
G01X347145Y129258D02*
X347342Y129372D01*
G01X345177Y130932D02*
X345374Y131045D01*
G01X345177Y132408D02*
X345374Y132522D01*
G01X345177Y134081D02*
X345374Y134195D01*
G01X345177Y135558D02*
X345374Y135671D01*
G01X347145Y137231D02*
X347342Y137345D01*
G01X345177Y140380D02*
X345374Y140494D01*
G01X347145Y143530D02*
X347342Y143644D01*
G01X349409Y136614D02*
X347834Y138189D01*
G01X347283Y142465D02*
X347104Y142641D01*
G01X344569Y144575D02*
X344463Y144538D01*
G01X347342Y145135D02*
X347145Y145249D01*
G01X345177Y142099D02*
X345374Y141986D01*
G01X347342Y138836D02*
X347145Y138950D01*
G01X345374Y137163D02*
X345177Y137276D01*
G01Y135800D02*
X345374Y135687D01*
G01Y134013D02*
X345177Y134127D01*
G01Y132650D02*
X345374Y132537D01*
G01X347342Y130864D02*
X347145Y130977D01*
G01X347342Y129387D02*
X347145Y129501D01*
G01X344998Y144586D02*
X344634D01*
G01Y142696D02*
X346967D01*
G01Y139586D02*
X344634D01*
G01X347430Y154479D02*
X347441Y154414D01*
G01X347397Y154537D02*
X347430Y154479D01*
G01X347342Y154584D02*
X347397Y154537D01*
G01X345461Y159497D02*
X345472Y159562D01*
G01X345428Y159438D02*
X345461Y159497D01*
G01X345374Y159392D02*
X345428Y159438D01*
G01X345461Y156348D02*
X345472Y156413D01*
G01X345428Y156289D02*
X345461Y156348D01*
G01X345374Y156242D02*
X345428Y156289D01*
G01X345461Y150048D02*
X345472Y150113D01*
G01X345428Y149989D02*
X345461Y150048D01*
G01X345374Y149943D02*
X345428Y149989D01*
G01X345461Y146899D02*
X345472Y146964D01*
G01X345428Y146840D02*
X345461Y146899D01*
G01X345374Y146793D02*
X345428Y146840D01*
G01Y148239D02*
X345374Y148285D01*
G01X345461Y148181D02*
X345428Y148239D01*
G01X345472Y148115D02*
X345461Y148181D01*
G01X345428Y151389D02*
X345374Y151435D01*
G01X345461Y151330D02*
X345428Y151389D01*
G01X345472Y151264D02*
X345461Y151330D01*
G01X345428Y157688D02*
X345374Y157734D01*
G01X345461Y157630D02*
X345428Y157688D01*
G01X345472Y157563D02*
X345461Y157630D01*
G01X345428Y160838D02*
X345374Y160883D01*
G01X345461Y160779D02*
X345428Y160838D01*
G01X345472Y160713D02*
X345461Y160779D01*
G01X347396Y153138D02*
X347342Y153093D01*
G01X347429Y153197D02*
X347396Y153138D01*
G01X347441Y153263D02*
X347429Y153197D01*
G01X347145Y154698D02*
G03X347047Y154724I-98J-171D01*
G01Y152952D02*
G03X347145Y152979I-2J197D01*
G01X346967Y154586D02*
G03X347104Y154643I-1J197D01*
G01Y157641D02*
G03X346967Y157696I-136J-142D01*
G01X345177Y157847D02*
G03X345078Y157874I-99J-170D01*
G01Y156102D02*
G03X345177Y156128I1J197D01*
G01Y160997D02*
G03X345078Y161023I-98J-171D01*
G01Y159252D02*
G03X345177Y159278I1J197D01*
G01X344569Y152708D02*
G03X344634Y152696I68J185D01*
G01Y154586D02*
G03X344493Y154527I-1J-197D01*
G01Y157756D02*
G03X344634Y157696I142J137D01*
G01X344398Y159527D02*
G03X344463Y159538I0J197D01*
G01X344634Y159586D02*
G03X344569Y159575I0J-197D01*
G01X344998Y159586D02*
G03X345136Y159643I-1J197D01*
G01X345177Y148398D02*
G03X345078Y148425I-99J-170D01*
G01Y146653D02*
G03X345177Y146680I0J197D01*
G01Y151548D02*
G03X345078Y151574I-98J-171D01*
G01Y149803D02*
G03X345177Y149829I1J197D01*
G01X345136Y147641D02*
G03X344998Y147696I-136J-142D01*
G01X344569Y147708D02*
G03X344634Y147696I68J185D01*
G01X344463Y147745D02*
G03X344398Y147756I-65J-186D01*
G01Y149527D02*
G03X344463Y149538I0J197D01*
G01X344634Y149586D02*
G03X344569Y149575I0J-197D01*
G01X344998Y149586D02*
G03X345136Y149643I-1J197D01*
G01Y152641D02*
G03X344998Y152696I-136J-142D01*
G01X344463Y152745D02*
G03X344398Y152756I-65J-186D01*
G01X347441Y153263D02*
Y154414D01*
G01X347283Y157465D02*
Y154817D01*
G01X347174Y152995D02*
Y154682D01*
G01X347069Y154723D02*
Y152954D01*
G01X346736Y157696D02*
Y154586D01*
G01X346560D02*
Y157696D01*
G01X345472Y148115D02*
Y146964D01*
G01Y151264D02*
Y150113D01*
G01Y157563D02*
Y156413D01*
G01Y160713D02*
Y159562D01*
G01X345315Y152465D02*
Y149817D01*
G01Y162465D02*
Y159817D01*
G01X345205Y159295D02*
Y160981D01*
G01Y156145D02*
Y157831D01*
G01Y149846D02*
Y151532D01*
G01Y146696D02*
Y148382D01*
G01X345101Y148424D02*
Y146655D01*
G01Y151573D02*
Y149804D01*
G01Y157872D02*
Y156104D01*
G01Y161022D02*
Y159253D01*
G01X344768Y159586D02*
Y162696D01*
G01Y149586D02*
Y152696D01*
G01X344592Y152701D02*
Y149582D01*
G01Y162701D02*
Y159582D01*
G01X345136Y149643D02*
X345315Y149817D01*
G01X347104Y154643D02*
X347283Y154817D01*
G01X345136Y159643D02*
X345315Y159817D01*
G01X347283Y157465D02*
X347104Y157641D01*
G01X345177Y146680D02*
X345374Y146793D01*
G01X345177Y149829D02*
X345374Y149943D01*
G01X347145Y152979D02*
X347342Y153093D01*
G01X345177Y156128D02*
X345374Y156242D01*
G01X345177Y159278D02*
X345374Y159392D01*
G01X345315Y152465D02*
X345136Y152641D01*
G01X345315Y147465D02*
X345136Y147641D01*
G01X344569Y149575D02*
X344463Y149538D01*
G01X344569Y159575D02*
X344463Y159538D01*
G01X345177Y160997D02*
X345374Y160883D01*
G01X345177Y157847D02*
X345374Y157734D01*
G01X347342Y154584D02*
X347145Y154698D01*
G01X345177Y151548D02*
X345374Y151435D01*
G01X345177Y148398D02*
X345374Y148285D01*
G01X344463Y152745D02*
X344569Y152708D01*
G01X344463Y147745D02*
X344569Y147708D01*
G01X344998Y159586D02*
X344634D01*
G01Y157696D02*
X346967D01*
G01Y154586D02*
X344634D01*
G01Y152696D02*
X344998D01*
G01Y149586D02*
X344634D01*
G01Y147696D02*
X344998D01*
G01X347430Y163928D02*
X347441Y163863D01*
G01X347397Y163986D02*
X347430Y163928D01*
G01X347342Y164033D02*
X347397Y163986D01*
G01X345461Y168946D02*
X345472Y169011D01*
G01X345428Y168887D02*
X345461Y168946D01*
G01X345374Y168841D02*
X345428Y168887D01*
G01X345461Y165796D02*
X345472Y165861D01*
G01X345428Y165737D02*
X345461Y165796D01*
G01X345374Y165691D02*
X345428Y165737D01*
G01Y167137D02*
X345374Y167183D01*
G01X345461Y167078D02*
X345428Y167137D01*
G01X345472Y167012D02*
X345461Y167078D01*
G01X345428Y170287D02*
X345374Y170332D01*
G01X345461Y170228D02*
X345428Y170287D01*
G01X345472Y170162D02*
X345461Y170228D01*
G01X347396Y162587D02*
X347342Y162541D01*
G01X347429Y162646D02*
X347396Y162587D01*
G01X347441Y162712D02*
X347429Y162646D01*
G01X347145Y164146D02*
G03X347047Y164173I-99J-170D01*
G01X346967Y169586D02*
G03X347104Y169643I-1J197D01*
G01Y172641D02*
G03X346967Y172696I-136J-142D01*
G01X347047Y162401D02*
G03X347145Y162428I-1J197D01*
G01X345177Y167296D02*
G03X345078Y167322I-98J-171D01*
G01Y165551D02*
G03X345177Y165577I1J197D01*
G01Y170446D02*
G03X345078Y170472I-98J-171D01*
G01Y168700D02*
G03X345177Y168727I-1J197D01*
G01X344569Y162708D02*
G03X344634Y162696I68J185D01*
G01X344398Y164527D02*
G03X344463Y164538I0J197D01*
G01X344634Y164586D02*
G03X344569Y164575I0J-197D01*
G01X344998Y164586D02*
G03X345136Y164643I-1J197D01*
G01Y167641D02*
G03X344998Y167696I-136J-142D01*
G01X344569Y167708D02*
G03X344634Y167696I68J185D01*
G01X344463Y167745D02*
G03X344398Y167756I-65J-186D01*
G01X344634Y169586D02*
G03X344493Y169527I-1J-197D01*
G01Y172756D02*
G03X344634Y172696I142J137D01*
G01X345136Y162641D02*
G03X344998Y162696I-136J-142D01*
G01X344463Y162745D02*
G03X344398Y162756I-65J-186D01*
G01X347441Y162712D02*
Y163863D01*
G01X347283Y172465D02*
Y169817D01*
G01X347174Y162444D02*
Y164130D01*
G01X347069Y164172D02*
Y162403D01*
G01X346736Y172696D02*
Y169586D01*
G01X346560D02*
Y172696D01*
G01X345472Y167012D02*
Y165861D01*
G01Y170162D02*
Y169011D01*
G01X345315Y167465D02*
Y164817D01*
G01X345205Y168743D02*
Y170430D01*
G01Y165594D02*
Y167280D01*
G01X345101Y167321D02*
Y165552D01*
G01Y170471D02*
Y168702D01*
G01X344768Y164586D02*
Y167696D01*
G01X344592Y167701D02*
Y164582D01*
G01X345136Y164643D02*
X345315Y164817D01*
G01X347104Y169643D02*
X347283Y169817D01*
G01X348228Y174448D02*
X349409Y173267D01*
G01X347283Y172465D02*
X347104Y172641D01*
G01X345315Y167465D02*
X345136Y167641D01*
G01X345315Y162465D02*
X345136Y162641D01*
G01X347145Y162428D02*
X347342Y162541D01*
G01X345177Y165577D02*
X345374Y165691D01*
G01X345177Y168727D02*
X345374Y168841D01*
G01X345177Y170446D02*
X345374Y170332D01*
G01X345177Y167296D02*
X345374Y167183D01*
G01X347342Y164033D02*
X347145Y164146D01*
G01X344569Y164575D02*
X344463Y164538D01*
G01Y167745D02*
X344569Y167708D01*
G01X344463Y162745D02*
X344569Y162708D01*
G01X344634Y172696D02*
X346967D01*
G01Y169586D02*
X344634D01*
G01Y167696D02*
X344998D01*
G01Y164586D02*
X344634D01*
G01Y162696D02*
X344998D01*
G01X347441Y193957D02*
G03X349408Y195925I-1J1968D01*
G01X347441Y193956D02*
G03X349409Y195925I-1J1969D01*
G01X347441Y193956D02*
G03X349409Y195925I-1J1969D01*
G01X347441Y193956D02*
G03X349409Y195925I-1J1969D01*
G01X347441Y193956D02*
G03X349409Y195925I-1J1969D01*
G01D02*
Y183897D01*
G01X347363Y189606D02*
Y181852D01*
G01X347680Y188425D02*
X347363Y189606D01*
G01X343110Y193956D02*
Y203582D01*
G01Y192756D02*
Y193956D01*
G01X341535Y189606D02*
Y192756D01*
G01X347362Y181850D02*
X349409Y183897D01*
G01X347680Y188425D02*
X349409Y189423D01*
G01Y190787D02*
X347363Y189606D01*
G01X349409Y195925D02*
Y215630D01*
G01X338110Y198086D02*
X338021Y198117D01*
G01X338243Y198074D02*
X338110Y198086D01*
G01X338405Y198071D02*
X338243Y198074D01*
G01X338137Y199259D02*
X338329Y199252D01*
G01X338021Y199281D02*
X338137Y199259D01*
G01X337995Y199327D02*
X337992Y199313D01*
G01X338011Y199347D02*
X337995Y199327D01*
G01X337992Y198162D02*
Y198169D01*
G01X338001Y198138D02*
X337992Y198162D01*
G01X338021Y198117D02*
X338001Y198138D01*
G01X338195Y199612D02*
X338011Y199347D01*
G01X338379Y200023D02*
X338195Y199612D01*
G01X338564Y200542D02*
X338379Y200023D01*
G01Y199305D02*
X338564Y200136D01*
G01X338195Y198647D02*
X338379Y199305D01*
G01X338011Y198223D02*
X338195Y198647D01*
G01X338001Y199294D02*
X338021Y199281D01*
G01X337992Y199309D02*
X338001Y199294D01*
G01X337992Y199313D02*
Y199309D01*
G01X338574Y200580D02*
X338564Y200542D01*
G01X338580Y200619D02*
X338574Y200580D01*
G01X338582Y200659D02*
X338580Y200619D01*
G01X337995Y198191D02*
X338011Y198223D01*
G01X337992Y198169D02*
X337995Y198191D01*
G01X338580Y200260D02*
X338582Y200323D01*
G01X338574Y200198D02*
X338580Y200260D01*
G01X338564Y200136D02*
X338574Y200198D01*
G01X338582Y207086D02*
G03X337401Y208267I-1181J0D01*
G01X349409Y215630D02*
Y195925D01*
G01Y215630D02*
Y195925D01*
G01Y203582D02*
Y195925D01*
G01X343149Y199252D02*
Y198070D01*
G01X342559Y199252D02*
Y198070D01*
G01X341259Y199252D02*
Y198070D01*
G01X340782D02*
Y199252D01*
G01X340698D02*
Y198070D01*
G01X340451D02*
Y199252D01*
G01X339447D02*
Y198070D01*
G01X339370D02*
Y199252D01*
G01X339173Y199291D02*
Y203582D01*
G01X338582Y200323D02*
Y207086D01*
G01Y198070D02*
Y199252D01*
G01X338564Y200543D02*
Y200136D01*
G01X338021Y198117D02*
Y199281D01*
G01X338011Y199347D02*
Y198223D01*
G01X337992Y199313D02*
Y198169D01*
G01X337322Y198070D02*
Y199252D01*
G01X336929D02*
Y198070D01*
G01X339173Y203582D02*
X349409D01*
G01Y200472D02*
X339173D01*
G01X349409Y199882D02*
X339173D01*
G01X349409Y215630D02*
Y195925D01*
G01Y215630D02*
Y195925D01*
G01Y215630D02*
G03X347441Y217598I-1968J0D01*
G01X337598Y219567D02*
Y274843D01*
G01Y219567D02*
G03X339567Y217598I1969J0D01*
G01X347441D02*
X339567D01*
G01X349409Y215630D02*
G03X347441Y217598I-1968J0D01*
G01X337598Y219567D02*
G03X339567Y217598I1969J0D01*
G01X337598Y219567D02*
G03X339567Y217598I1969J0D01*
G01X349409Y215630D02*
G03X347441Y217598I-1968J0D01*
G01X337598Y219567D02*
G03X339567Y217598I1969J0D01*
G01X337598Y219567D02*
G03X339567Y217598I1969J0D01*
G01X349409Y215630D02*
G03X347441Y217598I-1968J0D01*
G01X349409Y215630D02*
G03X347441Y217598I-1968J0D01*
G01X337598Y274842D02*
Y219567D01*
G01Y274842D02*
Y219567D01*
G01X347441Y217598D02*
X339567D01*
G01X347441D02*
X339567D01*
G01X337598Y274842D02*
Y219567D01*
G01Y274842D02*
Y219567D01*
G01X347441Y217598D02*
X339567D01*
G01X347441D02*
X339567D01*
G01X347441Y276811D02*
G03X349409Y278780I0J1968D01*
G01X339567Y276811D02*
X347441D01*
G01X339567D02*
G03X337598Y274843I0J-1969D01*
G01X347441Y276811D02*
G03X349409Y278779I0J1968D01*
G01X339567Y276811D02*
G03X337598Y274842I0J-1969D01*
G01X347441Y276811D02*
G03X349409Y278779I0J1968D01*
G01X339567Y276811D02*
G03X337598Y274842I0J-1969D01*
G01X347441Y276811D02*
G03X349409Y278779I0J1968D01*
G01X339567Y276811D02*
G03X337598Y274842I0J-1969D01*
G01X347441Y276811D02*
G03X349409Y278779I0J1968D01*
G01X339567Y276811D02*
G03X337598Y274842I0J-1969D01*
G01X347441Y276811D02*
X339567D01*
G01X347441D02*
X339567D01*
G01X347441D02*
X339567D01*
G01X347441D02*
X339567D01*
G01X353346Y282717D02*
G03X349409Y278780I0J-3937D01*
G01D02*
Y355551D01*
G01D02*
Y278779D01*
G01Y355551D02*
Y278779D01*
G01Y355551D02*
Y278779D01*
G01Y355551D02*
Y278779D01*
G01Y309489D02*
G03X353346Y305552I3937J0D01*
G01X349409Y355797D02*
Y423796D01*
G01X349408Y355551D02*
G03X341535Y363425I-7874J0D01*
G01X349409Y355551D02*
G03X341535Y363425I-7874J0D01*
G01X349409Y355551D02*
G03X341535Y363425I-7874J0D01*
G01X349409Y355551D02*
G03X341535Y363425I-7874J0D01*
G01X349409Y355551D02*
G03X341535Y363425I-7874J0D01*
G01X344167Y381710D02*
Y384510D01*
G01X349409Y419228D02*
X349245Y420089D01*
X348753Y421073D01*
X347933Y421689D01*
X346784Y421935D01*
X345636Y421689D01*
X344652Y420950D01*
X344159Y419843D01*
Y418613D01*
X343831Y417875D01*
X343011Y417259D01*
X341863Y417013D01*
X340714Y417383D01*
X339894Y418244D01*
X339566Y419228D01*
X339894Y420212D01*
X340714Y421073D01*
X341863Y421443D01*
X343011Y421196D01*
X343831Y420581D01*
X344159Y419843D01*
Y418613D01*
X344652Y417506D01*
X345636Y416767D01*
X346784Y416521D01*
X347933Y416767D01*
X348753Y417383D01*
X349245Y418367D01*
X349409Y419228D01*
G01Y429071D02*
X349245Y429932D01*
X348753Y430916D01*
X347933Y431532D01*
X346784Y431778D01*
X345636Y431532D01*
X344652Y430793D01*
X344159Y429686D01*
Y428456D01*
X343831Y427718D01*
X343011Y427102D01*
X341863Y426856D01*
X340714Y427226D01*
X339894Y428087D01*
X339566Y429071D01*
X339894Y430055D01*
X340714Y430916D01*
X341863Y431286D01*
X343011Y431039D01*
X343831Y430424D01*
X344159Y429686D01*
Y428456D01*
X344652Y427349D01*
X345636Y426610D01*
X346784Y426364D01*
X347933Y426610D01*
X348753Y427226D01*
X349245Y428210D01*
X349409Y429071D01*
G01X349737Y438914D02*
X349573Y438668D01*
X349245D01*
X349081Y438914D01*
X349245Y439160D01*
X349573D01*
X349737Y438914D01*
G01X349409Y448511D02*
X347277Y448757D01*
X345472Y449126D01*
X343831Y449618D01*
X342027Y450233D01*
X339566Y451218D01*
Y446296D01*
G01X347933Y455893D02*
X348753Y456631D01*
X349245Y457493D01*
X349409Y458600D01*
X349081Y459707D01*
X348425Y460568D01*
X347277Y461184D01*
X345964Y461307D01*
X344652Y461061D01*
X343831Y460445D01*
X343175Y459584D01*
X343011Y458723D01*
X343175Y457862D01*
X343831Y456755D01*
X339566Y457124D01*
Y460445D01*
G01X359401Y-752009D02*
Y-745709D01*
X356503Y-750224D01*
X360419D01*
G01X353346Y-47481D02*
X369094D01*
G01X373031Y-51418D02*
G03X369094Y-47481I-3937J0D01*
G01X353346Y-24646D02*
X369094D01*
G01D02*
G03X373031Y-20709I0J3937D01*
G01X353346Y282717D02*
X369094D01*
G01X373031Y278780D02*
G03X369094Y282717I-3937J0D01*
G01X353346Y305552D02*
X369094D01*
G01D02*
G03X373031Y309489I0J3937D01*
G01X371883Y417136D02*
X372703Y417998D01*
X373031Y418982D01*
X372703Y419966D01*
X371719Y420827D01*
X370242Y421443D01*
X368766Y421689D01*
X366961D01*
X365485Y421443D01*
X364172Y420827D01*
X363516Y420089D01*
X363188Y419228D01*
X363516Y418244D01*
X364172Y417506D01*
X365156Y417013D01*
X366469Y416767D01*
X367617Y417013D01*
X368766Y417629D01*
X369422Y418367D01*
X369586Y419228D01*
X369258Y420212D01*
X368438Y420950D01*
X366961Y421689D01*
G01X373031Y430547D02*
X363188D01*
X370242Y425995D01*
Y432147D01*
G01X373359Y438914D02*
X373195Y438668D01*
X372867D01*
X372703Y438914D01*
X372867Y439160D01*
X373195D01*
X373359Y438914D01*
G01X373031Y448511D02*
X370899Y448757D01*
X369094Y449126D01*
X367453Y449618D01*
X365649Y450233D01*
X363188Y451218D01*
Y446296D01*
G01X371555Y455893D02*
X372375Y456631D01*
X372867Y457493D01*
X373031Y458600D01*
X372703Y459707D01*
X372047Y460568D01*
X370899Y461184D01*
X369586Y461307D01*
X368274Y461061D01*
X367453Y460445D01*
X366797Y459584D01*
X366633Y458723D01*
X366797Y457862D01*
X367453Y456755D01*
X363188Y457124D01*
Y460445D01*
G01X359401Y608621D02*
Y614921D01*
X356503Y610406D01*
X360419D01*
G01X373030Y-97480D02*
G03X380904Y-105354I7874J0D01*
G01X373030Y-97480D02*
G03X380904Y-105354I7874J0D01*
G01X373030Y-97480D02*
G03X380904Y-105354I7874J0D01*
G01X373030Y-97480D02*
G03X380904Y-105354I7874J0D01*
G01D02*
X714566D01*
G01X380904D02*
X714566D01*
G01X380904D02*
X714566D01*
G01X380904D02*
X714566D01*
G01X380905D02*
X714566D01*
G01X373031Y-97480D02*
G03X380905Y-105354I7874J0D01*
G01X373030Y-97480D02*
Y-20709D01*
G01Y-97480D02*
Y-20709D01*
G01Y-97480D02*
Y-20709D01*
G01Y-97480D02*
Y-20709D01*
G01X373031D02*
Y-97480D01*
G01X374999Y-18740D02*
G03X373030Y-20709I0J-1969D01*
G01X374999Y-18740D02*
G03X373030Y-20709I0J-1969D01*
G01X374999Y-18740D02*
G03X373030Y-20709I0J-1969D01*
G01X374999Y-18740D02*
G03X373030Y-20709I0J-1969D01*
G01X374999Y-18740D02*
G03X373030Y-20709I0J-1969D01*
G01X382873Y-18740D02*
G03X384841Y-16772I0J1968D01*
G01X382873Y-18740D02*
G03X384841Y-16772I0J1968D01*
G01X382873Y-18740D02*
G03X384841Y-16772I0J1968D01*
G01X382873Y-18740D02*
G03X384841Y-16772I0J1968D01*
G01D02*
Y38504D01*
G01Y-16772D02*
Y38504D01*
G01X374999Y-18740D02*
X382873D01*
G01X374999D02*
X382873D01*
G01X384841Y-16772D02*
Y38504D01*
G01Y-16772D02*
Y38504D01*
G01X374999Y-18740D02*
X382873D01*
G01X374999D02*
X382873D01*
G01D02*
X374999D01*
G01X382873D02*
G03X384841Y-16772I0J1968D01*
G01X384842Y38504D02*
Y-16772D01*
G01X373030Y42441D02*
G03X374999Y40472I1969J0D01*
G01X384841Y38504D02*
G03X382873Y40472I-1968J0D01*
G01X384841Y38504D02*
G03X382873Y40472I-1968J0D01*
G01X373030Y42441D02*
G03X374999Y40472I1969J0D01*
G01X384841Y38504D02*
G03X382873Y40472I-1968J0D01*
G01X384841Y38504D02*
G03X382873Y40472I-1968J0D01*
G01X373030Y42441D02*
G03X374999Y40472I1969J0D01*
G01X373030Y42441D02*
G03X374999Y40472I1969J0D01*
G01X373030Y42441D02*
Y62146D01*
G01Y42441D02*
Y62146D01*
G01X374999Y40472D02*
X382873D01*
G01X374999D02*
X382873D01*
G01X373030Y42441D02*
Y62146D01*
G01Y42441D02*
Y62146D01*
G01X374999Y40472D02*
X382873D01*
G01X374999D02*
X382873D01*
G01X373031Y42441D02*
G03X374999Y40473I1968J0D01*
G01X373031Y62146D02*
Y42441D01*
G01X384842Y38504D02*
G03X382873Y40473I-1969J0D01*
G01X374999D02*
X382873D01*
G01X384330Y59984D02*
X384418Y59953D01*
G01X384197Y59996D02*
X384330Y59984D01*
G01X384035Y60000D02*
X384197Y59996D01*
G01X384303Y58811D02*
X384111Y58818D01*
G01X384418Y58790D02*
X384303Y58811D01*
G01X384444Y58743D02*
X384448Y58758D01*
G01X384429Y58723D02*
X384444Y58743D01*
G01X384447Y59908D02*
X384448Y59902D01*
G01X384439Y59933D02*
X384447Y59908D01*
G01X384418Y59953D02*
X384439Y59933D01*
G01X384244Y58458D02*
X384429Y58723D01*
G01X384060Y58048D02*
X384244Y58458D01*
G01X383876Y57528D02*
X384060Y58048D01*
G01Y58766D02*
X383876Y57934D01*
G01X384244Y59423D02*
X384060Y58766D01*
G01X384429Y59847D02*
X384244Y59423D01*
G01X384439Y58777D02*
X384418Y58790D01*
G01X384447Y58761D02*
X384439Y58777D01*
G01X384448Y58758D02*
X384447Y58761D01*
G01X383865Y57490D02*
X383876Y57528D01*
G01X383859Y57451D02*
X383865Y57490D01*
G01X383857Y57411D02*
X383859Y57451D01*
G01X384444Y59880D02*
X384429Y59847D01*
G01X384448Y59902D02*
X384444Y59880D01*
G01X383859Y57811D02*
X383857Y57748D01*
G01X383865Y57873D02*
X383859Y57811D01*
G01X383876Y57934D02*
X383865Y57873D01*
G01X383857Y50984D02*
G03X385038Y49803I1181J0D01*
G01X374999Y64114D02*
G03X373030Y62146I0J-1969D01*
G01X374999Y64114D02*
G03X373030Y62146I0J-1969D01*
G01X374999Y64114D02*
G03X373030Y62146I0J-1969D01*
G01X374999Y64114D02*
G03X373030Y62146I0J-1969D01*
G01D02*
Y74173D01*
G01Y54488D02*
Y62146D01*
G01X379290Y58819D02*
Y60000D01*
G01X379330Y64114D02*
Y54488D01*
G01X379881Y58819D02*
Y60000D01*
G01X381180Y58819D02*
Y60000D01*
G01X381657D02*
Y58819D01*
G01X381742D02*
Y60000D01*
G01X381989D02*
Y58819D01*
G01X382993D02*
Y60000D01*
G01X383070D02*
Y58819D01*
G01X383267Y58780D02*
Y54488D01*
G01X383857Y57747D02*
Y50984D01*
G01Y60000D02*
Y58819D01*
G01X383876Y57528D02*
Y57934D01*
G01X384418Y59953D02*
Y58790D01*
G01X384429Y58723D02*
Y59847D01*
G01X384448Y58758D02*
Y59902D01*
G01X385117Y60000D02*
Y58819D01*
G01X385511D02*
Y60000D01*
G01X391337Y49803D02*
X385038D01*
G01X383267Y54488D02*
X373030D01*
G01X383857Y56850D02*
X392519D01*
G01X373030Y57598D02*
X383267D01*
G01X373030Y58189D02*
X383267D01*
G01Y58386D02*
X393109D01*
G01X373030Y58780D02*
X402952D01*
G01X397085Y58819D02*
X379290D01*
G01X397085Y60000D02*
X379290D01*
G01X402952Y60039D02*
X373030D01*
G01Y60630D02*
X402952D01*
G01X373030Y61220D02*
X402952D01*
G01X374999Y64114D02*
G03X373031Y62146I0J-1968D01*
G01X375076Y68465D02*
Y76219D01*
G01X374759Y69646D02*
X375076Y68465D01*
G01X379330Y65315D02*
Y64114D01*
G01X380904Y68465D02*
Y65315D01*
G01X375078Y76220D02*
X373030Y74173D01*
G01X374759Y69646D02*
X373030Y68647D01*
G01Y67283D02*
X375076Y68465D01*
G01X402952Y63346D02*
X373030D01*
G01X374999Y64114D02*
X401377D01*
G01X374999D02*
X401377D01*
G01X403186Y65315D02*
X373030D01*
G01X375076Y68465D02*
X399802D01*
G01X373030Y69646D02*
X399802D01*
G01X373030Y72402D02*
X399802D01*
G01X373030Y73583D02*
X399802D01*
G01X390353Y76220D02*
X375078D01*
G01X374999Y64114D02*
X401377D01*
G01X374999D02*
X401377D01*
G01D02*
X374999D01*
G01X375010Y94143D02*
X374999Y94208D01*
G01X375043Y94084D02*
X375010Y94143D01*
G01X375097Y94037D02*
X375043Y94084D01*
G01X376978Y89124D02*
X376967Y89059D01*
G01X377011Y89183D02*
X376978Y89124D01*
G01X377066Y89230D02*
X377011Y89183D01*
G01X376978Y92274D02*
X376967Y92209D01*
G01X377011Y92333D02*
X376978Y92274D01*
G01X377066Y92380D02*
X377011Y92333D01*
G01X377012Y90933D02*
X377066Y90888D01*
G01X376979Y90992D02*
X377012Y90933D01*
G01X376967Y91058D02*
X376979Y90992D01*
G01X377012Y87784D02*
X377066Y87738D01*
G01X376979Y87843D02*
X377012Y87784D01*
G01X376967Y87909D02*
X376979Y87843D01*
G01X375043Y95483D02*
X375097Y95529D01*
G01X375010Y95425D02*
X375043Y95483D01*
G01X374999Y95359D02*
X375010Y95425D01*
G01X375294Y93924D02*
G03X375393Y93898I98J171D01*
G01X375473Y88484D02*
G03X375335Y88428I0J-197D01*
G01Y85430D02*
G03X375473Y85374I138J141D01*
G01X375393Y95669D02*
G03X375294Y95643I-1J-197D01*
G01X377263Y90774D02*
G03X377361Y90748I98J171D01*
G01Y92520D02*
G03X377263Y92493I2J-197D01*
G01Y87625D02*
G03X377361Y87598I99J170D01*
G01Y89370D02*
G03X377263Y89344I0J-197D01*
G01X377870Y95363D02*
G03X377806Y95374I-65J-186D01*
G01X378041Y93543D02*
G03X377976Y93532I0J-197D01*
G01X377806Y93484D02*
G03X377870Y93495I-1J197D01*
G01X377441Y93484D02*
G03X377304Y93428I0J-197D01*
G01Y90430D02*
G03X377441Y90374I137J141D01*
G01X377870Y90363D02*
G03X377806Y90374I-65J-186D01*
G01X377976Y90326D02*
G03X378041Y90315I65J186D01*
G01X377806Y88484D02*
G03X377946Y88543I-1J197D01*
G01Y85315D02*
G03X377806Y85374I-141J-138D01*
G01X377304Y95430D02*
G03X377441Y95374I137J141D01*
G01X377976Y95326D02*
G03X378041Y95315I65J186D01*
G01X373030Y214055D02*
Y84803D01*
G01X374211Y215236D02*
Y83622D01*
G01X374999Y95359D02*
Y94208D01*
G01X375156Y85605D02*
Y88253D01*
G01X375266Y95626D02*
Y93940D01*
G01X375370Y93899D02*
Y95668D01*
G01X375703Y85374D02*
Y88484D01*
G01X375879D02*
Y85374D01*
G01X376967Y91058D02*
Y92209D01*
G01Y87909D02*
Y89059D01*
G01X377125Y95605D02*
Y98253D01*
G01Y90605D02*
Y93253D01*
G01X377234Y89327D02*
Y87641D01*
G01Y92477D02*
Y90791D01*
G01X377339Y90749D02*
Y92518D01*
G01Y87600D02*
Y89369D01*
G01X377672Y93484D02*
Y90374D01*
G01Y98484D02*
Y95374D01*
G01X377848Y95369D02*
Y98489D01*
G01Y90369D02*
Y93489D01*
G01X377304Y93428D02*
X377125Y93253D01*
G01X375335Y88428D02*
X375156Y88253D01*
G01X374211Y83622D02*
X373030Y84803D01*
G01X375156Y85605D02*
X375335Y85430D01*
G01X377125Y90605D02*
X377304Y90430D01*
G01X377125Y95605D02*
X377304Y95430D01*
G01X375294Y95643D02*
X375097Y95529D01*
G01X377263Y92493D02*
X377066Y92380D01*
G01X377263Y89344D02*
X377066Y89230D01*
G01X377263Y87625D02*
X377066Y87738D01*
G01X377263Y90774D02*
X377066Y90888D01*
G01X375097Y94037D02*
X375294Y93924D01*
G01X377870Y93495D02*
X377976Y93532D01*
G01Y90326D02*
X377870Y90363D01*
G01X377976Y95326D02*
X377870Y95363D01*
G01X403159Y83622D02*
X374211D01*
G01X387516Y85315D02*
X377946D01*
G01X377806Y85374D02*
X375473D01*
G01X377361Y87598D02*
X388913D01*
G01X375473Y88484D02*
X377806D01*
G01X377946Y88543D02*
X387516D01*
G01X377361Y89370D02*
X387814D01*
G01X387516Y90315D02*
X378041D01*
G01X377806Y90374D02*
X377441D01*
G01X388913Y90748D02*
X377361D01*
G01Y92520D02*
X387814D01*
G01X377441Y93484D02*
X377806D01*
G01X378041Y93543D02*
X387516D01*
G01X388995Y93898D02*
X375393D01*
G01X387516Y95315D02*
X378041D01*
G01X377806Y95374D02*
X377441D01*
G01X375393Y95669D02*
X387814D01*
G01X375010Y103592D02*
X374999Y103657D01*
G01X375043Y103533D02*
X375010Y103592D01*
G01X375097Y103486D02*
X375043Y103533D01*
G01X376978Y98573D02*
X376967Y98508D01*
G01X377011Y98632D02*
X376978Y98573D01*
G01X377066Y98679D02*
X377011Y98632D01*
G01X376978Y101723D02*
X376967Y101658D01*
G01X377011Y101782D02*
X376978Y101723D01*
G01X377066Y101828D02*
X377011Y101782D01*
G01X376978Y108022D02*
X376967Y107957D01*
G01X377011Y108081D02*
X376978Y108022D01*
G01X377066Y108128D02*
X377011Y108081D01*
G01X376978Y111172D02*
X376967Y111107D01*
G01X377011Y111231D02*
X376978Y111172D01*
G01X377066Y111277D02*
X377011Y111231D01*
G01X377012Y109831D02*
X377066Y109785D01*
G01X376979Y109890D02*
X377012Y109831D01*
G01X376967Y109956D02*
X376979Y109890D01*
G01X377012Y106682D02*
X377066Y106636D01*
G01X376979Y106740D02*
X377012Y106682D01*
G01X376967Y106806D02*
X376979Y106740D01*
G01X377012Y100382D02*
X377066Y100337D01*
G01X376979Y100441D02*
X377012Y100382D01*
G01X376967Y100507D02*
X376979Y100441D01*
G01X377012Y97233D02*
X377066Y97187D01*
G01X376979Y97291D02*
X377012Y97233D01*
G01X376967Y97358D02*
X376979Y97291D01*
G01X375043Y104932D02*
X375097Y104978D01*
G01X375010Y104874D02*
X375043Y104932D01*
G01X374999Y104808D02*
X375010Y104874D01*
G01X375294Y103373D02*
G03X375393Y103346I100J170D01*
G01Y105118D02*
G03X375294Y105092I-1J-197D01*
G01X375473Y103484D02*
G03X375335Y103428I0J-197D01*
G01Y100430D02*
G03X375473Y100374I138J141D01*
G01X377263Y100223D02*
G03X377361Y100197I98J171D01*
G01Y101969D02*
G03X377263Y101942I2J-197D01*
G01Y97074D02*
G03X377361Y97047I99J170D01*
G01Y98819D02*
G03X377263Y98793I0J-197D01*
G01X377870Y105363D02*
G03X377806Y105374I-65J-186D01*
G01Y103484D02*
G03X377946Y103543I-1J197D01*
G01Y100315D02*
G03X377806Y100374I-141J-138D01*
G01X378041Y98543D02*
G03X377976Y98532I0J-197D01*
G01X377806Y98484D02*
G03X377870Y98495I-1J197D01*
G01X377441Y98484D02*
G03X377304Y98428I0J-197D01*
G01X377263Y109672D02*
G03X377361Y109646I98J171D01*
G01Y111417D02*
G03X377263Y111391I0J-197D01*
G01Y106522D02*
G03X377361Y106496I98J171D01*
G01Y108268D02*
G03X377263Y108241I2J-197D01*
G01X377304Y110430D02*
G03X377441Y110374I137J141D01*
G01X377870Y110363D02*
G03X377806Y110374I-65J-186D01*
G01X377976Y110326D02*
G03X378041Y110315I65J186D01*
G01Y108543D02*
G03X377976Y108532I0J-197D01*
G01X377806Y108484D02*
G03X377870Y108495I-1J197D01*
G01X377441Y108484D02*
G03X377304Y108428I0J-197D01*
G01Y105430D02*
G03X377441Y105374I137J141D01*
G01X377976Y105326D02*
G03X378041Y105315I65J186D01*
G01X374999Y104808D02*
Y103657D01*
G01X375156Y100605D02*
Y103253D01*
G01X375266Y105075D02*
Y103389D01*
G01X375370Y103348D02*
Y105117D01*
G01X375703Y100374D02*
Y103484D01*
G01X375879D02*
Y100374D01*
G01X376967Y109956D02*
Y111107D01*
G01Y106806D02*
Y107957D01*
G01Y100507D02*
Y101658D01*
G01Y97358D02*
Y98508D01*
G01X377125Y110605D02*
Y113253D01*
G01Y105605D02*
Y108253D01*
G01X377234Y98776D02*
Y97090D01*
G01Y101926D02*
Y100239D01*
G01Y108225D02*
Y106539D01*
G01Y111374D02*
Y109688D01*
G01X377339Y109647D02*
Y111416D01*
G01Y106497D02*
Y108266D01*
G01Y100198D02*
Y101967D01*
G01Y97048D02*
Y98817D01*
G01X377672Y108484D02*
Y105374D01*
G01Y113484D02*
Y110374D01*
G01X377848Y110369D02*
Y113489D01*
G01Y105369D02*
Y108489D01*
G01X377304Y108428D02*
X377125Y108253D01*
G01X375335Y103428D02*
X375156Y103253D01*
G01X377304Y98428D02*
X377125Y98253D01*
G01X375156Y100605D02*
X375335Y100430D01*
G01X377263Y111391D02*
X377066Y111277D01*
G01X377263Y108241D02*
X377066Y108128D01*
G01X375294Y105092D02*
X375097Y104978D01*
G01X377263Y101942D02*
X377066Y101828D01*
G01X377263Y98793D02*
X377066Y98679D01*
G01X377125Y105605D02*
X377304Y105430D01*
G01X377125Y110605D02*
X377304Y110430D01*
G01X377870Y108495D02*
X377976Y108532D01*
G01X377870Y98495D02*
X377976Y98532D01*
G01X377263Y97074D02*
X377066Y97187D01*
G01X377263Y100223D02*
X377066Y100337D01*
G01X375097Y103486D02*
X375294Y103373D01*
G01X377263Y106522D02*
X377066Y106636D01*
G01X377263Y109672D02*
X377066Y109785D01*
G01X377976Y105326D02*
X377870Y105363D01*
G01X377976Y110326D02*
X377870Y110363D01*
G01X388913Y97047D02*
X377361D01*
G01X377441Y98484D02*
X377806D01*
G01X378041Y98543D02*
X387516D01*
G01X377361Y98819D02*
X387814D01*
G01X388913Y100197D02*
X377361D01*
G01X387516Y100315D02*
X377946D01*
G01X377806Y100374D02*
X375473D01*
G01X377361Y101969D02*
X387814D01*
G01X388995Y103346D02*
X375393D01*
G01X375473Y103484D02*
X377806D01*
G01X377946Y103543D02*
X387516D01*
G01X375393Y105118D02*
X387814D01*
G01X387516Y105315D02*
X378041D01*
G01X377806Y105374D02*
X377441D01*
G01X388913Y106496D02*
X377361D01*
G01Y108268D02*
X387814D01*
G01X377441Y108484D02*
X377806D01*
G01X378041Y108543D02*
X387516D01*
G01X388913Y109646D02*
X377361D01*
G01X387516Y110315D02*
X378041D01*
G01X377806Y110374D02*
X377441D01*
G01X377361Y111417D02*
X387814D01*
G01X375043Y128730D02*
X375010Y128789D01*
G01X375097Y128683D02*
X375043Y128730D01*
G01X375010Y119340D02*
X374999Y119405D01*
G01X375043Y119281D02*
X375010Y119340D01*
G01X375097Y119234D02*
X375043Y119281D01*
G01X375010Y113041D02*
X374999Y113106D01*
G01X375043Y112982D02*
X375010Y113041D01*
G01X375097Y112935D02*
X375043Y112982D01*
G01X376978Y117471D02*
X376967Y117406D01*
G01X377011Y117530D02*
X376978Y117471D01*
G01X377066Y117576D02*
X377011Y117530D01*
G01X376978Y123770D02*
X376967Y123705D01*
G01X377011Y123829D02*
X376978Y123770D01*
G01X377066Y123876D02*
X377011Y123829D01*
G01X376978Y126920D02*
X376967Y126855D01*
G01X377011Y126979D02*
X376978Y126920D01*
G01X377066Y127025D02*
X377011Y126979D01*
G01X376979Y122296D02*
X376967Y122229D01*
G01X377013Y122355D02*
X376979Y122296D01*
G01X377066Y122399D02*
X377013Y122355D01*
G01X376979Y125446D02*
X376967Y125378D01*
G01X377013Y125505D02*
X376979Y125446D01*
G01X377066Y125549D02*
X377013Y125505D01*
G01X375011Y128595D02*
X374999Y128528D01*
G01X375045Y128654D02*
X375011Y128595D01*
G01X375097Y128698D02*
X375045Y128654D01*
G01X377013Y124101D02*
X377066Y124057D01*
G01X376979Y124160D02*
X377013Y124101D01*
G01X376967Y124228D02*
X376979Y124160D01*
G01X377013Y120952D02*
X377066Y120908D01*
G01X376979Y121011D02*
X377013Y120952D01*
G01X376967Y121078D02*
X376979Y121011D01*
G01X375045Y127251D02*
X375097Y127207D01*
G01X375011Y127310D02*
X375045Y127251D01*
G01X374999Y127377D02*
X375011Y127310D01*
G01X377012Y125579D02*
X377066Y125533D01*
G01X376979Y125638D02*
X377012Y125579D01*
G01X376967Y125704D02*
X376979Y125638D01*
G01X377012Y122430D02*
X377066Y122384D01*
G01X376979Y122488D02*
X377012Y122430D01*
G01X376967Y122554D02*
X376979Y122488D01*
G01X377012Y116130D02*
X377066Y116085D01*
G01X376979Y116189D02*
X377012Y116130D01*
G01X376967Y116255D02*
X376979Y116189D01*
G01X375043Y114381D02*
X375097Y114427D01*
G01X375010Y114322D02*
X375043Y114381D01*
G01X374999Y114256D02*
X375010Y114322D01*
G01X375043Y120680D02*
X375097Y120726D01*
G01X375010Y120622D02*
X375043Y120680D01*
G01X374999Y120556D02*
X375010Y120622D01*
G01X375294Y112822D02*
G03X375393Y112795I99J170D01*
G01Y114567D02*
G03X375294Y114541I-1J-197D01*
G01Y119121D02*
G03X375393Y119095I98J171D01*
G01Y120866D02*
G03X375294Y120840I-1J-197D01*
G01X375473Y118484D02*
G03X375335Y118428I0J-197D01*
G01Y115430D02*
G03X375473Y115374I138J141D01*
G01X377946Y115315D02*
G03X377806Y115374I-141J-138D01*
G01X378041Y113543D02*
G03X377976Y113532I0J-197D01*
G01X377806Y113484D02*
G03X377870Y113495I-1J197D01*
G01X377441Y113484D02*
G03X377304Y113428I0J-197D01*
G01X377361Y124016D02*
G03X377263Y123989I2J-197D01*
G01Y122270D02*
G03X377361Y122244I98J171D01*
G01X377263Y115971D02*
G03X377361Y115945I98J171D01*
G01Y117717D02*
G03X377263Y117690I2J-197D01*
G01X377361Y125689D02*
G03X377263Y125663I0J-197D01*
G01Y123944D02*
G03X377361Y123917I99J170D01*
G01Y122539D02*
G03X377263Y122513I0J-197D01*
G01Y120794D02*
G03X377361Y120768I98J171D01*
G01X377806Y118484D02*
G03X377946Y118543I-1J197D01*
G01X375294Y128570D02*
G03X375393Y128543I99J170D01*
G01X375294Y127093D02*
G03X375393Y127067I98J171D01*
G01X377361Y127165D02*
G03X377263Y127139I0J-197D01*
G01Y125420D02*
G03X377361Y125394I98J171D01*
G01X374605Y119882D02*
Y138976D01*
G01X374999Y114256D02*
Y113106D01*
G01Y120556D02*
Y119405D01*
G01Y127377D02*
Y128528D01*
G01X375156Y115605D02*
Y118253D01*
G01X375266Y114524D02*
Y112838D01*
G01Y120823D02*
Y119137D01*
G01Y130272D02*
Y128586D01*
G01D02*
Y127109D01*
G01X375370Y128545D02*
Y130313D01*
G01Y127068D02*
Y128545D01*
G01Y119096D02*
Y120865D01*
G01Y112796D02*
Y114565D01*
G01X375703Y115374D02*
Y118484D01*
G01X375879D02*
Y115374D01*
G01X376967Y125704D02*
Y126855D01*
G01Y122554D02*
Y123705D01*
G01Y124228D02*
Y125378D01*
G01Y121078D02*
Y122229D01*
G01Y116255D02*
Y117406D01*
G01X377234Y117674D02*
Y115987D01*
G01Y123973D02*
Y122287D01*
G01Y127122D02*
Y125436D01*
G01Y123973D02*
Y125436D01*
G01Y120810D02*
Y122287D01*
G01X377339Y122245D02*
Y120769D01*
G01Y125395D02*
Y124014D01*
G01Y125395D02*
Y127164D01*
G01Y122245D02*
Y124014D01*
G01Y115946D02*
Y117715D01*
G01X375335Y118428D02*
X375156Y118253D01*
G01X377304Y113428D02*
X377125Y113253D01*
G01X375294Y128812D02*
X375097Y128698D01*
G01X377263Y127139D02*
X377066Y127025D01*
G01X377263Y125663D02*
X377066Y125549D01*
G01X377263Y123989D02*
X377066Y123876D01*
G01X377263Y122513D02*
X377066Y122399D01*
G01X375294Y120840D02*
X375097Y120726D01*
G01X377263Y117690D02*
X377066Y117576D01*
G01X375294Y114541D02*
X375097Y114427D01*
G01X373030Y121457D02*
X374605Y119882D01*
G01X375156Y115605D02*
X375335Y115430D01*
G01X377870Y113495D02*
X377976Y113532D01*
G01X375097Y112935D02*
X375294Y112822D01*
G01X377263Y115971D02*
X377066Y116085D01*
G01X375097Y119234D02*
X375294Y119121D01*
G01X377066Y120908D02*
X377263Y120794D01*
G01Y122270D02*
X377066Y122384D01*
G01Y124057D02*
X377263Y123944D01*
G01Y125420D02*
X377066Y125533D01*
G01X375097Y127207D02*
X375294Y127093D01*
G01X375097Y128683D02*
X375294Y128570D01*
G01X388995Y112795D02*
X375393D01*
G01X377441Y113484D02*
X377806D01*
G01X378041Y113543D02*
X387516D01*
G01X375393Y114567D02*
X387814D01*
G01X387516Y115315D02*
X377946D01*
G01X377806Y115374D02*
X375473D01*
G01X388913Y115945D02*
X377361D01*
G01Y117717D02*
X387814D01*
G01X375473Y118484D02*
X377806D01*
G01X377946Y118543D02*
X387516D01*
G01X388995Y119095D02*
X375393D01*
G01X392322Y119882D02*
X374605D01*
G01X392269Y120768D02*
X377361D01*
G01X375393Y120866D02*
X387814D01*
G01X388913Y122244D02*
X377361D01*
G01Y122539D02*
X392269D01*
G01Y123917D02*
X377361D01*
G01Y124016D02*
X387814D01*
G01X388913Y125394D02*
X377361D01*
G01Y125689D02*
X392269D01*
G01Y127067D02*
X375393D01*
G01X377361Y127165D02*
X387814D01*
G01X388995Y128543D02*
X375393D01*
G01X375010Y144537D02*
X374999Y144602D01*
G01X375043Y144478D02*
X375010Y144537D01*
G01X375097Y144431D02*
X375043Y144478D01*
G01X375010Y138237D02*
X374999Y138302D01*
G01X375043Y138179D02*
X375010Y138237D01*
G01X375097Y138132D02*
X375043Y138179D01*
G01X375010Y128789D02*
X374999Y128854D01*
G01X376979Y131745D02*
X376967Y131678D01*
G01X377013Y131804D02*
X376979Y131745D01*
G01X377066Y131848D02*
X377013Y131804D01*
G01X376978Y133219D02*
X376967Y133154D01*
G01X377011Y133278D02*
X376978Y133219D01*
G01X377066Y133324D02*
X377011Y133278D01*
G01X376978Y136369D02*
X376967Y136304D01*
G01X377011Y136428D02*
X376978Y136369D01*
G01X377066Y136474D02*
X377011Y136428D01*
G01X376978Y142668D02*
X376967Y142603D01*
G01X377011Y142727D02*
X376978Y142668D01*
G01X377066Y142773D02*
X377011Y142727D01*
G01X376979Y134895D02*
X376967Y134827D01*
G01X377013Y134954D02*
X376979Y134895D01*
G01X377066Y134998D02*
X377013Y134954D01*
G01X375011Y138044D02*
X374999Y137977D01*
G01X375045Y138103D02*
X375011Y138044D01*
G01X375097Y138147D02*
X375045Y138103D01*
G01X377013Y133550D02*
X377066Y133506D01*
G01X376979Y133609D02*
X377013Y133550D01*
G01X376967Y133676D02*
X376979Y133609D01*
G01X377013Y130400D02*
X377066Y130356D01*
G01X376979Y130459D02*
X377013Y130400D01*
G01X376967Y130527D02*
X376979Y130459D01*
G01X375045Y136700D02*
X375097Y136656D01*
G01X375011Y136759D02*
X375045Y136700D01*
G01X374999Y136826D02*
X375011Y136759D01*
G01X377012Y141327D02*
X377066Y141282D01*
G01X376979Y141386D02*
X377012Y141327D01*
G01X376967Y141452D02*
X376979Y141386D01*
G01X377012Y135028D02*
X377066Y134982D01*
G01X376979Y135087D02*
X377012Y135028D01*
G01X376967Y135153D02*
X376979Y135087D01*
G01X377012Y131878D02*
X377066Y131833D01*
G01X376979Y131937D02*
X377012Y131878D01*
G01X376967Y132003D02*
X376979Y131937D01*
G01X375043Y130129D02*
X375097Y130175D01*
G01X375010Y130070D02*
X375043Y130129D01*
G01X374999Y130004D02*
X375010Y130070D01*
G01X375043Y139578D02*
X375097Y139624D01*
G01X375010Y139519D02*
X375043Y139578D01*
G01X374999Y139453D02*
X375010Y139519D01*
G01X375393Y130315D02*
G03X375294Y130289I-1J-197D01*
G01X375393Y128839D02*
G03X375294Y128812I1J-197D01*
G01X375393Y139764D02*
G03X375294Y139737I1J-197D01*
G01Y138019D02*
G03X375393Y137992I99J170D01*
G01X375294Y144318D02*
G03X375393Y144291I99J170D01*
G01Y138287D02*
G03X375294Y138261I-1J-197D01*
G01Y136542D02*
G03X375393Y136516I98J171D01*
G01X377361Y133465D02*
G03X377263Y133438I2J-197D01*
G01Y131719D02*
G03X377361Y131693I98J171D01*
G01X377263Y134869D02*
G03X377361Y134843I98J170D01*
G01Y135138D02*
G03X377263Y135111I1J-197D01*
G01Y133393D02*
G03X377361Y133366I99J169D01*
G01Y131988D02*
G03X377263Y131962I0J-197D01*
G01Y130243D02*
G03X377361Y130217I98J170D01*
G01Y136614D02*
G03X377263Y136588I0J-197D01*
G01X377361Y142913D02*
G03X377263Y142887I0J-197D01*
G01Y141168D02*
G03X377361Y141142I98J171D01*
G01X378041Y143543D02*
G03X377976Y143532I0J-197D01*
G01X377806Y143484D02*
G03X377870Y143495I-1J197D01*
G01X377441Y143484D02*
G03X377304Y143428I0J-197D01*
G01Y140430D02*
G03X377441Y140374I137J141D01*
G01X377870Y140363D02*
G03X377806Y140374I-65J-186D01*
G01X377976Y140326D02*
G03X378041Y140315I65J186D01*
G01X374999Y130004D02*
Y128854D01*
G01Y139453D02*
Y138302D01*
G01Y145752D02*
Y144602D01*
G01Y136826D02*
Y137977D01*
G01X375266Y139721D02*
Y138035D01*
G01D02*
Y136558D01*
G01Y146020D02*
Y144334D01*
G01X375370Y137993D02*
Y136517D01*
G01Y144293D02*
Y146061D01*
G01Y137993D02*
Y139762D01*
G01X376967Y141452D02*
Y142603D01*
G01Y135153D02*
Y136304D01*
G01Y132003D02*
Y133154D01*
G01Y133676D02*
Y134827D01*
G01Y130527D02*
Y131678D01*
G01X377125Y140605D02*
Y143253D01*
G01X377234Y133422D02*
Y131735D01*
G01Y136571D02*
Y134885D01*
G01Y142870D02*
Y141184D01*
G01Y133422D02*
Y134885D01*
G01Y130259D02*
Y131735D01*
G01X377339Y131694D02*
Y130218D01*
G01Y134844D02*
Y133463D01*
G01Y141143D02*
Y142912D01*
G01Y134844D02*
Y136613D01*
G01Y131694D02*
Y133463D01*
G01X377304Y143428D02*
X377125Y143253D01*
G01X374605Y138976D02*
X373030Y137402D01*
G01X377672Y143484D02*
Y140374D01*
G01X377848Y140369D02*
Y143489D01*
G01X377263Y142887D02*
X377066Y142773D01*
G01X375294Y139737D02*
X375097Y139624D01*
G01X375294Y138261D02*
X375097Y138147D01*
G01X377263Y136588D02*
X377066Y136474D01*
G01X377263Y135111D02*
X377066Y134998D01*
G01X377263Y133438D02*
X377066Y133324D01*
G01X377263Y131962D02*
X377066Y131848D01*
G01X375294Y130289D02*
X375097Y130175D01*
G01X377870Y143495D02*
X377976Y143532D01*
G01X377125Y140605D02*
X377304Y140430D01*
G01X377066Y130356D02*
X377263Y130243D01*
G01Y131719D02*
X377066Y131833D01*
G01Y133506D02*
X377263Y133393D01*
G01Y134869D02*
X377066Y134982D01*
G01X375097Y136656D02*
X375294Y136542D01*
G01X375097Y138132D02*
X375294Y138019D01*
G01X377263Y141168D02*
X377066Y141282D01*
G01X375097Y144431D02*
X375294Y144318D01*
G01X377976Y140326D02*
X377870Y140363D01*
G01X375393Y128839D02*
X392269D01*
G01Y130217D02*
X377361D01*
G01X375393Y130315D02*
X387814D01*
G01X388913Y131693D02*
X377361D01*
G01Y131988D02*
X392269D01*
G01Y133366D02*
X377361D01*
G01Y133465D02*
X387814D01*
G01X388913Y134843D02*
X377361D01*
G01Y135138D02*
X392269D01*
G01Y136516D02*
X375393D01*
G01X377361Y136614D02*
X387814D01*
G01X388995Y137992D02*
X375393D01*
G01Y138287D02*
X392269D01*
G01X374605Y138976D02*
X392322D01*
G01X375393Y139764D02*
X387814D01*
G01X387516Y140315D02*
X378041D01*
G01X377806Y140374D02*
X377441D01*
G01X388913Y141142D02*
X377361D01*
G01Y142913D02*
X387814D01*
G01X377441Y143484D02*
X377806D01*
G01X378041Y143543D02*
X387516D01*
G01X388995Y144291D02*
X375393D01*
G01X375010Y153985D02*
X374999Y154050D01*
G01X375043Y153927D02*
X375010Y153985D01*
G01X375097Y153880D02*
X375043Y153927D01*
G01X376978Y148967D02*
X376967Y148902D01*
G01X377011Y149026D02*
X376978Y148967D01*
G01X377066Y149072D02*
X377011Y149026D01*
G01X376978Y152117D02*
X376967Y152052D01*
G01X377011Y152176D02*
X376978Y152117D01*
G01X377066Y152222D02*
X377011Y152176D01*
G01X377012Y160225D02*
X377066Y160179D01*
G01X376979Y160283D02*
X377012Y160225D01*
G01X376967Y160350D02*
X376979Y160283D01*
G01X377012Y157075D02*
X377066Y157030D01*
G01X376979Y157134D02*
X377012Y157075D01*
G01X376967Y157200D02*
X376979Y157134D01*
G01X377012Y150776D02*
X377066Y150730D01*
G01X376979Y150835D02*
X377012Y150776D01*
G01X376967Y150901D02*
X376979Y150835D01*
G01X377012Y147626D02*
X377066Y147581D01*
G01X376979Y147685D02*
X377012Y147626D01*
G01X376967Y147751D02*
X376979Y147685D01*
G01X375043Y145877D02*
X375097Y145923D01*
G01X375010Y145819D02*
X375043Y145877D01*
G01X374999Y145752D02*
X375010Y145819D01*
G01X375043Y155326D02*
X375097Y155372D01*
G01X375010Y155267D02*
X375043Y155326D01*
G01X374999Y155201D02*
X375010Y155267D01*
G01X376978Y158416D02*
X376967Y158351D01*
G01X377011Y158475D02*
X376978Y158416D01*
G01X377066Y158521D02*
X377011Y158475D01*
G01X376978Y161565D02*
X376967Y161500D01*
G01X377011Y161624D02*
X376978Y161565D01*
G01X377066Y161671D02*
X377011Y161624D01*
G01X375393Y146063D02*
G03X375294Y146037I-1J-197D01*
G01X377304Y145430D02*
G03X377441Y145374I137J141D01*
G01X377870Y145363D02*
G03X377806Y145374I-65J-186D01*
G01X377976Y145326D02*
G03X378041Y145315I65J186D01*
G01X375393Y155512D02*
G03X375294Y155485I1J-197D01*
G01Y153767D02*
G03X375393Y153740I99J170D01*
G01X375335Y155430D02*
G03X375473Y155374I138J141D01*
G01Y153484D02*
G03X375335Y153428I0J-197D01*
G01Y150430D02*
G03X375473Y150374I138J141D01*
G01X375335Y160430D02*
G03X375473Y160374I138J141D01*
G01Y158484D02*
G03X375335Y158428I0J-197D01*
G01X377361Y149213D02*
G03X377263Y149186I2J-197D01*
G01Y147467D02*
G03X377361Y147441I98J171D01*
G01Y152362D02*
G03X377263Y152336I0J-197D01*
G01Y150617D02*
G03X377361Y150591I98J170D01*
G01X377263Y156916D02*
G03X377361Y156890I98J171D01*
G01X378041Y148543D02*
G03X377976Y148532I0J-197D01*
G01X377806Y148484D02*
G03X377870Y148495I-1J197D01*
G01X377441Y148484D02*
G03X377304Y148428I0J-197D01*
G01X377946Y155315D02*
G03X377806Y155374I-141J-138D01*
G01Y153484D02*
G03X377946Y153543I-1J197D01*
G01Y150315D02*
G03X377806Y150374I-141J-138D01*
G01X377361Y158661D02*
G03X377263Y158635I0J-197D01*
G01Y160066D02*
G03X377361Y160039I99J170D01*
G01X377946Y160315D02*
G03X377806Y160374I-141J-138D01*
G01Y158484D02*
G03X377946Y158543I-1J197D01*
G01X375335Y158428D02*
X375156Y158253D01*
G01X375335Y153428D02*
X375156Y153253D01*
G01X377304Y148428D02*
X377125Y148253D01*
G01X374999Y155201D02*
Y154050D01*
G01X375156Y160605D02*
Y163253D01*
G01Y155605D02*
Y158253D01*
G01Y150605D02*
Y153253D01*
G01X375266Y155469D02*
Y153783D01*
G01X375370Y153741D02*
Y155510D01*
G01X375703Y153484D02*
Y150374D01*
G01Y158484D02*
Y155374D01*
G01Y163484D02*
Y160374D01*
G01X375879Y153484D02*
Y150374D01*
G01Y158484D02*
Y155374D01*
G01Y163484D02*
Y160374D01*
G01X376967Y160350D02*
Y161500D01*
G01Y157200D02*
Y158351D01*
G01Y150901D02*
Y152052D01*
G01Y147751D02*
Y148902D01*
G01X377125Y145605D02*
Y148253D01*
G01X377234Y149170D02*
Y147483D01*
G01Y152319D02*
Y150633D01*
G01Y158619D02*
Y156932D01*
G01Y161768D02*
Y160082D01*
G01X377339Y160041D02*
Y161809D01*
G01Y156891D02*
Y158660D01*
G01Y150592D02*
Y152361D01*
G01Y147442D02*
Y149211D01*
G01X377263Y161785D02*
X377066Y161671D01*
G01X377263Y158635D02*
X377066Y158521D01*
G01X375294Y155485D02*
X375097Y155372D01*
G01X377672Y148484D02*
Y145374D01*
G01X377848Y145369D02*
Y148489D01*
G01X377263Y152336D02*
X377066Y152222D01*
G01X377263Y149186D02*
X377066Y149072D01*
G01X375294Y146037D02*
X375097Y145923D01*
G01X377870Y148495D02*
X377976Y148532D01*
G01X377125Y145605D02*
X377304Y145430D01*
G01X375156Y150605D02*
X375335Y150430D01*
G01X375156Y155605D02*
X375335Y155430D01*
G01X375156Y160605D02*
X375335Y160430D01*
G01X377263Y147467D02*
X377066Y147581D01*
G01X377263Y150617D02*
X377066Y150730D01*
G01X375097Y153880D02*
X375294Y153767D01*
G01X377263Y156916D02*
X377066Y157030D01*
G01X377263Y160066D02*
X377066Y160179D01*
G01X377976Y145326D02*
X377870Y145363D01*
G01X387516Y145315D02*
X378041D01*
G01X377806Y145374D02*
X377441D01*
G01X375393Y146063D02*
X387814D01*
G01X388913Y147441D02*
X377361D01*
G01X377441Y148484D02*
X377806D01*
G01X378041Y148543D02*
X387516D01*
G01X377361Y149213D02*
X387814D01*
G01X387516Y150315D02*
X377946D01*
G01X377806Y150374D02*
X375473D01*
G01X388913Y150591D02*
X377361D01*
G01Y152362D02*
X387814D01*
G01X375473Y153484D02*
X377806D01*
G01X377946Y153543D02*
X387516D01*
G01X388995Y153740D02*
X375393D01*
G01X387516Y155315D02*
X377946D01*
G01X377806Y155374D02*
X375473D01*
G01X375393Y155512D02*
X387814D01*
G01X388913Y156890D02*
X377361D01*
G01X375473Y158484D02*
X377806D01*
G01X377946Y158543D02*
X387516D01*
G01X377361Y158661D02*
X387814D01*
G01X388913Y160039D02*
X377361D01*
G01X387516Y160315D02*
X377946D01*
G01X377806Y160374D02*
X375473D01*
G01X375010Y172883D02*
X374999Y172948D01*
G01X375043Y172824D02*
X375010Y172883D01*
G01X375097Y172778D02*
X375043Y172824D01*
G01X375010Y163434D02*
X374999Y163499D01*
G01X375043Y163376D02*
X375010Y163434D01*
G01X375097Y163329D02*
X375043Y163376D01*
G01X377012Y175973D02*
X377066Y175927D01*
G01X376979Y176032D02*
X377012Y175973D01*
G01X376967Y176098D02*
X376979Y176032D01*
G01X377012Y169674D02*
X377066Y169628D01*
G01X376979Y169732D02*
X377012Y169674D01*
G01X376967Y169798D02*
X376979Y169732D01*
G01X377012Y166524D02*
X377066Y166478D01*
G01X376979Y166583D02*
X377012Y166524D01*
G01X376967Y166649D02*
X376979Y166583D01*
G01X375043Y164775D02*
X375097Y164820D01*
G01X375010Y164716D02*
X375043Y164775D01*
G01X374999Y164650D02*
X375010Y164716D01*
G01X375043Y174224D02*
X375097Y174269D01*
G01X375010Y174165D02*
X375043Y174224D01*
G01X374999Y174099D02*
X375010Y174165D01*
G01X376978Y167865D02*
X376967Y167800D01*
G01X377011Y167924D02*
X376978Y167865D01*
G01X377066Y167970D02*
X377011Y167924D01*
G01X376978Y171014D02*
X376967Y170949D01*
G01X377011Y171073D02*
X376978Y171014D01*
G01X377066Y171120D02*
X377011Y171073D01*
G01X376978Y177313D02*
X376967Y177248D01*
G01X377011Y177372D02*
X376978Y177313D01*
G01X377066Y177419D02*
X377011Y177372D01*
G01X375393Y164961D02*
G03X375294Y164934I1J-197D01*
G01Y163215D02*
G03X375393Y163189I98J171D01*
G01X375473Y168484D02*
G03X375335Y168428I0J-197D01*
G01Y165430D02*
G03X375473Y165374I138J141D01*
G01Y163484D02*
G03X375335Y163428I0J-197D01*
G01X377361Y161811D02*
G03X377263Y161785I0J-197D01*
G01X377361Y168110D02*
G03X377263Y168084I0J-197D01*
G01Y166365D02*
G03X377361Y166339I98J171D01*
G01X377806Y168484D02*
G03X377946Y168543I-1J197D01*
G01Y165315D02*
G03X377806Y165374I-141J-138D01*
G01Y163484D02*
G03X377946Y163543I-1J197D01*
G01X377361Y171260D02*
G03X377263Y171233I1J-197D01*
G01Y169515D02*
G03X377361Y169488I99J170D01*
G01X375393Y174409D02*
G03X375294Y174383I-1J-197D01*
G01Y172664D02*
G03X375393Y172638I98J171D01*
G01X377361Y177559D02*
G03X377263Y177533I0J-197D01*
G01Y175814D02*
G03X377361Y175787I99J170D01*
G01X377304Y175430D02*
G03X377441Y175374I137J141D01*
G01X377870Y175363D02*
G03X377806Y175374I-65J-186D01*
G01X377976Y175326D02*
G03X378041Y175315I65J186D01*
G01X377806Y173484D02*
G03X377946Y173543I-1J197D01*
G01X375473Y173484D02*
G03X375335Y173428I0J-197D01*
G01Y170430D02*
G03X375473Y170374I138J141D01*
G01X377946Y170315D02*
G03X377806Y170374I-141J-138D01*
G01X377304Y178428D02*
X377125Y178253D01*
G01X375335Y173428D02*
X375156Y173253D01*
G01X377263Y177533D02*
X377066Y177419D01*
G01X375294Y174383D02*
X375097Y174269D01*
G01X375335Y168428D02*
X375156Y168253D01*
G01X375335Y163428D02*
X375156Y163253D01*
G01X374999Y164650D02*
Y163499D01*
G01Y174099D02*
Y172948D01*
G01X375156Y170605D02*
Y173253D01*
G01Y165605D02*
Y168253D01*
G01X375266Y164918D02*
Y163232D01*
G01Y174367D02*
Y172680D01*
G01X375370Y172639D02*
Y174408D01*
G01Y163190D02*
Y164959D01*
G01X375703Y168484D02*
Y165374D01*
G01Y173484D02*
Y170374D01*
G01X375879Y168484D02*
Y165374D01*
G01Y173484D02*
Y170374D01*
G01X376967Y176098D02*
Y177248D01*
G01Y169798D02*
Y170949D01*
G01Y166649D02*
Y167800D01*
G01X377125Y175605D02*
Y178253D01*
G01X377234Y168067D02*
Y166381D01*
G01Y171217D02*
Y169531D01*
G01Y177516D02*
Y175830D01*
G01X377339Y175789D02*
Y177558D01*
G01Y169489D02*
Y171258D01*
G01Y166340D02*
Y168109D01*
G01X377263Y171233D02*
X377066Y171120D01*
G01X377263Y168084D02*
X377066Y167970D01*
G01X375294Y164934D02*
X375097Y164820D01*
G01X377672Y175374D02*
Y178484D01*
G01X377848Y178489D02*
Y175369D01*
G01X375156Y165605D02*
X375335Y165430D01*
G01X375156Y170605D02*
X375335Y170430D01*
G01X377125Y175605D02*
X377304Y175430D01*
G01X375097Y163329D02*
X375294Y163215D01*
G01X377263Y166365D02*
X377066Y166478D01*
G01X377263Y169515D02*
X377066Y169628D01*
G01X375097Y172778D02*
X375294Y172664D01*
G01X377263Y175814D02*
X377066Y175927D01*
G01X377976Y175326D02*
X377870Y175363D01*
G01X377361Y161811D02*
X387814D01*
G01X388995Y163189D02*
X375393D01*
G01X375473Y163484D02*
X377806D01*
G01X377946Y163543D02*
X387516D01*
G01X375393Y164961D02*
X387814D01*
G01X387516Y165315D02*
X377946D01*
G01X377806Y165374D02*
X375473D01*
G01X388913Y166339D02*
X377361D01*
G01Y168110D02*
X387814D01*
G01X375473Y168484D02*
X377806D01*
G01X377946Y168543D02*
X387516D01*
G01X377361Y169488D02*
X388913D01*
G01X387516Y170315D02*
X377946D01*
G01X377806Y170374D02*
X375473D01*
G01X377361Y171260D02*
X387814D01*
G01X388995Y172638D02*
X375393D01*
G01X375473Y173484D02*
X377806D01*
G01X377946Y173543D02*
X387516D01*
G01X375393Y174409D02*
X387814D01*
G01X387516Y175315D02*
X378041D01*
G01X377806Y175374D02*
X377441D01*
G01X388913Y175787D02*
X377361D01*
G01Y177559D02*
X387814D01*
G01X375010Y191781D02*
X374999Y191846D01*
G01X375043Y191722D02*
X375010Y191781D01*
G01X375097Y191675D02*
X375043Y191722D01*
G01X375010Y182332D02*
X374999Y182397D01*
G01X375043Y182273D02*
X375010Y182332D01*
G01X375097Y182226D02*
X375043Y182273D01*
G01X377012Y188571D02*
X377066Y188526D01*
G01X376979Y188630D02*
X377012Y188571D01*
G01X376967Y188696D02*
X376979Y188630D01*
G01X377012Y185422D02*
X377066Y185376D01*
G01X376979Y185480D02*
X377012Y185422D01*
G01X376967Y185546D02*
X376979Y185480D01*
G01X377012Y179122D02*
X377066Y179077D01*
G01X376979Y179181D02*
X377012Y179122D01*
G01X376967Y179247D02*
X376979Y179181D01*
G01X375043Y183672D02*
X375097Y183718D01*
G01X375010Y183614D02*
X375043Y183672D01*
G01X374999Y183548D02*
X375010Y183614D01*
G01X375043Y193121D02*
X375097Y193167D01*
G01X375010Y193063D02*
X375043Y193121D01*
G01X374999Y192996D02*
X375010Y193063D01*
G01X376978Y180463D02*
X376967Y180398D01*
G01X377011Y180522D02*
X376978Y180463D01*
G01X377066Y180569D02*
X377011Y180522D01*
G01X376978Y186762D02*
X376967Y186697D01*
G01X377011Y186821D02*
X376978Y186762D01*
G01X377066Y186868D02*
X377011Y186821D01*
G01X376978Y189912D02*
X376967Y189847D01*
G01X377011Y189971D02*
X376978Y189912D01*
G01X377066Y190017D02*
X377011Y189971D01*
G01X377263Y178963D02*
G03X377361Y178937I98J171D01*
G01X378041Y178543D02*
G03X377976Y178532I0J-197D01*
G01X377806Y178484D02*
G03X377870Y178495I-1J197D01*
G01X377441Y178484D02*
G03X377304Y178428I0J-197D01*
G01X377361Y180709D02*
G03X377263Y180682I2J-197D01*
G01X375393Y183858D02*
G03X375294Y183832I-1J-197D01*
G01Y182113D02*
G03X375393Y182087I98J171D01*
G01X377361Y187008D02*
G03X377263Y186982I0J-197D01*
G01Y185263D02*
G03X377361Y185236I99J170D01*
G01Y190158D02*
G03X377263Y190131I2J-197D01*
G01Y188412D02*
G03X377361Y188386I98J171D01*
G01X377304Y190430D02*
G03X377441Y190374I137J141D01*
G01X377870Y190363D02*
G03X377806Y190374I-65J-186D01*
G01X377976Y190326D02*
G03X378041Y190315I65J186D01*
G01X377806Y188484D02*
G03X377946Y188543I-1J197D01*
G01X375473Y188484D02*
G03X375335Y188428I0J-197D01*
G01Y185430D02*
G03X375473Y185374I138J141D01*
G01X377946Y185315D02*
G03X377806Y185374I-141J-138D01*
G01X378041Y183543D02*
G03X377976Y183532I0J-197D01*
G01X377806Y183484D02*
G03X377870Y183495I-1J197D01*
G01X377441Y183484D02*
G03X377304Y183428I0J-197D01*
G01Y180430D02*
G03X377441Y180374I137J141D01*
G01X377870Y180363D02*
G03X377806Y180374I-65J-186D01*
G01X377976Y180326D02*
G03X378041Y180315I65J186D01*
G01X375393Y193307D02*
G03X375294Y193281I-1J-197D01*
G01Y191562D02*
G03X375393Y191535I99J170D01*
G01X377263Y194711D02*
G03X377361Y194685I98J171D01*
G01X378041Y193543D02*
G03X377976Y193532I0J-197D01*
G01X377806Y193484D02*
G03X377870Y193495I-1J197D01*
G01X377441Y193484D02*
G03X377304Y193428I0J-197D01*
G01X375294Y193281D02*
X375097Y193167D01*
G01X377304Y193428D02*
X377125Y193253D01*
G01X375335Y188428D02*
X375156Y188253D01*
G01X377304Y183428D02*
X377125Y183253D01*
G01X377263Y190131D02*
X377066Y190017D01*
G01X377263Y186982D02*
X377066Y186868D01*
G01X375294Y183832D02*
X375097Y183718D01*
G01X377263Y180682D02*
X377066Y180569D01*
G01X374999Y183548D02*
Y182397D01*
G01Y192996D02*
Y191846D01*
G01X375156Y185605D02*
Y188253D01*
G01X375266Y183815D02*
Y182129D01*
G01Y193264D02*
Y191578D01*
G01X375370Y191537D02*
Y193306D01*
G01Y182088D02*
Y183857D01*
G01X375703Y188484D02*
Y185374D01*
G01X375879Y188484D02*
Y185374D01*
G01X376967Y188696D02*
Y189847D01*
G01Y185546D02*
Y186697D01*
G01Y179247D02*
Y180398D01*
G01X377125Y190605D02*
Y193253D01*
G01Y180605D02*
Y183253D01*
G01X377234Y180666D02*
Y178980D01*
G01Y186965D02*
Y185279D01*
G01Y190115D02*
Y188428D01*
G01Y196414D02*
Y194728D01*
G01X377339Y194686D02*
Y196455D01*
G01Y188387D02*
Y190156D01*
G01Y185237D02*
Y187006D01*
G01Y178938D02*
Y180707D01*
G01X377870Y193495D02*
X377976Y193532D01*
G01X377870Y183495D02*
X377976Y183532D01*
G01X377672Y190374D02*
Y193484D01*
G01Y180374D02*
Y183484D01*
G01X377848Y183489D02*
Y180369D01*
G01Y193489D02*
Y190369D01*
G01X377870Y178495D02*
X377976Y178532D01*
G01X377125Y180605D02*
X377304Y180430D01*
G01X375156Y185605D02*
X375335Y185430D01*
G01X377125Y190605D02*
X377304Y190430D01*
G01X377263Y178963D02*
X377066Y179077D01*
G01X375097Y182226D02*
X375294Y182113D01*
G01X377263Y185263D02*
X377066Y185376D01*
G01X377263Y188412D02*
X377066Y188526D01*
G01X375097Y191675D02*
X375294Y191562D01*
G01X377263Y194711D02*
X377066Y194825D01*
G01X377976Y180326D02*
X377870Y180363D01*
G01X377976Y190326D02*
X377870Y190363D01*
G01X377441Y178484D02*
X377806D01*
G01X378041Y178543D02*
X387516D01*
G01X388913Y178937D02*
X377361D01*
G01X387516Y180315D02*
X378041D01*
G01X377806Y180374D02*
X377441D01*
G01X377361Y180709D02*
X387814D01*
G01X388995Y182087D02*
X375393D01*
G01X377441Y183484D02*
X377806D01*
G01X378041Y183543D02*
X387516D01*
G01X375393Y183858D02*
X387814D01*
G01X388913Y185236D02*
X377361D01*
G01X387516Y185315D02*
X377946D01*
G01X377806Y185374D02*
X375473D01*
G01X377361Y187008D02*
X387814D01*
G01X388913Y188386D02*
X377361D01*
G01X375473Y188484D02*
X377806D01*
G01X377946Y188543D02*
X387516D01*
G01X377361Y190158D02*
X387814D01*
G01X387516Y190315D02*
X378041D01*
G01X377806Y190374D02*
X377441D01*
G01X388995Y191535D02*
X375393D01*
G01Y193307D02*
X387814D01*
G01X377441Y193484D02*
X377806D01*
G01X378041Y193543D02*
X387516D01*
G01X388913Y194685D02*
X377361D01*
G01X375010Y210678D02*
X374999Y210743D01*
G01X375043Y210620D02*
X375010Y210678D01*
G01X375097Y210573D02*
X375043Y210620D01*
G01X375010Y201230D02*
X374999Y201295D01*
G01X375043Y201171D02*
X375010Y201230D01*
G01X375097Y201124D02*
X375043Y201171D01*
G01X377012Y207469D02*
X377066Y207423D01*
G01X376979Y207528D02*
X377012Y207469D01*
G01X376967Y207594D02*
X376979Y207528D01*
G01X377012Y204319D02*
X377066Y204274D01*
G01X376979Y204378D02*
X377012Y204319D01*
G01X376967Y204444D02*
X376979Y204378D01*
G01X377012Y198020D02*
X377066Y197974D01*
G01X376979Y198079D02*
X377012Y198020D01*
G01X376967Y198145D02*
X376979Y198079D01*
G01X377012Y194870D02*
X377066Y194825D01*
G01X376979Y194929D02*
X377012Y194870D01*
G01X376967Y194995D02*
X376979Y194929D01*
G01X375043Y202570D02*
X375097Y202616D01*
G01X375010Y202511D02*
X375043Y202570D01*
G01X374999Y202445D02*
X375010Y202511D01*
G01X376978Y196211D02*
X376967Y196146D01*
G01X377011Y196270D02*
X376978Y196211D01*
G01X377066Y196317D02*
X377011Y196270D01*
G01X376978Y199361D02*
X376967Y199296D01*
G01X377011Y199420D02*
X376978Y199361D01*
G01X377066Y199466D02*
X377011Y199420D01*
G01X376978Y205660D02*
X376967Y205595D01*
G01X377011Y205719D02*
X376978Y205660D01*
G01X377066Y205765D02*
X377011Y205719D01*
G01X376978Y208809D02*
X376967Y208745D01*
G01X377011Y208869D02*
X376978Y208809D01*
G01X377066Y208915D02*
X377011Y208869D01*
G01X377361Y196457D02*
G03X377263Y196430I2J-197D01*
G01X377361Y199606D02*
G03X377263Y199580I0J-197D01*
G01Y197861D02*
G03X377361Y197835I98J171D01*
G01X375294Y201011D02*
G03X375393Y200984I99J170D01*
G01X375335Y200430D02*
G03X375473Y200374I138J141D01*
G01X377946Y200315D02*
G03X377806Y200374I-141J-138D01*
G01Y198484D02*
G03X377946Y198543I-1J197D01*
G01X375473Y198484D02*
G03X375335Y198428I0J-197D01*
G01Y195430D02*
G03X375473Y195374I138J141D01*
G01X377946Y195315D02*
G03X377806Y195374I-141J-138D01*
G01X375393Y202756D02*
G03X375294Y202730I-1J-197D01*
G01X377361Y205906D02*
G03X377263Y205879I2J-197D01*
G01Y204160D02*
G03X377361Y204134I98J171D01*
G01Y209055D02*
G03X377263Y209029I0J-197D01*
G01Y207310D02*
G03X377361Y207283I99J170D01*
G01X375294Y210459D02*
G03X375393Y210433I98J171D01*
G01X377304Y210430D02*
G03X377441Y210374I137J141D01*
G01X377870Y210363D02*
G03X377806Y210374I-65J-186D01*
G01X377976Y210326D02*
G03X378041Y210315I65J186D01*
G01Y208543D02*
G03X377976Y208532I0J-197D01*
G01X377806Y208484D02*
G03X377870Y208495I-1J197D01*
G01X377441Y208484D02*
G03X377304Y208428I0J-197D01*
G01Y205430D02*
G03X377441Y205374I137J141D01*
G01X377870Y205363D02*
G03X377806Y205374I-65J-186D01*
G01X377976Y205326D02*
G03X378041Y205315I65J186D01*
G01X377806Y203484D02*
G03X377946Y203543I-1J197D01*
G01X375473Y203484D02*
G03X375335Y203428I0J-197D01*
G01X377304Y208428D02*
X377125Y208253D01*
G01X375335Y203428D02*
X375156Y203253D01*
G01X375335Y198428D02*
X375156Y198253D01*
G01X377263Y209029D02*
X377066Y208915D01*
G01X377263Y205879D02*
X377066Y205765D01*
G01X375294Y202730D02*
X375097Y202616D01*
G01X377263Y199580D02*
X377066Y199466D01*
G01X377263Y196430D02*
X377066Y196317D01*
G01X377870Y208495D02*
X377976Y208532D01*
G01X374999Y202445D02*
Y201295D01*
G01Y211894D02*
Y210743D01*
G01X375156Y200605D02*
Y203253D01*
G01Y195605D02*
Y198253D01*
G01X375266Y202713D02*
Y201027D01*
G01Y212162D02*
Y210476D01*
G01X375370Y210434D02*
Y212203D01*
G01Y200985D02*
Y202754D01*
G01X375703Y198484D02*
Y195374D01*
G01Y203484D02*
Y200374D01*
G01X375879Y198484D02*
Y195374D01*
G01Y203484D02*
Y200374D01*
G01X376967Y207594D02*
Y208745D01*
G01Y204444D02*
Y205595D01*
G01Y198145D02*
Y199296D01*
G01Y194995D02*
Y196146D01*
G01X377125Y210605D02*
Y213253D01*
G01Y205605D02*
Y208253D01*
G01X377234Y199563D02*
Y197877D01*
G01Y205863D02*
Y204176D01*
G01Y209012D02*
Y207326D01*
G01X377339Y207285D02*
Y209054D01*
G01Y204135D02*
Y205904D01*
G01Y197836D02*
Y199605D01*
G01X377672Y210374D02*
Y213484D01*
G01Y205374D02*
Y208484D01*
G01X377848Y208489D02*
Y205369D01*
G01Y213489D02*
Y210369D01*
G01X375156Y195605D02*
X375335Y195430D01*
G01X375156Y200605D02*
X375335Y200430D01*
G01X377125Y205605D02*
X377304Y205430D01*
G01X377125Y210605D02*
X377304Y210430D01*
G01X377263Y197861D02*
X377066Y197974D01*
G01X375097Y201124D02*
X375294Y201011D01*
G01X377263Y204160D02*
X377066Y204274D01*
G01X377263Y207310D02*
X377066Y207423D01*
G01X375097Y210573D02*
X375294Y210459D01*
G01X377976Y205326D02*
X377870Y205363D01*
G01X377976Y210326D02*
X377870Y210363D01*
G01X387516Y195315D02*
X377946D01*
G01X377806Y195374D02*
X375473D01*
G01X377361Y196457D02*
X387814D01*
G01X388913Y197835D02*
X377361D01*
G01X375473Y198484D02*
X377806D01*
G01X377946Y198543D02*
X387516D01*
G01X377361Y199606D02*
X387814D01*
G01X387516Y200315D02*
X377946D01*
G01X377806Y200374D02*
X375473D01*
G01X388995Y200984D02*
X375393D01*
G01Y202756D02*
X387814D01*
G01X375473Y203484D02*
X377806D01*
G01X377946Y203543D02*
X387516D01*
G01X388913Y204134D02*
X377361D01*
G01X387516Y205315D02*
X378041D01*
G01X377806Y205374D02*
X377441D01*
G01X377361Y205906D02*
X387814D01*
G01X388913Y207283D02*
X377361D01*
G01X377441Y208484D02*
X377806D01*
G01X378041Y208543D02*
X387516D01*
G01X377361Y209055D02*
X387814D01*
G01X387516Y210315D02*
X378041D01*
G01X377806Y210374D02*
X377441D01*
G01X388995Y210433D02*
X375393D01*
G01X375043Y212019D02*
X375097Y212065D01*
G01X375010Y211960D02*
X375043Y212019D01*
G01X374999Y211894D02*
X375010Y211960D01*
G01X375393Y212205D02*
G03X375294Y212178I1J-197D01*
G01X378041Y213543D02*
G03X377976Y213532I0J-197D01*
G01X377806Y213484D02*
G03X377870Y213495I-1J197D01*
G01X377441Y213484D02*
G03X377304Y213428I0J-197D01*
G01X373030Y214055D02*
X374211Y215236D01*
G01X377304Y213428D02*
X377125Y213253D01*
G01X375294Y212178D02*
X375097Y212065D01*
G01X377870Y213495D02*
X377976Y213532D01*
G01X373030Y236673D02*
Y224685D01*
G01X375076Y230394D02*
X375078Y222638D01*
G01X373030Y224685D02*
X375078Y222638D01*
G01X375393Y212205D02*
X387814D01*
G01X377441Y213484D02*
X377806D01*
G01X378041Y213543D02*
X387516D01*
G01X403186Y215236D02*
X374211D01*
G01X390353Y222638D02*
X375078D01*
G01X373030Y225276D02*
X399802D01*
G01X373030Y226457D02*
X399802D01*
G01X384439Y240082D02*
X384448Y240100D01*
G01X384340Y240050D02*
X384439Y240082D01*
G01X384136Y240040D02*
X384340Y240050D01*
G01X384060Y240810D02*
X383876Y241330D01*
G01X384244Y240400D02*
X384060Y240810D01*
G01X384429Y240135D02*
X384244Y240400D01*
G01X384447Y238961D02*
X384448Y238956D01*
G01X384429Y239011D02*
X384447Y238961D01*
G01X383859Y241407D02*
X383857Y241446D01*
G01X383865Y241368D02*
X383859Y241407D01*
G01X383876Y241330D02*
X383865Y241368D01*
G01X384244Y239435D02*
X384429Y239011D01*
G01X384060Y240092D02*
X384244Y239435D01*
G01X383876Y240924D02*
X384060Y240092D01*
G01X383865Y240985D02*
X383876Y240924D01*
G01X383859Y241047D02*
X383865Y240985D01*
G01X383857Y241110D02*
X383859Y241047D01*
G01X384155Y238860D02*
X384057Y238858D01*
G01X384247Y238864D02*
X384155Y238860D01*
G01X384330Y238874D02*
X384247Y238864D01*
G01X384394Y238892D02*
X384330Y238874D01*
G01X384435Y238921D02*
X384394Y238892D01*
G01X384448Y238956D02*
X384435Y238921D01*
G01X373030Y236673D02*
G03X374999Y234705I1968J0D01*
G01X373030Y236673D02*
G03X374999Y234705I1968J0D01*
G01X373030Y236673D02*
G03X374999Y234705I1968J0D01*
G01X373030Y236673D02*
G03X374999Y234705I1968J0D01*
G01X375076Y230394D02*
X374759Y229213D01*
G01X373030Y256102D02*
Y236673D01*
G01Y256102D02*
Y236673D01*
G01Y244370D02*
Y236673D01*
G01X379290Y240039D02*
Y238858D01*
G01X379330Y234705D02*
Y233543D01*
G01Y244370D02*
Y234705D01*
G01X379881Y240039D02*
Y238858D01*
G01X380904Y230394D02*
Y233543D01*
G01X381180Y240039D02*
Y238858D01*
G01X381657Y240039D02*
Y238858D01*
G01X381742D02*
Y240039D01*
G01X381989D02*
Y238858D01*
G01X382993D02*
Y240039D01*
G01X383070D02*
Y238858D01*
G01X383267Y244370D02*
Y240079D01*
G01X383857Y240039D02*
Y238858D01*
G01Y241111D02*
Y247874D01*
G01X383876Y240924D02*
Y241330D01*
G01X384429Y240135D02*
Y239011D01*
G01X384448Y238956D02*
Y240100D01*
G01X385117Y240039D02*
Y238858D01*
G01X385511D02*
Y240039D01*
G01X384448Y240100D02*
X384429Y240135D01*
G01X373030Y230211D02*
X374759Y229213D01*
G01X373030Y231575D02*
X375076Y230394D01*
G01X399802Y229213D02*
X373030D01*
G01X399802Y230394D02*
X375076D01*
G01X403159Y233543D02*
X373030D01*
G01X401377Y234705D02*
X374999D01*
G01X401377D02*
X374999D01*
G01X373030Y235512D02*
X402952D01*
G01Y237638D02*
X373030D01*
G01X402952Y238228D02*
X373030D01*
G01X402952Y238819D02*
X373030D01*
G01X397085Y238858D02*
X379290D01*
G01X397085Y240039D02*
X379290D01*
G01X402952Y240079D02*
X373030D01*
G01X383267Y240472D02*
X393109D01*
G01X383267Y240669D02*
X373030D01*
G01Y241260D02*
X383267D01*
G01X383857Y242008D02*
X392519D01*
G01X373030Y256102D02*
Y236673D01*
G01Y256102D02*
Y236673D01*
G01X401377Y234705D02*
X374999D01*
G01X401377D02*
X374999D01*
G01D02*
X401377D01*
G01X373031Y236673D02*
G03X374999Y234705I1968J0D01*
G01X373031Y256102D02*
Y236673D01*
G01X385038Y249055D02*
G03X383857Y247874I0J-1181D01*
G01X374999Y258071D02*
G03X373030Y256102I0J-1969D01*
G01X374999Y258071D02*
G03X373030Y256102I0J-1969D01*
G01X374999Y258071D02*
G03X373030Y256102I0J-1969D01*
G01X374999Y258071D02*
G03X373030Y256102I0J-1969D01*
G01X383267Y244370D02*
X373030D01*
G01X385038Y249055D02*
X391337D01*
G01X498621Y258071D02*
X374999D01*
G01X498621D02*
X374999D01*
G01X498621D02*
X374999D01*
G01X498621D02*
X374999D01*
G01D02*
G03X373030Y256102I0J-1969D01*
G01X498620Y258071D02*
X374999D01*
G01X373031Y273819D02*
G03X380905Y265945I7874J0D01*
G01X373031Y273819D02*
G03X380905Y265945I7874J0D01*
G01X373031Y273819D02*
G03X380905Y265945I7874J0D01*
G01X373031Y273819D02*
G03X380905Y265945I7874J0D01*
G01D02*
X581102D01*
G01D02*
X380905D01*
G01X373031Y355551D02*
Y273819D01*
G01Y355551D02*
Y273819D01*
G01X380905Y265945D02*
X661220D01*
G01X380905D02*
X581102D01*
G01X373031Y355551D02*
Y273819D01*
G01Y355551D02*
Y273819D01*
G01X380905Y265945D02*
X581102D01*
G01X373031Y273819D02*
G03X380905Y265945I7874J0D01*
G01X373031Y355551D02*
Y273819D01*
G01X414369Y316181D02*
G03X382874I-15747J0D01*
G03X414369I15748J0D01*
G01D02*
G03X382874I-15747J0D01*
G03X414369I15748J0D01*
G01X373031Y355797D02*
Y423796D01*
G01X380905Y363425D02*
G03X373031Y355551I0J-7874D01*
G01X380905Y363425D02*
G03X373031Y355551I0J-7874D01*
G01X380905Y363425D02*
G03X373031Y355551I0J-7874D01*
G01X380905Y363425D02*
G03X373031Y355551I0J-7874D01*
G01X380905Y363425D02*
G03X373031Y355551I0J-7874D01*
G01X714566Y363425D02*
X380905D01*
G01X714566D02*
X380905D01*
G01X714566D02*
X380905D01*
G01X714566D02*
X380905D01*
G01X714566D02*
X380905D01*
G01X375663Y381710D02*
Y384510D01*
G01X391937Y58776D02*
X391928Y58758D01*
G01X392035Y58808D02*
X391937Y58776D01*
G01X392240Y58818D02*
X392035Y58808D01*
G01X392220Y59998D02*
X392317Y60000D01*
G01X392128Y59994D02*
X392220Y59998D01*
G01X392046Y59984D02*
X392128Y59994D01*
G01X391981Y59966D02*
X392046Y59984D01*
G01X391940Y59937D02*
X391981Y59966D01*
G01X391928Y59902D02*
X391940Y59937D01*
G01X392315Y58048D02*
X392500Y57528D01*
G01X392131Y58458D02*
X392315Y58048D01*
G01X391946Y58723D02*
X392131Y58458D01*
G01X391928Y59897D02*
Y59902D01*
G01X391946Y59847D02*
X391928Y59897D01*
G01X392510Y57873D02*
X392500Y57934D01*
G01X392517Y57811D02*
X392510Y57873D01*
G01X392519Y57748D02*
X392517Y57811D01*
G01X392516Y57451D02*
X392519Y57411D01*
G01X392510Y57490D02*
X392516Y57451D01*
G01X392500Y57528D02*
X392510Y57490D01*
G01X392131Y59423D02*
X391946Y59847D01*
G01X392315Y58766D02*
X392131Y59423D01*
G01X392500Y57934D02*
X392315Y58766D01*
G01X391337Y49803D02*
G03X392519Y50984I1J1181D01*
G01X386298Y60000D02*
Y58819D01*
G01X390078Y60000D02*
Y58819D01*
G01X390865D02*
Y60000D01*
G01X391259Y58819D02*
Y60000D01*
G01X391928Y59902D02*
Y58758D01*
G01X391946Y58723D02*
Y59847D01*
G01X392500Y57934D02*
Y57528D01*
G01X392519Y57747D02*
Y50984D01*
G01Y60000D02*
Y58819D01*
G01X393109Y58780D02*
Y54488D01*
G01X393306Y58819D02*
Y60000D01*
G01X393383D02*
Y58819D01*
G01X391928Y58758D02*
X391946Y58723D01*
G01X394387Y58819D02*
Y60000D01*
G01X394633D02*
Y58819D01*
G01X394718D02*
Y60000D01*
G01X395038Y60433D02*
Y58386D01*
G01X395196Y58819D02*
Y60000D01*
G01X395432Y60433D02*
Y58386D01*
G01X396495Y58819D02*
Y60000D01*
G01X397046Y54488D02*
Y64114D01*
G01X397085Y58819D02*
Y60000D01*
G01X395038Y58780D02*
X395432Y58386D01*
G01X395038Y60039D02*
X395432Y60433D01*
G01X402952Y54488D02*
X393109D01*
G01Y57598D02*
X402952D01*
G01Y58189D02*
X393109D01*
G01X395432Y58386D02*
X395038D01*
G01Y60433D02*
X395432D01*
G01X401377Y64114D02*
G03X403345Y66083I0J1968D01*
G01X401377Y64114D02*
G03X403345Y66083I0J1968D01*
G01X401377Y64114D02*
G03X403345Y66083I0J1968D01*
G01X401377Y64114D02*
G03X403345Y66083I0J1968D01*
G01X392322Y78189D02*
Y220669D01*
G01X397046Y64114D02*
Y65315D01*
G01X399802Y79846D02*
Y68465D01*
G01X402164Y68071D02*
Y80866D01*
G01X392322Y78189D02*
X390353Y76220D01*
G01X399408Y65315D02*
X402164Y68071D01*
G01X399802Y69252D02*
X402952D01*
G01X401377Y64114D02*
G03X403346Y66083I0J1969D01*
G01X391962Y89176D02*
X391928Y89173D01*
G01X391995Y89185D02*
X391962Y89176D01*
G01X392026Y89200D02*
X391995Y89185D01*
G01X391962Y92326D02*
X391928Y92323D01*
G01X391995Y92335D02*
X391962Y92326D01*
G01X392026Y92349D02*
X391995Y92335D01*
G01X392026Y94068D02*
G03X391928Y94095I-100J-170D01*
G01X392026Y90919D02*
G03X391928Y90945I-98J-171D01*
G01X389273D02*
G03X389134Y90887I1J-197D01*
G01X388913Y90748D02*
G03X389053Y90806I1J197D01*
G01X387953Y92462D02*
G03X387814Y92520I-140J-139D01*
G01X388035Y92380D02*
G03X388174Y92323I138J140D01*
G01X392026Y87769D02*
G03X391928Y87795I-98J-171D01*
G01X389273D02*
G03X389134Y87737I1J-197D01*
G01X388913Y87598D02*
G03X389053Y87656I0J197D01*
G01X387953Y89312D02*
G03X387814Y89370I-140J-139D01*
G01X388035Y89231D02*
G03X388174Y89173I139J139D01*
G01X390745Y93150D02*
G03X390796Y93156I3J197D01*
G01X387933Y93207D02*
G03X388072Y93150I138J140D01*
G01X387655Y93485D02*
G03X387516Y93543I-139J-139D01*
G01Y90315D02*
G03X387655Y90372I0J197D01*
G01X388072Y90709D02*
G03X387933Y90651I1J-197D01*
G01X390796Y90702D02*
G03X390745Y90709I-52J-190D01*
G01Y88150D02*
G03X390796Y88156I3J197D01*
G01X387933Y88207D02*
G03X388072Y88150I138J140D01*
G01X387655Y88485D02*
G03X387516Y88543I-139J-139D01*
G01Y85315D02*
G03X387655Y85372I0J197D01*
G01X388072Y85709D02*
G03X387933Y85651I1J-197D01*
G01X390796Y85702D02*
G03X390745Y85709I-52J-190D01*
G01X391928Y95472D02*
G03X392026Y95499I-1J197D01*
G01X387516Y95315D02*
G03X387655Y95372I0J197D01*
G01X388072Y95709D02*
G03X387933Y95651I1J-197D01*
G01X390796Y95702D02*
G03X390745Y95709I-52J-190D01*
G01X396990Y87894D02*
G03X396613Y87815I-180J-79D01*
G01Y89154D02*
G03X396990Y89075I197J0D01*
G01Y91043D02*
G03X396613Y90964I-180J-79D01*
G01Y92303D02*
G03X396990Y92224I197J0D01*
G01Y94193D02*
G03X396613Y94114I-180J-79D01*
G01X394290Y86752D02*
G03X396259Y84783I1969J0D01*
G01X394290Y86752D02*
G03X396259Y84783I1969J0D01*
G01X396613Y95453D02*
G03X396990Y95374I197J0D01*
G01X401972Y92913D02*
G03X402169Y92717I197J1D01*
G01Y91142D02*
G03X401972Y90945I0J-197D01*
G01Y87913D02*
G03X402169Y87717I197J1D01*
G01Y86142D02*
G03X401972Y85945I0J-197D01*
G01X403345Y82815D02*
G03X401377Y84783I-1968J0D01*
G01X403345Y82815D02*
G03X401377Y84783I-1968J0D01*
G01X394290Y86752D02*
G03X396259Y84783I1969J0D01*
G01X403345Y82815D02*
G03X401377Y84783I-1968J0D01*
G01X403345Y82815D02*
G03X401377Y84783I-1968J0D01*
G01X394290Y86752D02*
G03X396259Y84783I1969J0D01*
G01X391141Y95079D02*
Y93780D01*
G01Y88780D02*
Y90079D01*
G01Y83622D02*
Y85079D01*
G01X399633Y94193D02*
X399712Y94350D01*
G01X400394D02*
X400315Y94193D01*
G01X399633Y91043D02*
X399712Y91201D01*
G01X400394D02*
X400315Y91043D01*
G01X399633Y87894D02*
X399712Y88051D01*
G01X400394D02*
X400315Y87894D01*
G01X394290Y86752D02*
Y212067D01*
G01Y86752D02*
Y212067D01*
G01X396416Y84783D02*
Y83622D01*
G01Y214035D02*
Y84783D01*
G01X396613Y87815D02*
Y87296D01*
G01Y89682D02*
Y89154D01*
G01Y90964D02*
Y90445D01*
G01Y92831D02*
Y92303D01*
G01Y94114D02*
Y93595D01*
G01Y95981D02*
Y95453D01*
G01X397221Y94193D02*
Y95374D01*
G01Y91043D02*
Y92224D01*
G01Y87894D02*
Y89075D01*
G01X398074D02*
Y87894D01*
G01Y92224D02*
Y91043D01*
G01Y95374D02*
Y94193D01*
G01X398621Y214035D02*
Y84783D01*
G01Y83622D02*
Y84783D01*
G01X398756Y94193D02*
Y95374D01*
G01Y91043D02*
Y92224D01*
G01Y87894D02*
Y89075D01*
G01X400378Y94350D02*
Y95217D01*
G01Y91201D02*
Y92067D01*
G01Y88051D02*
Y88917D01*
G01X401059D02*
Y88051D01*
G01Y92067D02*
Y91201D01*
G01Y95217D02*
Y94350D01*
G01X401912D02*
Y95217D01*
G01Y91201D02*
Y92067D01*
G01Y88051D02*
Y88917D01*
G01X401972Y88898D02*
Y87913D01*
G01Y90945D02*
Y89961D01*
G01Y93898D02*
Y92913D01*
G01Y95945D02*
Y94961D01*
G01Y84961D02*
Y85945D01*
G01X399712Y88917D02*
X399633Y89075D01*
G01X400315D02*
X400394Y88917D01*
G01X399712Y92067D02*
X399633Y92224D01*
G01X400315D02*
X400394Y92067D01*
G01X399712Y95217D02*
X399633Y95374D01*
G01X400315D02*
X400394Y95217D01*
G01X387655Y95372D02*
X387933Y95651D01*
G01X388995Y93898D02*
X389192Y94095D01*
G01X387655Y90372D02*
X387933Y90651D01*
G01X389053Y90806D02*
X389134Y90887D01*
G01X389053Y87656D02*
X389134Y87737D01*
G01X387933Y88207D02*
X387655Y88485D01*
G01X388035Y89231D02*
X387953Y89312D01*
G01X387655Y85372D02*
X387933Y85651D01*
G01X388035Y92380D02*
X387953Y92462D01*
G01X387933Y93207D02*
X387655Y93485D01*
G01X402164Y80866D02*
X399408Y83622D01*
G01X388011Y95472D02*
X387814Y95669D01*
G01X392322D02*
X392026Y95499D01*
G01X392322Y92520D02*
X392026Y92349D01*
G01X392322Y89370D02*
X392026Y89200D01*
G01Y87769D02*
X392322Y87598D01*
G01X392026Y90919D02*
X392322Y90748D01*
G01X392026Y94068D02*
X392322Y93898D01*
G01Y83334D02*
X399802Y79846D01*
G01X390796Y85702D02*
X392322Y85293D01*
G01X390796Y90702D02*
X392322Y90293D01*
G01X390796Y95702D02*
X392322Y95293D01*
G01X401377Y84783D02*
X396259D01*
G01X401377D02*
X396259D01*
G01X401972Y84961D02*
X398621D01*
G01X391141Y85079D02*
X392322D01*
G01X390745Y85709D02*
X388072D01*
G01X404721Y86142D02*
X402169D01*
G01X396613Y87296D02*
X396416D01*
G01X404721Y87717D02*
X402169D01*
G01X389273Y87795D02*
X391928D01*
G01X400315Y87894D02*
X396990D01*
G01X404668Y88051D02*
X399712D01*
G01X388072Y88150D02*
X390745D01*
G01X392322Y88780D02*
X391141D01*
G01X398621Y88898D02*
X401972D01*
G01X399712Y88917D02*
X404668D01*
G01X400315Y89075D02*
X396990D01*
G01X388174Y89173D02*
X391928D01*
G01X396416Y89682D02*
X396613D01*
G01X401972Y89961D02*
X398621D01*
G01X392322Y90079D02*
X391141D01*
G01X396613Y90445D02*
X396416D01*
G01X390745Y90709D02*
X388072D01*
G01X391928Y90945D02*
X389273D01*
G01X400315Y91043D02*
X396990D01*
G01X404721Y91142D02*
X402169D01*
G01X404668Y91201D02*
X399712D01*
G01Y92067D02*
X404668D01*
G01X400315Y92224D02*
X396990D01*
G01X391928Y92323D02*
X388174D01*
G01X404721Y92717D02*
X402169D01*
G01X396416Y92831D02*
X396613D01*
G01X388072Y93150D02*
X390745D01*
G01X396416Y93595D02*
X396613D01*
G01X392322Y93780D02*
X391141D01*
G01X401972Y93898D02*
X398621D01*
G01X391928Y94095D02*
X389192D01*
G01X400315Y94193D02*
X396990D01*
G01X404668Y94350D02*
X399712D01*
G01X401972Y94961D02*
X398621D01*
G01X392322Y95079D02*
X391141D01*
G01X399712Y95217D02*
X404668D01*
G01X400315Y95374D02*
X396990D01*
G01X388011Y95472D02*
X391928D01*
G01X390745Y95709D02*
X388072D01*
G01X392322Y88565D02*
X390796Y88156D01*
G01X392322Y93565D02*
X390796Y93156D01*
G01X394290Y86752D02*
Y212067D01*
G01Y86752D02*
Y212067D01*
G01X401377Y84783D02*
X396259D01*
G01X401377D02*
X396259D01*
G01X403346Y82815D02*
G03X401377Y84784I-1969J0D01*
G01X396259D02*
X401377D01*
G01X394290Y86752D02*
G03X396259Y84784I1968J0D01*
G01X394290Y212067D02*
Y86752D01*
G01X391962Y98625D02*
X391928Y98622D01*
G01X391995Y98634D02*
X391962Y98625D01*
G01X392026Y98648D02*
X391995Y98634D01*
G01X391962Y101774D02*
X391928Y101772D01*
G01X391995Y101783D02*
X391962Y101774D01*
G01X392026Y101798D02*
X391995Y101783D01*
G01X391962Y108074D02*
X391928Y108071D01*
G01X391995Y108083D02*
X391962Y108074D01*
G01X392026Y108097D02*
X391995Y108083D01*
G01X391962Y111223D02*
X391928Y111220D01*
G01X391995Y111232D02*
X391962Y111223D01*
G01X392026Y111247D02*
X391995Y111232D01*
G01X391928Y104921D02*
G03X392026Y104948I-1J197D01*
G01Y103517D02*
G03X391928Y103543I-98J-171D01*
G01X392026Y100367D02*
G03X391928Y100394I-100J-170D01*
G01X389273D02*
G03X389134Y100336I1J-197D01*
G01X388913Y100197D02*
G03X389053Y100254I1J197D01*
G01X387953Y101911D02*
G03X387814Y101969I-140J-139D01*
G01X388035Y101829D02*
G03X388174Y101772I138J140D01*
G01X392026Y97218D02*
G03X391928Y97244I-98J-171D01*
G01X389273D02*
G03X389134Y97186I1J-197D01*
G01X388913Y97047D02*
G03X389053Y97105I0J197D01*
G01X387953Y98761D02*
G03X387814Y98819I-140J-139D01*
G01X388035Y98680D02*
G03X388174Y98622I139J139D01*
G01X390745Y103150D02*
G03X390796Y103156I3J197D01*
G01X387933Y103207D02*
G03X388072Y103150I138J140D01*
G01X387655Y103485D02*
G03X387516Y103543I-139J-139D01*
G01Y100315D02*
G03X387655Y100372I0J197D01*
G01X388072Y100709D02*
G03X387933Y100651I1J-197D01*
G01X390796Y100702D02*
G03X390745Y100709I-52J-190D01*
G01Y98150D02*
G03X390796Y98156I3J197D01*
G01X387933Y98207D02*
G03X388072Y98150I138J140D01*
G01X387655Y98485D02*
G03X387516Y98543I-139J-139D01*
G01X396990Y100492D02*
G03X396613Y100413I-180J-79D01*
G01Y101752D02*
G03X396990Y101673I197J0D01*
G01Y97343D02*
G03X396613Y97263I-180J-79D01*
G01Y98602D02*
G03X396990Y98524I197J1D01*
G01X396613Y104902D02*
G03X396990Y104823I197J0D01*
G01Y103642D02*
G03X396613Y103563I-180J-79D01*
G01X392026Y109816D02*
G03X391928Y109843I-100J-170D01*
G01X389273D02*
G03X389134Y109785I1J-197D01*
G01X388913Y109646D02*
G03X389053Y109703I2J197D01*
G01X387953Y111359D02*
G03X387814Y111417I-139J-139D01*
G01X388035Y111278D02*
G03X388174Y111220I140J139D01*
G01X392026Y106667D02*
G03X391928Y106693I-98J-171D01*
G01X389273D02*
G03X389134Y106635I1J-197D01*
G01X388913Y106496D02*
G03X389053Y106554I1J197D01*
G01X387953Y108210D02*
G03X387814Y108268I-140J-139D01*
G01X388035Y108128D02*
G03X388174Y108071I138J140D01*
G01X387516Y110315D02*
G03X387655Y110372I0J197D01*
G01X388072Y110709D02*
G03X387933Y110651I1J-197D01*
G01X390796Y110702D02*
G03X390745Y110709I-52J-190D01*
G01Y108150D02*
G03X390796Y108156I3J197D01*
G01X387933Y108207D02*
G03X388072Y108150I138J140D01*
G01X387655Y108485D02*
G03X387516Y108543I-139J-139D01*
G01Y105315D02*
G03X387655Y105372I0J197D01*
G01X388072Y105709D02*
G03X387933Y105651I1J-197D01*
G01X390796Y105702D02*
G03X390745Y105709I-52J-190D01*
G01X396990Y109941D02*
G03X396613Y109862I-180J-79D01*
G01Y111201D02*
G03X396990Y111122I197J0D01*
G01Y106791D02*
G03X396613Y106712I-180J-79D01*
G01Y108051D02*
G03X396990Y107972I197J0D01*
G01X401972Y107913D02*
G03X402169Y107717I197J1D01*
G01Y106142D02*
G03X401972Y105945I0J-197D01*
G01X402169Y111142D02*
G03X401972Y110945I0J-197D01*
G01Y97913D02*
G03X402169Y97717I197J1D01*
G01Y96142D02*
G03X401972Y95945I0J-197D01*
G01Y102913D02*
G03X402169Y102717I197J1D01*
G01Y101142D02*
G03X401972Y100945I0J-197D01*
G01X391141Y110079D02*
Y108780D01*
G01Y103780D02*
Y105079D01*
G01Y98780D02*
Y100079D01*
G01X387655Y110372D02*
X387933Y110651D01*
G01X399633Y109941D02*
X399712Y110098D01*
G01X400394D02*
X400315Y109941D01*
G01X399633Y106791D02*
X399712Y106949D01*
G01X400394D02*
X400315Y106791D01*
G01X399633Y103642D02*
X399712Y103799D01*
G01X400394D02*
X400315Y103642D01*
G01X399633Y100492D02*
X399712Y100650D01*
G01X400394D02*
X400315Y100492D01*
G01X399633Y97343D02*
X399712Y97500D01*
G01X400394D02*
X400315Y97343D01*
G01X396613Y97263D02*
Y96745D01*
G01Y99130D02*
Y98602D01*
G01Y100413D02*
Y99894D01*
G01Y102280D02*
Y101752D01*
G01Y103563D02*
Y103044D01*
G01Y106712D02*
Y106193D01*
G01Y108579D02*
Y108051D01*
G01Y109862D02*
Y109343D01*
G01Y111729D02*
Y111201D01*
G01Y104902D02*
Y105430D01*
G01X397221Y109941D02*
Y111122D01*
G01Y106791D02*
Y107972D01*
G01Y103642D02*
Y104823D01*
G01Y100492D02*
Y101673D01*
G01Y97343D02*
Y98524D01*
G01X398074D02*
Y97343D01*
G01Y101673D02*
Y100492D01*
G01Y104823D02*
Y103642D01*
G01Y107972D02*
Y106791D01*
G01Y111122D02*
Y109941D01*
G01X398756D02*
Y111122D01*
G01Y106791D02*
Y107972D01*
G01Y103642D02*
Y104823D01*
G01Y100492D02*
Y101673D01*
G01Y97343D02*
Y98524D01*
G01X400378Y110098D02*
Y110965D01*
G01Y106949D02*
Y107815D01*
G01Y103799D02*
Y104665D01*
G01Y100650D02*
Y101516D01*
G01Y97500D02*
Y98366D01*
G01X401059D02*
Y97500D01*
G01Y101516D02*
Y100650D01*
G01Y104665D02*
Y103799D01*
G01Y107815D02*
Y106949D01*
G01Y110965D02*
Y110098D01*
G01X401912D02*
Y110965D01*
G01Y106949D02*
Y107815D01*
G01Y103799D02*
Y104665D01*
G01Y100650D02*
Y101516D01*
G01Y97500D02*
Y98366D01*
G01X401972Y98898D02*
Y97913D01*
G01Y103898D02*
Y102913D01*
G01Y105945D02*
Y104961D01*
G01Y108898D02*
Y107913D01*
G01Y110945D02*
Y109961D01*
G01Y99961D02*
Y100945D01*
G01X399712Y98366D02*
X399633Y98524D01*
G01X400315D02*
X400394Y98366D01*
G01X399712Y101516D02*
X399633Y101673D01*
G01X400315D02*
X400394Y101516D01*
G01X389053Y109703D02*
X389134Y109785D01*
G01X387655Y105372D02*
X387933Y105651D01*
G01X389053Y106554D02*
X389134Y106635D01*
G01X388995Y103346D02*
X389192Y103543D01*
G01X387655Y100372D02*
X387933Y100651D01*
G01X389053Y100254D02*
X389134Y100336D01*
G01X389053Y97105D02*
X389134Y97186D01*
G01X399712Y104665D02*
X399633Y104823D01*
G01X400315D02*
X400394Y104665D01*
G01X399712Y107815D02*
X399633Y107972D01*
G01X400315D02*
X400394Y107815D01*
G01X399712Y110965D02*
X399633Y111122D01*
G01X400315D02*
X400394Y110965D01*
G01X392322Y111417D02*
X392026Y111247D01*
G01X392322Y108268D02*
X392026Y108097D01*
G01X387933Y98207D02*
X387655Y98485D01*
G01X388035Y98680D02*
X387953Y98761D01*
G01X388035Y101829D02*
X387953Y101911D01*
G01X387933Y103207D02*
X387655Y103485D01*
G01X388011Y104921D02*
X387814Y105118D01*
G01X387933Y108207D02*
X387655Y108485D01*
G01X388035Y108128D02*
X387953Y108210D01*
G01X388035Y111278D02*
X387953Y111359D01*
G01X392322Y105118D02*
X392026Y104948D01*
G01X392322Y101969D02*
X392026Y101798D01*
G01X392322Y98819D02*
X392026Y98648D01*
G01Y97218D02*
X392322Y97047D01*
G01X392026Y100367D02*
X392322Y100197D01*
G01X392026Y103517D02*
X392322Y103346D01*
G01X392026Y106667D02*
X392322Y106496D01*
G01X392026Y109816D02*
X392322Y109646D01*
G01X390796Y100702D02*
X392322Y100293D01*
G01X390796Y105702D02*
X392322Y105293D01*
G01X390796Y110702D02*
X392322Y110293D01*
G01X396416Y95981D02*
X396613D01*
G01X404721Y96142D02*
X402169D01*
G01X396613Y96745D02*
X396416D01*
G01X391928Y97244D02*
X389273D01*
G01X400315Y97343D02*
X396990D01*
G01X404668Y97500D02*
X399712D01*
G01X404721Y97717D02*
X402169D01*
G01X388072Y98150D02*
X390745D01*
G01X399712Y98366D02*
X404668D01*
G01X400315Y98524D02*
X396990D01*
G01X391928Y98622D02*
X388174D01*
G01X392322Y98780D02*
X391141D01*
G01X398621Y98898D02*
X401972D01*
G01X396416Y99130D02*
X396613D01*
G01Y99894D02*
X396416D01*
G01X401972Y99961D02*
X398621D01*
G01X391141Y100079D02*
X392322D01*
G01X391928Y100394D02*
X389273D01*
G01X400315Y100492D02*
X396990D01*
G01X404668Y100650D02*
X399712D01*
G01X390745Y100709D02*
X388072D01*
G01X404721Y101142D02*
X402169D01*
G01X399712Y101516D02*
X404668D01*
G01X400315Y101673D02*
X396990D01*
G01X391928Y101772D02*
X388174D01*
G01X396416Y102280D02*
X396613D01*
G01X404721Y102717D02*
X402169D01*
G01X396416Y103044D02*
X396613D01*
G01X388072Y103150D02*
X390745D01*
G01X391928Y103543D02*
X389192D01*
G01X400315Y103642D02*
X396990D01*
G01X391141Y103780D02*
X392322D01*
G01X404668Y103799D02*
X399712D01*
G01X398621Y103898D02*
X401972D01*
G01X399712Y104665D02*
X404668D01*
G01X400315Y104823D02*
X396990D01*
G01X388011Y104921D02*
X391928D01*
G01X401972Y104961D02*
X398621D01*
G01X391141Y105079D02*
X392322D01*
G01X396613Y105430D02*
X396416D01*
G01X390745Y105709D02*
X388072D01*
G01X404721Y106142D02*
X402169D01*
G01X396613Y106193D02*
X396416D01*
G01X391928Y106693D02*
X389273D01*
G01X400315Y106791D02*
X396990D01*
G01X404668Y106949D02*
X399712D01*
G01X404721Y107717D02*
X402169D01*
G01X399712Y107815D02*
X404668D01*
G01X400315Y107972D02*
X396990D01*
G01X391928Y108071D02*
X388174D01*
G01X388072Y108150D02*
X390745D01*
G01X396416Y108579D02*
X396613D01*
G01X391141Y108780D02*
X392322D01*
G01X401972Y108898D02*
X398621D01*
G01X396613Y109343D02*
X396416D01*
G01X391928Y109843D02*
X389273D01*
G01X400315Y109941D02*
X396990D01*
G01X401972Y109961D02*
X398621D01*
G01X392322Y110079D02*
X391141D01*
G01X404668Y110098D02*
X399712D01*
G01X390745Y110709D02*
X388072D01*
G01X399712Y110965D02*
X404668D01*
G01X400315Y111122D02*
X396990D01*
G01X404721Y111142D02*
X402169D01*
G01X391928Y111220D02*
X388174D01*
G01X396416Y111729D02*
X396613D01*
G01X392322Y98565D02*
X390796Y98156D01*
G01X392322Y103565D02*
X390796Y103156D01*
G01X392322Y108565D02*
X390796Y108156D01*
G01X401878Y128714D02*
X401851Y128682D01*
G01X401908Y128733D02*
X401878Y128714D01*
G01X401941Y128740D02*
X401908Y128733D01*
G01X402376Y128570D02*
X402402Y128601D01*
G01X402345Y128550D02*
X402376Y128570D01*
G01X402313Y128543D02*
X402345Y128550D01*
G01X401773Y127336D02*
X401799Y127304D01*
G01X401742Y127356D02*
X401773Y127336D01*
G01X401709Y127362D02*
X401742Y127356D01*
G01X402481Y127192D02*
X402454Y127223D01*
G01X402511Y127172D02*
X402481Y127192D01*
G01X402544Y127165D02*
X402511Y127172D01*
G01X402345Y127356D02*
X402313Y127362D01*
G01X402376Y127336D02*
X402345Y127356D01*
G01X402402Y127304D02*
X402376Y127336D01*
G01X401908Y127172D02*
X401941Y127165D01*
G01X401878Y127192D02*
X401908Y127172D01*
G01X401851Y127223D02*
X401878Y127192D01*
G01X391962Y117522D02*
X391928Y117520D01*
G01X391995Y117532D02*
X391962Y117522D01*
G01X392026Y117546D02*
X391995Y117532D01*
G01X391962Y123822D02*
X391928Y123819D01*
G01X391995Y123831D02*
X391962Y123822D01*
G01X392026Y123845D02*
X391995Y123831D01*
G01X391962Y126971D02*
X391928Y126969D01*
G01X391995Y126980D02*
X391962Y126971D01*
G01X392026Y126995D02*
X391995Y126980D01*
G01X402511Y128733D02*
X402544Y128740D01*
G01X402481Y128714D02*
X402511Y128733D01*
G01X402454Y128682D02*
X402481Y128714D01*
G01X401742Y128550D02*
X401709Y128543D01*
G01X401773Y128570D02*
X401742Y128550D01*
G01X401799Y128601D02*
X401773Y128570D01*
G01X391928Y114370D02*
G03X392026Y114396I0J197D01*
G01Y112966D02*
G03X391928Y112992I-98J-171D01*
G01X390745Y113150D02*
G03X390796Y113156I3J197D01*
G01X387933Y113207D02*
G03X388072Y113150I138J140D01*
G01X387655Y113485D02*
G03X387516Y113543I-139J-139D01*
G01X387953Y123958D02*
G03X387814Y124016I-140J-139D01*
G01X388913Y122244D02*
G03X389053Y122302I1J197D01*
G01X389273Y122441D02*
G03X389134Y122383I1J-197D01*
G01X392026Y122415D02*
G03X391928Y122441I-98J-171D01*
G01X388035Y123876D02*
G03X388174Y123819I139J140D01*
G01X391928Y120669D02*
G03X392026Y120696I-1J197D01*
G01Y119265D02*
G03X391928Y119291I-98J-171D01*
G01X389273Y125591D02*
G03X389134Y125533I1J-197D01*
G01X392026Y125564D02*
G03X391928Y125591I-100J-170D01*
G01X392026Y116115D02*
G03X391928Y116142I-100J-170D01*
G01X389273D02*
G03X389134Y116084I1J-197D01*
G01X388913Y115945D02*
G03X389053Y116002I1J197D01*
G01X387953Y117659D02*
G03X387814Y117717I-140J-139D01*
G01X388035Y117577D02*
G03X388174Y117520I138J140D01*
G01X390745Y118150D02*
G03X390796Y118156I3J197D01*
G01X387933Y118207D02*
G03X388072Y118150I138J140D01*
G01X387655Y118485D02*
G03X387516Y118543I-139J-139D01*
G01Y115315D02*
G03X387655Y115372I0J197D01*
G01X388072Y115709D02*
G03X387933Y115651I1J-197D01*
G01X390796Y115702D02*
G03X390745Y115709I-52J-190D01*
G01X396613Y114350D02*
G03X396990Y114272I197J1D01*
G01Y113091D02*
G03X396613Y113012I-180J-79D01*
G01X396990Y116240D02*
G03X396613Y116161I-180J-79D01*
G01Y117500D02*
G03X396990Y117421I197J0D01*
G01Y122539D02*
G03X396613Y122460I-180J-79D01*
G01Y123799D02*
G03X396990Y123720I197J0D01*
G01X396613Y120650D02*
G03X396990Y120571I197J0D01*
G01Y119390D02*
G03X396613Y119311I-180J-79D01*
G01X392322Y123910D02*
G03X392269Y123917I-52J-190D01*
G01Y122539D02*
G03X392322Y122546I1J197D01*
G01Y120760D02*
G03X392269Y120768I-56J-189D01*
G01X388035Y127026D02*
G03X388174Y126969I138J140D01*
G01X387953Y127108D02*
G03X387814Y127165I-139J-140D01*
G01X388913Y125394D02*
G03X389053Y125451I1J197D01*
G01X392026Y128714D02*
G03X391928Y128740I-98J-171D01*
G01X396990Y125689D02*
G03X396613Y125610I-180J-79D01*
G01Y126949D02*
G03X396990Y126870I197J0D01*
G01X392322Y127059D02*
G03X392269Y127067I-56J-189D01*
G01Y125689D02*
G03X392322Y125696I1J197D01*
G01X399195Y121063D02*
G03X398818Y120984I-180J-79D01*
G01Y122323D02*
G03X399195Y122244I197J0D01*
G01Y124213D02*
G03X398818Y124134I-180J-79D01*
G01Y125472D02*
G03X399195Y125394I197J1D01*
G01X401972Y112913D02*
G03X402169Y112717I197J1D01*
G01X401972Y117913D02*
G03X402169Y117717I197J1D01*
G01Y116142D02*
G03X401972Y115945I0J-197D01*
G01X398818Y128622D02*
G03X399195Y128543I197J0D01*
G01Y127362D02*
G03X398818Y127283I-180J-79D01*
G01X399633Y125689D02*
X399712Y125846D01*
G01X400394D02*
X400315Y125689D01*
G01X391141Y115079D02*
Y113780D01*
G01Y119882D02*
Y118780D01*
G01X388995Y128543D02*
X389192Y128740D01*
G01X389053Y125451D02*
X389134Y125533D01*
G01X389053Y122302D02*
X389134Y122383D01*
G01X388995Y119095D02*
X389192Y119291D01*
G01X387655Y115372D02*
X387933Y115651D01*
G01X389053Y116002D02*
X389134Y116084D01*
G01X388995Y112795D02*
X389192Y112992D01*
G01X401851Y128682D02*
X401799Y128601D01*
G01X402402D02*
X402454Y128682D01*
G01X401888Y125591D02*
X401762Y125394D01*
G01X402365D02*
X402491Y125591D01*
G01X401888Y122441D02*
X401762Y122244D01*
G01X402365D02*
X402491Y122441D01*
G01X399633Y122539D02*
X399712Y122697D01*
G01X400394D02*
X400315Y122539D01*
G01X399633Y119390D02*
X399712Y119547D01*
G01X400394D02*
X400315Y119390D01*
G01X399633Y116240D02*
X399712Y116398D01*
G01X400394D02*
X400315Y116240D01*
G01X399633Y113091D02*
X399712Y113248D01*
G01X400394D02*
X400315Y113091D01*
G01X396613Y113012D02*
Y112493D01*
G01Y114878D02*
Y114350D01*
G01Y116161D02*
Y115642D01*
G01Y118028D02*
Y117500D01*
G01Y119311D02*
Y118792D01*
G01Y122460D02*
Y121941D01*
G01Y124327D02*
Y123799D01*
G01Y125610D02*
Y125091D01*
G01Y127477D02*
Y126949D01*
G01Y128760D02*
Y128241D01*
G01Y120650D02*
Y121178D01*
G01X396849Y117776D02*
Y141083D01*
G01X397221Y125689D02*
Y126870D01*
G01Y122539D02*
Y123720D01*
G01Y119390D02*
Y120571D01*
G01Y116240D02*
Y117421D01*
G01Y113091D02*
Y114272D01*
G01X398074D02*
Y113091D01*
G01Y117421D02*
Y116240D01*
G01Y120571D02*
Y119390D01*
G01Y123720D02*
Y122539D01*
G01Y126870D02*
Y125689D01*
G01X398756D02*
Y126870D01*
G01Y122539D02*
Y123720D01*
G01Y119390D02*
Y120571D01*
G01Y116240D02*
Y117421D01*
G01Y113091D02*
Y114272D01*
G01X398818Y120984D02*
Y120456D01*
G01Y122842D02*
Y122323D01*
G01Y124134D02*
Y123606D01*
G01Y125992D02*
Y125472D01*
G01Y127283D02*
Y126755D01*
G01Y129141D02*
Y128622D01*
G01X399999Y127362D02*
Y128543D01*
G01Y124213D02*
Y125394D01*
G01Y121063D02*
Y122244D01*
G01X400378Y125846D02*
Y126713D01*
G01Y122697D02*
Y123563D01*
G01Y119547D02*
Y120413D01*
G01Y116398D02*
Y117264D01*
G01Y113248D02*
Y114114D01*
G01X400753Y127362D02*
Y128543D01*
G01Y124213D02*
Y125394D01*
G01Y121063D02*
Y122244D01*
G01X401059Y114114D02*
Y113248D01*
G01Y117264D02*
Y116398D01*
G01Y120413D02*
Y119547D01*
G01Y123563D02*
Y122697D01*
G01Y126713D02*
Y125846D01*
G01X401220Y127047D02*
Y128858D01*
G01Y123898D02*
Y125709D01*
G01Y120748D02*
Y122559D01*
G01X401356Y128543D02*
Y127362D01*
G01Y124213D02*
Y125394D01*
G01Y121063D02*
Y122244D01*
G01X401912Y125846D02*
Y126713D01*
G01Y122697D02*
Y123563D01*
G01Y119547D02*
Y120413D01*
G01Y116398D02*
Y117264D01*
G01Y113248D02*
Y114114D01*
G01X401972Y113898D02*
Y112913D01*
G01Y115945D02*
Y114961D01*
G01Y117913D02*
Y118898D01*
G01X392322Y127165D02*
X392026Y126995D01*
G01X399712Y114114D02*
X399633Y114272D01*
G01X400315D02*
X400394Y114114D01*
G01X399712Y117264D02*
X399633Y117421D01*
G01X400315D02*
X400394Y117264D01*
G01X399712Y120413D02*
X399633Y120571D01*
G01X400315D02*
X400394Y120413D01*
G01X399712Y123563D02*
X399633Y123720D01*
G01X400315D02*
X400394Y123563D01*
G01X399712Y126713D02*
X399633Y126870D01*
G01X400315D02*
X400394Y126713D01*
G01X392322Y124016D02*
X392026Y123845D01*
G01X392322Y120866D02*
X392026Y120696D01*
G01X392322Y117717D02*
X392026Y117546D01*
G01X392322Y114567D02*
X392026Y114396D01*
G01X401762Y121063D02*
X401888Y120866D01*
G01X402491D02*
X402365Y121063D01*
G01X401762Y124213D02*
X401888Y124016D01*
G01X402491D02*
X402365Y124213D01*
G01X401799Y127304D02*
X401851Y127223D01*
G01X402454D02*
X402402Y127304D01*
G01X387933Y113207D02*
X387655Y113485D01*
G01X388011Y114370D02*
X387814Y114567D01*
G01X388035Y117577D02*
X387953Y117659D01*
G01X387933Y118207D02*
X387655Y118485D01*
G01X388011Y120669D02*
X387814Y120866D01*
G01X388035Y123876D02*
X387953Y123958D01*
G01X388035Y127026D02*
X387953Y127108D01*
G01X392026Y112966D02*
X392322Y112795D01*
G01X392026Y116115D02*
X392322Y115945D01*
G01X392026Y119265D02*
X392322Y119095D01*
G01X392026Y122415D02*
X392322Y122244D01*
G01X392026Y125564D02*
X392322Y125394D01*
G01X392026Y128714D02*
X392322Y128543D01*
G01X390796Y115702D02*
X392322Y115293D01*
G01X396416Y112493D02*
X396613D01*
G01X404721Y112717D02*
X402169D01*
G01X391928Y112992D02*
X389192D01*
G01X400315Y113091D02*
X396990D01*
G01X388072Y113150D02*
X390745D01*
G01X404668Y113248D02*
X399712D01*
G01X391141Y113780D02*
X392322D01*
G01X398621Y113898D02*
X401972D01*
G01X399712Y114114D02*
X404668D01*
G01X400315Y114272D02*
X396990D01*
G01X388011Y114370D02*
X391928D01*
G01X396416Y114878D02*
X396613D01*
G01X401972Y114961D02*
X398621D01*
G01X391141Y115079D02*
X392322D01*
G01X396613Y115642D02*
X396416D01*
G01X390745Y115709D02*
X388072D01*
G01X391928Y116142D02*
X389273D01*
G01X404721D02*
X402169D01*
G01X400315Y116240D02*
X396990D01*
G01X404668Y116398D02*
X399712D01*
G01Y117264D02*
X404668D01*
G01X400315Y117421D02*
X396990D01*
G01X391928Y117520D02*
X388174D01*
G01X404721Y117717D02*
X402169D01*
G01X396416Y117776D02*
X396849D01*
G01X396416Y118028D02*
X396613D01*
G01X388072Y118150D02*
X390745D01*
G01X392322Y118780D02*
X391141D01*
G01X396416Y118792D02*
X396613D01*
G01X398621Y118898D02*
X401972D01*
G01X391928Y119291D02*
X389192D01*
G01X400315Y119390D02*
X396990D01*
G01X404668Y119547D02*
X399712D01*
G01X404526Y120079D02*
X398621D01*
G01X399712Y120413D02*
X404668D01*
G01X398818Y120456D02*
X398621D01*
G01X400315Y120571D02*
X396990D01*
G01X388011Y120669D02*
X391928D01*
G01X401220Y120748D02*
X404526D01*
G01X410309Y120866D02*
X401888D01*
G01X402365Y121063D02*
X399195D01*
G01X396613Y121178D02*
X396416D01*
G01X396613Y121941D02*
X396416D01*
G01X402365Y122244D02*
X399195D01*
G01X391928Y122441D02*
X389273D01*
G01X410309D02*
X401888D01*
G01X400315Y122539D02*
X396990D01*
G01X404526Y122559D02*
X401220D01*
G01X404668Y122697D02*
X399712D01*
G01X398621Y122842D02*
X398818D01*
G01X399712Y123563D02*
X404668D01*
G01X398818Y123606D02*
X398621D01*
G01X400315Y123720D02*
X396990D01*
G01X391928Y123819D02*
X388174D01*
G01X401220Y123898D02*
X404526D01*
G01X410309Y124016D02*
X401888D01*
G01X402365Y124213D02*
X399195D01*
G01X396416Y124327D02*
X396613D01*
G01Y125091D02*
X396416D01*
G01X402365Y125394D02*
X399195D01*
G01X391928Y125591D02*
X389273D01*
G01X410309D02*
X401888D01*
G01X400315Y125689D02*
X396990D01*
G01X404526Y125709D02*
X401220D01*
G01X404668Y125846D02*
X399712D01*
G01X398621Y125992D02*
X398818D01*
G01X399712Y126713D02*
X404668D01*
G01X398621Y126755D02*
X398818D01*
G01X400315Y126870D02*
X396990D01*
G01X391928Y126969D02*
X388174D01*
G01X401220Y127047D02*
X404526D01*
G01X410309Y127165D02*
X401941D01*
G01X401851Y127223D02*
X402454D01*
G01X402402Y127304D02*
X401799D01*
G01X402313Y127362D02*
X399195D01*
G01X396416Y127477D02*
X396613D01*
G01X396416Y128241D02*
X396613D01*
G01X402313Y128543D02*
X399195D01*
G01X401799Y128601D02*
X402402D01*
G01X402454Y128682D02*
X401851D01*
G01X391928Y128740D02*
X389192D01*
G01X410309D02*
X401941D01*
G01X392322Y113565D02*
X390796Y113156D01*
G01X392322Y118565D02*
X390796Y118156D01*
G01X401878Y138163D02*
X401851Y138131D01*
G01X401908Y138182D02*
X401878Y138163D01*
G01X401941Y138189D02*
X401908Y138182D01*
G01X402376Y138019D02*
X402402Y138050D01*
G01X402345Y137999D02*
X402376Y138019D01*
G01X402313Y137992D02*
X402345Y137999D01*
G01X401773Y136785D02*
X401799Y136753D01*
G01X401742Y136804D02*
X401773Y136785D01*
G01X401709Y136811D02*
X401742Y136804D01*
G01X402481Y136641D02*
X402454Y136672D01*
G01X402511Y136621D02*
X402481Y136641D01*
G01X402544Y136614D02*
X402511Y136621D01*
G01X402345Y136804D02*
X402313Y136811D01*
G01X402376Y136785D02*
X402345Y136804D01*
G01X402402Y136753D02*
X402376Y136785D01*
G01X401908Y136621D02*
X401941Y136614D01*
G01X401878Y136641D02*
X401908Y136621D01*
G01X401851Y136672D02*
X401878Y136641D01*
G01X391962Y133270D02*
X391928Y133268D01*
G01X391995Y133280D02*
X391962Y133270D01*
G01X392026Y133294D02*
X391995Y133280D01*
G01X391962Y136420D02*
X391928Y136417D01*
G01X391995Y136429D02*
X391962Y136420D01*
G01X392026Y136444D02*
X391995Y136429D01*
G01X391962Y142719D02*
X391928Y142717D01*
G01X391995Y142728D02*
X391962Y142719D01*
G01X392026Y142743D02*
X391995Y142728D01*
G01X402511Y138182D02*
X402544Y138189D01*
G01X402481Y138163D02*
X402511Y138182D01*
G01X402454Y138131D02*
X402481Y138163D01*
G01X401742Y137999D02*
X401709Y137992D01*
G01X401773Y138019D02*
X401742Y137999D01*
G01X401799Y138050D02*
X401773Y138019D01*
G01X391928Y130118D02*
G03X392026Y130145I-1J196D01*
G01X388035Y133325D02*
G03X388174Y133268I138J140D01*
G01X387953Y133407D02*
G03X387814Y133465I-140J-139D01*
G01X388913Y131693D02*
G03X389053Y131750I1J197D01*
G01X389273Y131890D02*
G03X389134Y131832I1J-197D01*
G01X392026Y131863D02*
G03X391928Y131890I-100J-170D01*
G01X388913Y134843D02*
G03X389053Y134900I2J197D01*
G01X389273Y135039D02*
G03X389134Y134982I0J-197D01*
G01X392026Y135013D02*
G03X391928Y135039I-98J-171D01*
G01X388035Y136475D02*
G03X388174Y136417I140J139D01*
G01X387953Y136556D02*
G03X387814Y136614I-139J-139D01*
G01X392026Y138163D02*
G03X391928Y138189I-98J-171D01*
G01Y139567D02*
G03X392026Y139593I0J197D01*
G01X388035Y142774D02*
G03X388174Y142717I138J140D01*
G01X387953Y142856D02*
G03X387814Y142913I-139J-140D01*
G01X388913Y141142D02*
G03X389053Y141199I1J197D01*
G01X389273Y141339D02*
G03X389134Y141281I1J-197D01*
G01X392026Y141312D02*
G03X391928Y141339I-100J-170D01*
G01X392026Y144462D02*
G03X391928Y144488I-98J-171D01*
G01X390745Y143150D02*
G03X390796Y143156I3J197D01*
G01X387933Y143207D02*
G03X388072Y143150I138J140D01*
G01X387655Y143485D02*
G03X387516Y143543I-139J-139D01*
G01Y140315D02*
G03X387655Y140372I0J197D01*
G01X388072Y140709D02*
G03X387933Y140651I1J-197D01*
G01X390796Y140702D02*
G03X390745Y140709I-52J-190D01*
G01X396990Y135138D02*
G03X396613Y135059I-180J-79D01*
G01X396990Y131988D02*
G03X396613Y131909I-180J-79D01*
G01Y133248D02*
G03X396990Y133169I197J0D01*
G01X396613Y130098D02*
G03X396990Y130020I197J1D01*
G01Y128839D02*
G03X396613Y128760I-180J-79D01*
G01X392269Y135138D02*
G03X392322Y135145I1J197D01*
G01Y133359D02*
G03X392269Y133366I-52J-190D01*
G01Y131988D02*
G03X392322Y131995I1J197D01*
G01Y130209D02*
G03X392269Y130217I-56J-189D01*
G01Y128839D02*
G03X392322Y128846I1J197D01*
G01X396613Y136398D02*
G03X396990Y136319I197J0D01*
G01Y141437D02*
G03X396613Y141358I-180J-79D01*
G01Y142697D02*
G03X396990Y142618I197J0D01*
G01Y144587D02*
G03X396613Y144508I-180J-79D01*
G01Y139547D02*
G03X396990Y139469I197J1D01*
G01Y138287D02*
G03X396613Y138209I-180J-79D01*
G01X392269Y138287D02*
G03X392322Y138295I-3J197D01*
G01Y136508D02*
G03X392269Y136516I-56J-189D01*
G01X398818Y138071D02*
G03X399195Y137992I197J0D01*
G01Y136811D02*
G03X398818Y136732I-180J-79D01*
G01X399195Y130512D02*
G03X398818Y130433I-180J-79D01*
G01Y131772D02*
G03X399195Y131693I197J0D01*
G01Y133661D02*
G03X398818Y133583I-180J-79D01*
G01Y134921D02*
G03X399195Y134843I197J0D01*
G01X401972Y142913D02*
G03X402169Y142717I197J1D01*
G01Y141142D02*
G03X401972Y140945I0J-197D01*
G01X388995Y144291D02*
X389192Y144488D01*
G01X387655Y140372D02*
X387933Y140651D01*
G01X389053Y141199D02*
X389134Y141281D01*
G01X388995Y137992D02*
X389192Y138189D01*
G01X389053Y134900D02*
X389134Y134982D01*
G01X401851Y138131D02*
X401799Y138050D01*
G01X402402D02*
X402454Y138131D01*
G01X401888Y135039D02*
X401762Y134843D01*
G01X402365D02*
X402491Y135039D01*
G01X399633Y144587D02*
X399712Y144744D01*
G01X400394D02*
X400315Y144587D01*
G01X399633Y141437D02*
X399712Y141595D01*
G01X400394D02*
X400315Y141437D01*
G01X399633Y138287D02*
X399712Y138445D01*
G01X400394D02*
X400315Y138287D01*
G01X399633Y135138D02*
X399712Y135295D01*
G01X400394D02*
X400315Y135138D01*
G01X399633Y131988D02*
X399712Y132146D01*
G01X400394D02*
X400315Y131988D01*
G01X399633Y128839D02*
X399712Y128996D01*
G01X400394D02*
X400315Y128839D01*
G01X391141Y143780D02*
Y145079D01*
G01Y138976D02*
Y140079D01*
G01X389053Y131750D02*
X389134Y131832D01*
G01X401888Y131890D02*
X401762Y131693D01*
G01X402365D02*
X402491Y131890D01*
G01X396613Y131909D02*
Y131390D01*
G01Y133776D02*
Y133248D01*
G01Y135059D02*
Y134540D01*
G01Y136926D02*
Y136398D01*
G01Y138209D02*
Y137689D01*
G01Y141358D02*
Y140839D01*
G01Y143225D02*
Y142697D01*
G01Y144508D02*
Y143989D01*
G01Y139547D02*
Y140075D01*
G01Y130098D02*
Y130626D01*
G01X397221Y144587D02*
Y145768D01*
G01Y141437D02*
Y142618D01*
G01Y138287D02*
Y139469D01*
G01Y135138D02*
Y136319D01*
G01Y131988D02*
Y133169D01*
G01Y128839D02*
Y130020D01*
G01X398074D02*
Y128839D01*
G01Y133169D02*
Y131988D01*
G01Y136319D02*
Y135138D01*
G01Y139469D02*
Y138287D01*
G01Y142618D02*
Y141437D01*
G01Y145768D02*
Y144587D01*
G01X398756D02*
Y145768D01*
G01Y141437D02*
Y142618D01*
G01Y138287D02*
Y139469D01*
G01Y135138D02*
Y136319D01*
G01Y131988D02*
Y133169D01*
G01Y128839D02*
Y130020D01*
G01X398818Y130433D02*
Y129905D01*
G01Y132291D02*
Y131772D01*
G01Y133583D02*
Y133054D01*
G01Y136732D02*
Y136204D01*
G01Y135441D02*
Y134921D01*
G01Y138590D02*
Y138071D01*
G01X399999Y136811D02*
Y137992D01*
G01Y133661D02*
Y134843D01*
G01Y130512D02*
Y131693D01*
G01X400378Y144744D02*
Y145610D01*
G01Y141595D02*
Y142461D01*
G01Y138445D02*
Y139311D01*
G01Y135295D02*
Y136161D01*
G01Y132146D02*
Y133012D01*
G01Y128996D02*
Y129862D01*
G01X400753Y136811D02*
Y137992D01*
G01Y133661D02*
Y134843D01*
G01Y130512D02*
Y131693D01*
G01X401059Y129862D02*
Y128996D01*
G01Y133012D02*
Y132146D01*
G01Y136161D02*
Y135295D01*
G01Y139311D02*
Y138445D01*
G01Y142461D02*
Y141595D01*
G01Y145610D02*
Y144744D01*
G01X401220Y136496D02*
Y138307D01*
G01Y133346D02*
Y135158D01*
G01Y130197D02*
Y132008D01*
G01X401356Y137992D02*
Y136811D01*
G01Y133661D02*
Y134843D01*
G01Y130512D02*
Y131693D01*
G01X401912Y144744D02*
Y145610D01*
G01Y141595D02*
Y142461D01*
G01Y138445D02*
Y139311D01*
G01Y135295D02*
Y136161D01*
G01Y132146D02*
Y133012D01*
G01Y128996D02*
Y129862D01*
G01X401972Y140945D02*
Y139961D01*
G01Y143898D02*
Y142913D01*
G01Y145945D02*
Y144961D01*
G01X392322Y142913D02*
X392026Y142743D01*
G01X392322Y139764D02*
X392026Y139593D01*
G01X392322Y136614D02*
X392026Y136444D01*
G01X392322Y133465D02*
X392026Y133294D01*
G01X392322Y130315D02*
X392026Y130145D01*
G01X399712Y129862D02*
X399633Y130020D01*
G01X400315D02*
X400394Y129862D01*
G01X399712Y133012D02*
X399633Y133169D01*
G01X400315D02*
X400394Y133012D01*
G01X399712Y136161D02*
X399633Y136319D01*
G01X400315D02*
X400394Y136161D01*
G01X399712Y139311D02*
X399633Y139469D01*
G01X400315D02*
X400394Y139311D01*
G01X399712Y142461D02*
X399633Y142618D01*
G01X400315D02*
X400394Y142461D01*
G01X401762Y130512D02*
X401888Y130315D01*
G01X402491D02*
X402365Y130512D01*
G01X401762Y133661D02*
X401888Y133465D01*
G01X402491D02*
X402365Y133661D01*
G01X401799Y136753D02*
X401851Y136672D01*
G01X402454D02*
X402402Y136753D01*
G01X388011Y130118D02*
X387814Y130315D01*
G01X388035Y133325D02*
X387953Y133407D01*
G01X388035Y136475D02*
X387953Y136556D01*
G01X388011Y139567D02*
X387814Y139764D01*
G01X388035Y142774D02*
X387953Y142856D01*
G01X387933Y143207D02*
X387655Y143485D01*
G01X392026Y131863D02*
X392322Y131693D01*
G01X392026Y135013D02*
X392322Y134843D01*
G01X392026Y138163D02*
X392322Y137992D01*
G01X392026Y141312D02*
X392322Y141142D01*
G01X392026Y144462D02*
X392322Y144291D01*
G01X390796Y140702D02*
X392322Y140293D01*
G01X400315Y128839D02*
X396990D01*
G01X404526Y128858D02*
X401220D01*
G01X404668Y128996D02*
X399712D01*
G01X398621Y129141D02*
X398818D01*
G01X399712Y129862D02*
X404668D01*
G01X398818Y129905D02*
X398621D01*
G01X400315Y130020D02*
X396990D01*
G01X388011Y130118D02*
X391928D01*
G01X401220Y130197D02*
X404526D01*
G01X410309Y130315D02*
X401888D01*
G01X402365Y130512D02*
X399195D01*
G01X396613Y130626D02*
X396416D01*
G01X396613Y131390D02*
X396416D01*
G01X402365Y131693D02*
X399195D01*
G01X391928Y131890D02*
X389273D01*
G01X410309D02*
X401888D01*
G01X400315Y131988D02*
X396990D01*
G01X404526Y132008D02*
X401220D01*
G01X404668Y132146D02*
X399712D01*
G01X398621Y132291D02*
X398818D01*
G01X399712Y133012D02*
X404668D01*
G01X398818Y133054D02*
X398621D01*
G01X400315Y133169D02*
X396990D01*
G01X391928Y133268D02*
X388174D01*
G01X401220Y133346D02*
X404526D01*
G01X410309Y133465D02*
X401888D01*
G01X402365Y133661D02*
X399195D01*
G01X396416Y133776D02*
X396613D01*
G01Y134540D02*
X396416D01*
G01X402365Y134843D02*
X399195D01*
G01X391928Y135039D02*
X389273D01*
G01X410309D02*
X401888D01*
G01X400315Y135138D02*
X396990D01*
G01X404526Y135158D02*
X401220D01*
G01X404668Y135295D02*
X399712D01*
G01X398621Y135441D02*
X398818D01*
G01X399712Y136161D02*
X404668D01*
G01X398621Y136204D02*
X398818D01*
G01X400315Y136319D02*
X396990D01*
G01X391928Y136417D02*
X388174D01*
G01X401220Y136496D02*
X404526D01*
G01X410309Y136614D02*
X401941D01*
G01X401851Y136672D02*
X402454D01*
G01X402402Y136753D02*
X401799D01*
G01X402313Y136811D02*
X399195D01*
G01X396416Y136926D02*
X396613D01*
G01X396416Y137689D02*
X396613D01*
G01X402313Y137992D02*
X399195D01*
G01X401799Y138050D02*
X402402D01*
G01X402454Y138131D02*
X401851D01*
G01X391928Y138189D02*
X389192D01*
G01X410309D02*
X401941D01*
G01X400315Y138287D02*
X396990D01*
G01X404526Y138307D02*
X401220D01*
G01X404668Y138445D02*
X399712D01*
G01X398621Y138590D02*
X398818D01*
G01X398621Y138976D02*
X404526D01*
G01X399712Y139311D02*
X404668D01*
G01X400315Y139469D02*
X396990D01*
G01X388011Y139567D02*
X391928D01*
G01X401972Y139961D02*
X398621D01*
G01X396613Y140075D02*
X396416D01*
G01X392322Y140079D02*
X391141D01*
G01X390745Y140709D02*
X388072D01*
G01X396613Y140839D02*
X396416D01*
G01Y141083D02*
X396849D01*
G01X404721Y141142D02*
X402169D01*
G01X391928Y141339D02*
X389273D01*
G01X400315Y141437D02*
X396990D01*
G01X404668Y141595D02*
X399712D01*
G01Y142461D02*
X404668D01*
G01X400315Y142618D02*
X396990D01*
G01X391928Y142717D02*
X388174D01*
G01X404721D02*
X402169D01*
G01X388072Y143150D02*
X390745D01*
G01X396416Y143225D02*
X396613D01*
G01X392322Y143780D02*
X391141D01*
G01X401972Y143898D02*
X398621D01*
G01X396416Y143989D02*
X396613D01*
G01X391928Y144488D02*
X389192D01*
G01X400315Y144587D02*
X396990D01*
G01X404668Y144744D02*
X399712D01*
G01X401972Y144961D02*
X398621D01*
G01X391141Y145079D02*
X392322D01*
G01Y143565D02*
X390796Y143156D01*
G01X391962Y149019D02*
X391928Y149016D01*
G01X391995Y149028D02*
X391962Y149019D01*
G01X392026Y149042D02*
X391995Y149028D01*
G01X391962Y152168D02*
X391928Y152165D01*
G01X391995Y152177D02*
X391962Y152168D01*
G01X392026Y152192D02*
X391995Y152177D01*
G01X391962Y158467D02*
X391928Y158465D01*
G01X391995Y158476D02*
X391962Y158467D01*
G01X392026Y158491D02*
X391995Y158476D01*
G01X391962Y161617D02*
X391928Y161614D01*
G01X391995Y161626D02*
X391962Y161617D01*
G01X392026Y161641D02*
X391995Y161626D01*
G01X391928Y145866D02*
G03X392026Y145893I-1J196D01*
G01X387516Y145315D02*
G03X387655Y145372I0J197D01*
G01X388072Y145709D02*
G03X387933Y145651I1J-197D01*
G01X390796Y145702D02*
G03X390745Y145709I-52J-190D01*
G01X396613Y145846D02*
G03X396990Y145768I197J1D01*
G01X388035Y149073D02*
G03X388174Y149016I138J140D01*
G01X387953Y149155D02*
G03X387814Y149213I-140J-139D01*
G01X388913Y147441D02*
G03X389053Y147498I1J197D01*
G01X389273Y147638D02*
G03X389134Y147580I1J-197D01*
G01X392026Y147611D02*
G03X391928Y147638I-99J-170D01*
G01X388035Y152223D02*
G03X388174Y152165I140J139D01*
G01X387953Y152304D02*
G03X387814Y152362I-139J-139D01*
G01X388913Y150591D02*
G03X389053Y150648I2J197D01*
G01X389273Y150787D02*
G03X389134Y150730I0J-197D01*
G01X392026Y150761D02*
G03X391928Y150787I-98J-171D01*
G01X392026Y153911D02*
G03X391928Y153937I-98J-171D01*
G01Y155315D02*
G03X392026Y155341I0J197D01*
G01X388913Y156890D02*
G03X389053Y156947I1J197D01*
G01X389273Y157087D02*
G03X389134Y157029I1J-197D01*
G01X392026Y157060D02*
G03X391928Y157087I-100J-170D01*
G01X390745Y148150D02*
G03X390796Y148156I3J197D01*
G01X387933Y148207D02*
G03X388072Y148150I138J140D01*
G01X387655Y148485D02*
G03X387516Y148543I-139J-139D01*
G01Y155315D02*
G03X387655Y155372I0J197D01*
G01X388072Y155709D02*
G03X387933Y155651I1J-197D01*
G01X390796Y155702D02*
G03X390745Y155709I-52J-190D01*
G01Y153150D02*
G03X390796Y153156I3J197D01*
G01X387933Y153207D02*
G03X388072Y153150I138J140D01*
G01X387655Y153485D02*
G03X387516Y153543I-139J-139D01*
G01Y150315D02*
G03X387655Y150372I0J197D01*
G01X388072Y150709D02*
G03X387933Y150651I1J-197D01*
G01X390796Y150702D02*
G03X390745Y150709I-52J-190D01*
G01X388035Y158522D02*
G03X388174Y158465I138J140D01*
G01X387953Y158604D02*
G03X387814Y158661I-139J-140D01*
G01X388035Y161672D02*
G03X388174Y161614I139J139D01*
G01X387953Y161753D02*
G03X387814Y161811I-140J-139D01*
G01X388913Y160039D02*
G03X389053Y160097I0J197D01*
G01X389273Y160236D02*
G03X389134Y160178I1J-197D01*
G01X392026Y160210D02*
G03X391928Y160236I-98J-171D01*
G01X387516Y160315D02*
G03X387655Y160372I0J197D01*
G01X388072Y160709D02*
G03X387933Y160651I1J-197D01*
G01X390796Y160702D02*
G03X390745Y160709I-52J-190D01*
G01Y158150D02*
G03X390796Y158156I3J197D01*
G01X387933Y158207D02*
G03X388072Y158150I138J140D01*
G01X387655Y158485D02*
G03X387516Y158543I-139J-139D01*
G01X396990Y150886D02*
G03X396613Y150807I-180J-79D01*
G01Y152146D02*
G03X396990Y152067I197J0D01*
G01Y157185D02*
G03X396613Y157106I-180J-79D01*
G01X396990Y147736D02*
G03X396613Y147657I-180J-79D01*
G01Y148996D02*
G03X396990Y148917I197J0D01*
G01X396613Y155295D02*
G03X396990Y155217I197J1D01*
G01Y154035D02*
G03X396613Y153957I-180J-79D01*
G01X396990Y160335D02*
G03X396613Y160256I-180J-79D01*
G01Y161595D02*
G03X396990Y161516I197J0D01*
G01X396613Y158445D02*
G03X396990Y158366I197J0D01*
G01X401972Y147913D02*
G03X402169Y147717I197J1D01*
G01Y146142D02*
G03X401972Y145945I0J-197D01*
G01Y157913D02*
G03X402169Y157717I197J1D01*
G01Y156142D02*
G03X401972Y155945I0J-197D01*
G01Y152913D02*
G03X402169Y152717I197J1D01*
G01Y151142D02*
G03X401972Y150945I0J-197D01*
G01X402169Y161142D02*
G03X401972Y160945I0J-197D01*
G01X387655Y160372D02*
X387933Y160651D01*
G01X389053Y160097D02*
X389134Y160178D01*
G01X389053Y156947D02*
X389134Y157029D01*
G01X387655Y155372D02*
X387933Y155651D01*
G01X388995Y153740D02*
X389192Y153937D01*
G01X387655Y150372D02*
X387933Y150651D01*
G01X389053Y150648D02*
X389134Y150730D01*
G01X389053Y147498D02*
X389134Y147580D01*
G01X387655Y145372D02*
X387933Y145651D01*
G01X399633Y160335D02*
X399712Y160492D01*
G01X400394D02*
X400315Y160335D01*
G01X399633Y157185D02*
X399712Y157343D01*
G01X400394D02*
X400315Y157185D01*
G01X399633Y154035D02*
X399712Y154193D01*
G01X400394D02*
X400315Y154035D01*
G01X399633Y150886D02*
X399712Y151043D01*
G01X400394D02*
X400315Y150886D01*
G01X399633Y147736D02*
X399712Y147894D01*
G01X400394D02*
X400315Y147736D01*
G01X391141Y150079D02*
Y148780D01*
G01Y160079D02*
Y158780D01*
G01Y153780D02*
Y155079D01*
G01X392322Y161811D02*
X392026Y161641D01*
G01X392322Y158661D02*
X392026Y158491D01*
G01X392322Y155512D02*
X392026Y155341D01*
G01X392322Y152362D02*
X392026Y152192D01*
G01X392322Y149213D02*
X392026Y149042D01*
G01X392322Y146063D02*
X392026Y145893D01*
G01X396613Y147657D02*
Y147138D01*
G01Y146374D02*
Y145846D01*
G01Y149524D02*
Y148996D01*
G01Y150807D02*
Y150288D01*
G01Y152674D02*
Y152146D01*
G01Y153957D02*
Y153437D01*
G01Y157106D02*
Y156587D01*
G01Y155823D02*
Y155295D01*
G01Y158973D02*
Y158445D01*
G01Y160256D02*
Y159737D01*
G01Y162122D02*
Y161595D01*
G01X397221Y160335D02*
Y161516D01*
G01Y157185D02*
Y158366D01*
G01Y154035D02*
Y155217D01*
G01Y150886D02*
Y152067D01*
G01Y147736D02*
Y148917D01*
G01X398074D02*
Y147736D01*
G01Y152067D02*
Y150886D01*
G01Y155217D02*
Y154035D01*
G01Y158366D02*
Y157185D01*
G01Y161516D02*
Y160335D01*
G01X398756D02*
Y161516D01*
G01Y157185D02*
Y158366D01*
G01Y154035D02*
Y155217D01*
G01Y150886D02*
Y152067D01*
G01Y147736D02*
Y148917D01*
G01X400378Y160492D02*
Y161358D01*
G01Y157343D02*
Y158209D01*
G01Y154193D02*
Y155059D01*
G01Y151043D02*
Y151909D01*
G01Y147894D02*
Y148760D01*
G01X401059D02*
Y147894D01*
G01Y151909D02*
Y151043D01*
G01Y155059D02*
Y154193D01*
G01Y158209D02*
Y157343D01*
G01Y161358D02*
Y160492D01*
G01X401912D02*
Y161358D01*
G01Y157343D02*
Y158209D01*
G01Y154193D02*
Y155059D01*
G01Y151043D02*
Y151909D01*
G01Y147894D02*
Y148760D01*
G01X401972Y148898D02*
Y147913D01*
G01Y153898D02*
Y152913D01*
G01Y155945D02*
Y154961D01*
G01Y160945D02*
Y159961D01*
G01Y157913D02*
Y158898D01*
G01Y149961D02*
Y150945D01*
G01X399712Y145610D02*
X399633Y145768D01*
G01X400315D02*
X400394Y145610D01*
G01X399712Y148760D02*
X399633Y148917D01*
G01X400315D02*
X400394Y148760D01*
G01X399712Y151909D02*
X399633Y152067D01*
G01X400315D02*
X400394Y151909D01*
G01X399712Y155059D02*
X399633Y155217D01*
G01X400315D02*
X400394Y155059D01*
G01X399712Y158209D02*
X399633Y158366D01*
G01X400315D02*
X400394Y158209D01*
G01X399712Y161358D02*
X399633Y161516D01*
G01X400315D02*
X400394Y161358D01*
G01X388011Y145866D02*
X387814Y146063D01*
G01X387933Y148207D02*
X387655Y148485D01*
G01X388035Y149073D02*
X387953Y149155D01*
G01X388035Y152223D02*
X387953Y152304D01*
G01X387933Y153207D02*
X387655Y153485D01*
G01X388011Y155315D02*
X387814Y155512D01*
G01X387933Y158207D02*
X387655Y158485D01*
G01X388035Y158522D02*
X387953Y158604D01*
G01X388035Y161672D02*
X387953Y161753D01*
G01X392026Y147611D02*
X392322Y147441D01*
G01X392026Y150761D02*
X392322Y150591D01*
G01X392026Y153911D02*
X392322Y153740D01*
G01X392026Y157060D02*
X392322Y156890D01*
G01X392026Y160210D02*
X392322Y160039D01*
G01X390796Y145702D02*
X392322Y145293D01*
G01X390796Y150702D02*
X392322Y150293D01*
G01X390796Y155702D02*
X392322Y155293D01*
G01X390796Y160702D02*
X392322Y160293D01*
G01X399712Y145610D02*
X404668D01*
G01X390745Y145709D02*
X388072D01*
G01X400315Y145768D02*
X396990D01*
G01X388011Y145866D02*
X391928D01*
G01X404721Y146142D02*
X402169D01*
G01X396416Y146374D02*
X396613D01*
G01Y147138D02*
X396416D01*
G01X391928Y147638D02*
X389273D01*
G01X404721Y147717D02*
X402169D01*
G01X400315Y147736D02*
X396990D01*
G01X404668Y147894D02*
X399712D01*
G01X388072Y148150D02*
X390745D01*
G01X399712Y148760D02*
X404668D01*
G01X391141Y148780D02*
X392322D01*
G01X398621Y148898D02*
X401972D01*
G01X400315Y148917D02*
X396990D01*
G01X391928Y149016D02*
X388174D01*
G01X396416Y149524D02*
X396613D01*
G01X401972Y149961D02*
X398621D01*
G01X391141Y150079D02*
X392322D01*
G01X396613Y150288D02*
X396416D01*
G01X390745Y150709D02*
X388072D01*
G01X391928Y150787D02*
X389273D01*
G01X400315Y150886D02*
X396990D01*
G01X404668Y151043D02*
X399712D01*
G01X404721Y151142D02*
X402169D01*
G01X399712Y151909D02*
X404668D01*
G01X400315Y152067D02*
X396990D01*
G01X391928Y152165D02*
X388174D01*
G01X396416Y152674D02*
X396613D01*
G01X404721Y152717D02*
X402169D01*
G01X388072Y153150D02*
X390745D01*
G01X396416Y153437D02*
X396613D01*
G01X391141Y153780D02*
X392322D01*
G01X398621Y153898D02*
X401972D01*
G01X391928Y153937D02*
X389192D01*
G01X400315Y154035D02*
X396990D01*
G01X404668Y154193D02*
X399712D01*
G01X401972Y154961D02*
X398621D01*
G01X399712Y155059D02*
X404668D01*
G01X391141Y155079D02*
X392322D01*
G01X400315Y155217D02*
X396990D01*
G01X388011Y155315D02*
X391928D01*
G01X390745Y155709D02*
X388072D01*
G01X396416Y155823D02*
X396613D01*
G01X404721Y156142D02*
X402169D01*
G01X396613Y156587D02*
X396416D01*
G01X391928Y157087D02*
X389273D01*
G01X400315Y157185D02*
X396990D01*
G01X404668Y157343D02*
X399712D01*
G01X404721Y157717D02*
X402169D01*
G01X388072Y158150D02*
X390745D01*
G01X399712Y158209D02*
X404668D01*
G01X400315Y158366D02*
X396990D01*
G01X391928Y158465D02*
X388174D01*
G01X392322Y158780D02*
X391141D01*
G01X398621Y158898D02*
X401972D01*
G01X396416Y158973D02*
X396613D01*
G01Y159737D02*
X396416D01*
G01X401972Y159961D02*
X398621D01*
G01X391141Y160079D02*
X392322D01*
G01X391928Y160236D02*
X389273D01*
G01X400315Y160335D02*
X396990D01*
G01X404668Y160492D02*
X399712D01*
G01X390745Y160709D02*
X388072D01*
G01X404721Y161142D02*
X402169D01*
G01X399712Y161358D02*
X404668D01*
G01X400315Y161516D02*
X396990D01*
G01X391928Y161614D02*
X388174D01*
G01X392322Y148565D02*
X390796Y148156D01*
G01X392322Y153565D02*
X390796Y153156D01*
G01X391962Y158467D02*
X390796Y158156D01*
G01X392322Y158565D02*
X391995Y158476D01*
G01X391962Y167916D02*
X391928Y167913D01*
G01X391995Y167925D02*
X391962Y167916D01*
G01X392026Y167940D02*
X391995Y167925D01*
G01X391962Y171066D02*
X391928Y171063D01*
G01X391995Y171075D02*
X391962Y171066D01*
G01X392026Y171089D02*
X391995Y171075D01*
G01X391962Y177365D02*
X391928Y177362D01*
G01X391995Y177374D02*
X391962Y177365D01*
G01X392026Y177389D02*
X391995Y177374D01*
G01X392026Y163359D02*
G03X391928Y163386I-99J-170D01*
G01Y164764D02*
G03X392026Y164790I0J197D01*
G01X388035Y167971D02*
G03X388174Y167913I140J139D01*
G01X387953Y168052D02*
G03X387814Y168110I-139J-139D01*
G01X388913Y166339D02*
G03X389053Y166396I2J197D01*
G01X389273Y166535D02*
G03X389134Y166478I0J-197D01*
G01X392026Y166509D02*
G03X391928Y166535I-98J-171D01*
G01X390745Y168150D02*
G03X390796Y168156I3J197D01*
G01X387933Y168207D02*
G03X388072Y168150I138J140D01*
G01X387655Y168485D02*
G03X387516Y168543I-139J-139D01*
G01Y165315D02*
G03X387655Y165372I0J197D01*
G01X388072Y165709D02*
G03X387933Y165651I1J-197D01*
G01X390796Y165702D02*
G03X390745Y165709I-52J-190D01*
G01Y163150D02*
G03X390796Y163156I3J197D01*
G01X387933Y163207D02*
G03X388072Y163150I138J140D01*
G01X387655Y163485D02*
G03X387516Y163543I-139J-139D01*
G01X396990Y166634D02*
G03X396613Y166555I-180J-79D01*
G01Y167894D02*
G03X396990Y167815I197J0D01*
G01X396613Y164744D02*
G03X396990Y164665I197J0D01*
G01Y163484D02*
G03X396613Y163406I-180J-79D01*
G01X401972Y167913D02*
G03X402169Y167717I197J1D01*
G01Y166142D02*
G03X401972Y165945I0J-197D01*
G01Y162913D02*
G03X402169Y162717I197J1D01*
G01X388035Y171120D02*
G03X388174Y171063I139J140D01*
G01X387953Y171202D02*
G03X387814Y171260I-140J-139D01*
G01X388035Y177420D02*
G03X388174Y177362I139J139D01*
G01X387953Y177501D02*
G03X387814Y177559I-140J-139D01*
G01X387933Y178207D02*
G03X388072Y178150I138J140D01*
G01X387516Y175315D02*
G03X387655Y175372I0J197D01*
G01X388072Y175709D02*
G03X387933Y175651I1J-197D01*
G01Y173207D02*
G03X388072Y173150I138J140D01*
G01X387655Y173485D02*
G03X387516Y173543I-139J-139D01*
G01Y170315D02*
G03X387655Y170372I0J197D01*
G01X388072Y170709D02*
G03X387933Y170651I1J-197D01*
G01X388913Y169488D02*
G03X389053Y169546I0J197D01*
G01X389273Y169685D02*
G03X389134Y169627I1J-197D01*
G01X392026Y169659D02*
G03X391928Y169685I-98J-171D01*
G01X392026Y172808D02*
G03X391928Y172835I-100J-170D01*
G01Y174213D02*
G03X392026Y174239I0J197D01*
G01X388913Y175787D02*
G03X389053Y175845I0J197D01*
G01X389273Y175984D02*
G03X389134Y175926I1J-197D01*
G01X392026Y175958D02*
G03X391928Y175984I-98J-171D01*
G01X390745Y178150D02*
G03X390796Y178156I3J197D01*
G01Y175702D02*
G03X390745Y175709I-52J-190D01*
G01Y173150D02*
G03X390796Y173156I3J197D01*
G01Y170702D02*
G03X390745Y170709I-52J-190D01*
G01X396990Y169783D02*
G03X396613Y169704I-180J-79D01*
G01Y171043D02*
G03X396990Y170965I197J1D01*
G01Y176083D02*
G03X396613Y176004I-180J-79D01*
G01Y177343D02*
G03X396990Y177264I197J0D01*
G01X396613Y174193D02*
G03X396990Y174114I197J0D01*
G01Y172933D02*
G03X396613Y172854I-180J-79D01*
G01X401972Y177913D02*
G03X402169Y177717I197J1D01*
G01Y176142D02*
G03X401972Y175945I0J-197D01*
G01Y172913D02*
G03X402169Y172717I197J1D01*
G01Y171142D02*
G03X401972Y170945I0J-197D01*
G01X387655Y175372D02*
X387933Y175651D01*
G01X389053Y175845D02*
X389134Y175926D01*
G01X388995Y172638D02*
X389192Y172835D01*
G01X387655Y170372D02*
X387933Y170651D01*
G01X389053Y169546D02*
X389134Y169627D01*
G01X387655Y165372D02*
X387933Y165651D01*
G01X389053Y166396D02*
X389134Y166478D01*
G01X388995Y163189D02*
X389192Y163386D01*
G01X399633Y176083D02*
X399712Y176240D01*
G01X400394D02*
X400315Y176083D01*
G01X399633Y172933D02*
X399712Y173091D01*
G01X400394D02*
X400315Y172933D01*
G01X399633Y169783D02*
X399712Y169941D01*
G01X400394D02*
X400315Y169783D01*
G01X399633Y166634D02*
X399712Y166791D01*
G01X400394D02*
X400315Y166634D01*
G01X399633Y163484D02*
X399712Y163642D01*
G01X400394D02*
X400315Y163484D01*
G01X392322Y177559D02*
X392026Y177389D01*
G01X392322Y174409D02*
X392026Y174239D01*
G01X392322Y171260D02*
X392026Y171089D01*
G01X392322Y168110D02*
X392026Y167940D01*
G01X392322Y164961D02*
X392026Y164790D01*
G01X391141Y170079D02*
Y168780D01*
G01Y175079D02*
Y173780D01*
G01Y163780D02*
Y165079D01*
G01X396613Y163406D02*
Y162886D01*
G01Y166555D02*
Y166036D01*
G01Y165272D02*
Y164744D01*
G01Y168422D02*
Y167894D01*
G01Y169704D02*
Y169185D01*
G01Y171571D02*
Y171043D01*
G01Y172854D02*
Y172335D01*
G01Y176004D02*
Y175485D01*
G01Y174721D02*
Y174193D01*
G01Y177870D02*
Y177343D01*
G01X397221Y176083D02*
Y177264D01*
G01Y172933D02*
Y174114D01*
G01Y169783D02*
Y170965D01*
G01Y166634D02*
Y167815D01*
G01Y163484D02*
Y164665D01*
G01X398074D02*
Y163484D01*
G01Y167815D02*
Y166634D01*
G01Y170965D02*
Y169783D01*
G01Y174114D02*
Y172933D01*
G01Y177264D02*
Y176083D01*
G01X398756D02*
Y177264D01*
G01Y172933D02*
Y174114D01*
G01Y169783D02*
Y170965D01*
G01Y166634D02*
Y167815D01*
G01Y163484D02*
Y164665D01*
G01X400378Y176240D02*
Y177106D01*
G01Y173091D02*
Y173957D01*
G01Y169941D02*
Y170807D01*
G01Y166791D02*
Y167658D01*
G01Y163642D02*
Y164508D01*
G01X401059D02*
Y163642D01*
G01Y167658D02*
Y166791D01*
G01Y170807D02*
Y169941D01*
G01Y173957D02*
Y173091D01*
G01Y177106D02*
Y176240D01*
G01X401912D02*
Y177106D01*
G01Y173091D02*
Y173957D01*
G01Y169941D02*
Y170807D01*
G01Y166791D02*
Y167658D01*
G01Y163642D02*
Y164508D01*
G01X401972Y165945D02*
Y164961D01*
G01Y173898D02*
Y172913D01*
G01Y175945D02*
Y174961D01*
G01Y178898D02*
Y177913D01*
G01Y169961D02*
Y170945D01*
G01Y167913D02*
Y168898D01*
G01Y162913D02*
Y163898D01*
G01X399712Y164508D02*
X399633Y164665D01*
G01X400315D02*
X400394Y164508D01*
G01X399712Y167658D02*
X399633Y167815D01*
G01X400315D02*
X400394Y167658D01*
G01X399712Y170807D02*
X399633Y170965D01*
G01X400315D02*
X400394Y170807D01*
G01X399712Y173957D02*
X399633Y174114D01*
G01X400315D02*
X400394Y173957D01*
G01X399712Y177106D02*
X399633Y177264D01*
G01X400315D02*
X400394Y177106D01*
G01X387933Y163207D02*
X387655Y163485D01*
G01X388011Y164764D02*
X387814Y164961D01*
G01X388035Y167971D02*
X387953Y168052D01*
G01X387933Y168207D02*
X387655Y168485D01*
G01X388035Y171120D02*
X387953Y171202D01*
G01X387933Y173207D02*
X387655Y173485D01*
G01X388011Y174213D02*
X387814Y174409D01*
G01X388035Y177420D02*
X387953Y177501D01*
G01X387933Y178207D02*
X387655Y178485D01*
G01X392026Y163359D02*
X392322Y163189D01*
G01X392026Y166509D02*
X392322Y166339D01*
G01X392026Y169659D02*
X392322Y169488D01*
G01X392026Y172808D02*
X392322Y172638D01*
G01X392026Y175958D02*
X392322Y175787D01*
G01X390796Y165702D02*
X392322Y165293D01*
G01X390796Y170702D02*
X392322Y170293D01*
G01X390796Y175702D02*
X392322Y175293D01*
G01X396416Y162122D02*
X396613D01*
G01X404721Y162717D02*
X402169D01*
G01X396416Y162886D02*
X396613D01*
G01X388072Y163150D02*
X390745D01*
G01X391928Y163386D02*
X389192D01*
G01X400315Y163484D02*
X396990D01*
G01X404668Y163642D02*
X399712D01*
G01X391141Y163780D02*
X392322D01*
G01X398621Y163898D02*
X401972D01*
G01X399712Y164508D02*
X404668D01*
G01X400315Y164665D02*
X396990D01*
G01X388011Y164764D02*
X391928D01*
G01X401972Y164961D02*
X398621D01*
G01X392322Y165079D02*
X391141D01*
G01X396416Y165272D02*
X396613D01*
G01X390745Y165709D02*
X388072D01*
G01X396613Y166036D02*
X396416D01*
G01X404721Y166142D02*
X402169D01*
G01X391928Y166535D02*
X389273D01*
G01X400315Y166634D02*
X396990D01*
G01X404668Y166791D02*
X399712D01*
G01Y167658D02*
X404668D01*
G01X404721Y167717D02*
X402169D01*
G01X400315Y167815D02*
X396990D01*
G01X391928Y167913D02*
X388174D01*
G01X388072Y168150D02*
X390745D01*
G01X396416Y168422D02*
X396613D01*
G01X391141Y168780D02*
X392322D01*
G01X398621Y168898D02*
X401972D01*
G01X396613Y169185D02*
X396416D01*
G01X389273Y169685D02*
X391928D01*
G01X400315Y169783D02*
X396990D01*
G01X404668Y169941D02*
X399712D01*
G01X401972Y169961D02*
X398621D01*
G01X392322Y170079D02*
X391141D01*
G01X390745Y170709D02*
X388072D01*
G01X399712Y170807D02*
X404668D01*
G01X400315Y170965D02*
X396990D01*
G01X388174Y171063D02*
X391928D01*
G01X404721Y171142D02*
X402169D01*
G01X396416Y171571D02*
X396613D01*
G01X396416Y172335D02*
X396613D01*
G01X404721Y172717D02*
X402169D01*
G01X391928Y172835D02*
X389192D01*
G01X400315Y172933D02*
X396990D01*
G01X404668Y173091D02*
X399712D01*
G01X388072Y173150D02*
X390745D01*
G01X391141Y173780D02*
X392322D01*
G01X398621Y173898D02*
X401972D01*
G01X399712Y173957D02*
X404668D01*
G01X400315Y174114D02*
X396990D01*
G01X388011Y174213D02*
X391928D01*
G01X396416Y174721D02*
X396613D01*
G01X401972Y174961D02*
X398621D01*
G01X391141Y175079D02*
X392322D01*
G01X396613Y175485D02*
X396416D01*
G01X390745Y175709D02*
X388072D01*
G01X391928Y175984D02*
X389273D01*
G01X400315Y176083D02*
X396990D01*
G01X404721Y176142D02*
X402169D01*
G01X404668Y176240D02*
X399712D01*
G01Y177106D02*
X404668D01*
G01X400315Y177264D02*
X396990D01*
G01X391928Y177362D02*
X388174D01*
G01X404721Y177717D02*
X402169D01*
G01X396416Y177870D02*
X396613D01*
G01X388072Y178150D02*
X390745D01*
G01X392322Y163565D02*
X390796Y163156D01*
G01X392322Y168565D02*
X390796Y168156D01*
G01X392322Y173565D02*
X390796Y173156D01*
G01X392322Y178565D02*
X390796Y178156D01*
G01X391962Y180515D02*
X391928Y180512D01*
G01X391995Y180524D02*
X391962Y180515D01*
G01X392026Y180538D02*
X391995Y180524D01*
G01X391962Y186814D02*
X391928Y186811D01*
G01X391995Y186823D02*
X391962Y186814D01*
G01X392026Y186837D02*
X391995Y186823D01*
G01X391962Y189963D02*
X391928Y189961D01*
G01X391995Y189972D02*
X391962Y189963D01*
G01X392026Y189987D02*
X391995Y189972D01*
G01X387655Y178485D02*
G03X387516Y178543I-139J-139D01*
G01X388035Y180569D02*
G03X388174Y180512I138J140D01*
G01X387953Y180651D02*
G03X387814Y180709I-140J-139D01*
G01X388035Y186869D02*
G03X388174Y186811I139J139D01*
G01X387953Y186950D02*
G03X387814Y187008I-140J-139D01*
G01X388035Y190018D02*
G03X388174Y189961I138J140D01*
G01X387953Y190100D02*
G03X387814Y190158I-140J-139D01*
G01X387516Y190315D02*
G03X387655Y190372I0J197D01*
G01X388072Y190709D02*
G03X387933Y190651I1J-197D01*
G01Y188207D02*
G03X388072Y188150I138J140D01*
G01X387655Y188485D02*
G03X387516Y188543I-139J-139D01*
G01Y185315D02*
G03X387655Y185372I0J197D01*
G01X388072Y185709D02*
G03X387933Y185651I1J-197D01*
G01Y183207D02*
G03X388072Y183150I138J140D01*
G01X387655Y183485D02*
G03X387516Y183543I-139J-139D01*
G01Y180315D02*
G03X387655Y180372I0J197D01*
G01X388072Y180709D02*
G03X387933Y180651I1J-197D01*
G01Y193207D02*
G03X388072Y193150I138J140D01*
G01X387655Y193485D02*
G03X387516Y193543I-139J-139D01*
G01X388913Y178937D02*
G03X389053Y178995I1J197D01*
G01X389273Y179134D02*
G03X389134Y179076I1J-197D01*
G01X392026Y179108D02*
G03X391928Y179134I-98J-171D01*
G01X392026Y182257D02*
G03X391928Y182283I-98J-171D01*
G01Y183661D02*
G03X392026Y183688I-1J197D01*
G01X388913Y185236D02*
G03X389053Y185294I0J197D01*
G01X389273Y185433D02*
G03X389134Y185375I1J-197D01*
G01X392026Y185407D02*
G03X391928Y185433I-98J-171D01*
G01X388913Y188386D02*
G03X389053Y188443I1J197D01*
G01X389273Y188583D02*
G03X389134Y188525I1J-197D01*
G01X392026Y188556D02*
G03X391928Y188583I-100J-170D01*
G01X390796Y190702D02*
G03X390745Y190709I-52J-190D01*
G01Y188150D02*
G03X390796Y188156I3J197D01*
G01Y185702D02*
G03X390745Y185709I-52J-190D01*
G01Y183150D02*
G03X390796Y183156I3J197D01*
G01Y180702D02*
G03X390745Y180709I-52J-190D01*
G01X396990Y179232D02*
G03X396613Y179153I-180J-79D01*
G01X396990Y188681D02*
G03X396613Y188602I-180J-79D01*
G01Y189941D02*
G03X396990Y189862I197J0D01*
G01X396613Y180492D02*
G03X396990Y180413I197J0D01*
G01Y185532D02*
G03X396613Y185452I-180J-79D01*
G01Y186791D02*
G03X396990Y186713I197J1D01*
G01X396613Y183642D02*
G03X396990Y183563I197J0D01*
G01Y182382D02*
G03X396613Y182303I-180J-79D01*
G01X401972Y182913D02*
G03X402169Y182717I197J1D01*
G01Y181142D02*
G03X401972Y180945I0J-197D01*
G01Y187913D02*
G03X402169Y187717I197J1D01*
G01Y186142D02*
G03X401972Y185945I0J-197D01*
G01X392026Y191706D02*
G03X391928Y191732I-98J-171D01*
G01Y193110D02*
G03X392026Y193137I-1J197D01*
G01X388913Y194685D02*
G03X389053Y194743I1J197D01*
G01X390745Y193150D02*
G03X390796Y193156I3J197D01*
G01X396613Y193091D02*
G03X396990Y193012I197J0D01*
G01Y191831D02*
G03X396613Y191752I-180J-79D01*
G01X401972Y192913D02*
G03X402169Y192717I197J1D01*
G01Y191142D02*
G03X401972Y190945I0J-197D01*
G01X389053Y194743D02*
X389134Y194824D01*
G01X387655Y190372D02*
X387933Y190651D01*
G01X388995Y191535D02*
X389192Y191732D01*
G01X389053Y188443D02*
X389134Y188525D01*
G01X387655Y185372D02*
X387933Y185651D01*
G01X389053Y185294D02*
X389134Y185375D01*
G01X392322Y193307D02*
X392026Y193137D01*
G01X392322Y190158D02*
X392026Y189987D01*
G01X392322Y187008D02*
X392026Y186837D01*
G01X392322Y183858D02*
X392026Y183688D01*
G01X388995Y182087D02*
X389192Y182283D01*
G01X387655Y180372D02*
X387933Y180651D01*
G01X389053Y178995D02*
X389134Y179076D01*
G01X399633Y191831D02*
X399712Y191988D01*
G01X400394D02*
X400315Y191831D01*
G01X399633Y188681D02*
X399712Y188839D01*
G01X400394D02*
X400315Y188681D01*
G01X399633Y185532D02*
X399712Y185689D01*
G01X400394D02*
X400315Y185532D01*
G01X399633Y182382D02*
X399712Y182539D01*
G01X400394D02*
X400315Y182382D01*
G01X399633Y179232D02*
X399712Y179390D01*
G01X400394D02*
X400315Y179232D01*
G01X392322Y180709D02*
X392026Y180538D01*
G01X391141Y185079D02*
Y183780D01*
G01Y190079D02*
Y188780D01*
G01Y195079D02*
Y193780D01*
G01Y178780D02*
Y180079D01*
G01X396613Y179153D02*
Y178634D01*
G01Y181020D02*
Y180492D01*
G01Y182303D02*
Y181784D01*
G01Y185452D02*
Y184933D01*
G01Y184170D02*
Y183642D01*
G01Y187319D02*
Y186791D01*
G01Y188602D02*
Y188083D01*
G01Y190469D02*
Y189941D01*
G01Y191752D02*
Y191233D01*
G01Y194901D02*
Y194382D01*
G01Y193091D02*
Y193619D01*
G01X397221Y191831D02*
Y193012D01*
G01Y188681D02*
Y189862D01*
G01Y185532D02*
Y186713D01*
G01Y182382D02*
Y183563D01*
G01Y179232D02*
Y180413D01*
G01X398074D02*
Y179232D01*
G01Y183563D02*
Y182382D01*
G01Y186713D02*
Y185532D01*
G01Y189862D02*
Y188681D01*
G01Y193012D02*
Y191831D01*
G01X398601Y183393D02*
Y181307D01*
G01X398756Y191831D02*
Y193012D01*
G01Y188681D02*
Y189862D01*
G01Y185532D02*
Y186713D01*
G01Y182382D02*
Y183563D01*
G01Y179232D02*
Y180413D01*
G01X400378Y191988D02*
Y192854D01*
G01Y188839D02*
Y189705D01*
G01Y185689D02*
Y186555D01*
G01Y182539D02*
Y183406D01*
G01Y179390D02*
Y180256D01*
G01X401059D02*
Y179390D01*
G01Y183406D02*
Y182539D01*
G01Y186555D02*
Y185689D01*
G01Y189705D02*
Y188839D01*
G01Y192854D02*
Y191988D01*
G01X401912D02*
Y192854D01*
G01Y188839D02*
Y189705D01*
G01Y185689D02*
Y186555D01*
G01Y182539D02*
Y183406D01*
G01Y179390D02*
Y180256D01*
G01X401972Y180945D02*
Y179961D01*
G01Y183898D02*
Y182913D01*
G01Y185945D02*
Y184961D01*
G01Y190945D02*
Y189961D01*
G01Y193898D02*
Y192913D01*
G01Y187913D02*
Y188898D01*
G01X399712Y180256D02*
X399633Y180413D01*
G01X400315D02*
X400394Y180256D01*
G01X399712Y183406D02*
X399633Y183563D01*
G01X400315D02*
X400394Y183406D01*
G01X399712Y186555D02*
X399633Y186713D01*
G01X400315D02*
X400394Y186555D01*
G01X399712Y189705D02*
X399633Y189862D01*
G01X400315D02*
X400394Y189705D01*
G01X399712Y192854D02*
X399633Y193012D01*
G01X400315D02*
X400394Y192854D01*
G01X388035Y180569D02*
X387953Y180651D01*
G01X387933Y183207D02*
X387655Y183485D01*
G01X388011Y183661D02*
X387814Y183858D01*
G01X388035Y186869D02*
X387953Y186950D01*
G01X387933Y188207D02*
X387655Y188485D01*
G01X388035Y190018D02*
X387953Y190100D01*
G01X388011Y193110D02*
X387814Y193307D01*
G01X387933Y193207D02*
X387655Y193485D01*
G01X392026Y179108D02*
X392322Y178937D01*
G01X392026Y182257D02*
X392322Y182087D01*
G01X392026Y185407D02*
X392322Y185236D01*
G01X392026Y188556D02*
X392322Y188386D01*
G01X392026Y191706D02*
X392322Y191535D01*
G01X392026Y194856D02*
X392322Y194685D01*
G01X390796Y180702D02*
X392322Y180293D01*
G01X390796Y185702D02*
X392322Y185293D01*
G01X390796Y190702D02*
X392322Y190293D01*
G01X396613Y178634D02*
X396416D01*
G01X391141Y178780D02*
X392322D01*
G01X398621Y178898D02*
X401972D01*
G01X391928Y179134D02*
X389273D01*
G01X400315Y179232D02*
X396990D01*
G01X404668Y179390D02*
X399712D01*
G01X401972Y179961D02*
X398621D01*
G01X392322Y180079D02*
X391141D01*
G01X399712Y180256D02*
X404668D01*
G01X400315Y180413D02*
X396990D01*
G01X391928Y180512D02*
X388174D01*
G01X390745Y180709D02*
X388072D01*
G01X396416Y181020D02*
X396613D01*
G01X404721Y181142D02*
X402169D01*
G01X396416Y181784D02*
X396613D01*
G01X391928Y182283D02*
X389192D01*
G01X400315Y182382D02*
X396990D01*
G01X404668Y182539D02*
X399712D01*
G01X404721Y182717D02*
X402169D01*
G01X388072Y183150D02*
X390745D01*
G01X399712Y183406D02*
X404668D01*
G01X400315Y183563D02*
X396990D01*
G01X388011Y183661D02*
X391928D01*
G01X391141Y183780D02*
X392322D01*
G01X398621Y183898D02*
X401972D01*
G01X396416Y184170D02*
X396613D01*
G01Y184933D02*
X396416D01*
G01X401972Y184961D02*
X398621D01*
G01X392322Y185079D02*
X391141D01*
G01X391928Y185433D02*
X389273D01*
G01X400315Y185532D02*
X396990D01*
G01X404668Y185689D02*
X399712D01*
G01X390745Y185709D02*
X388072D01*
G01X404721Y186142D02*
X402169D01*
G01X399712Y186555D02*
X404668D01*
G01X400315Y186713D02*
X396990D01*
G01X391928Y186811D02*
X388174D01*
G01X396416Y187319D02*
X396613D01*
G01X404721Y187717D02*
X402169D01*
G01X396613Y188083D02*
X396416D01*
G01X388072Y188150D02*
X390745D01*
G01X391928Y188583D02*
X389273D01*
G01X400315Y188681D02*
X396990D01*
G01X392322Y188780D02*
X391141D01*
G01X404668Y188839D02*
X399712D01*
G01X398621Y188898D02*
X401972D01*
G01X399712Y189705D02*
X404668D01*
G01X400315Y189862D02*
X396990D01*
G01X391928Y189961D02*
X388174D01*
G01X401972D02*
X398621D01*
G01X392322Y190079D02*
X391141D01*
G01X396416Y190469D02*
X396613D01*
G01X390745Y190709D02*
X388072D01*
G01X404721Y191142D02*
X402169D01*
G01X396416Y191233D02*
X396613D01*
G01X391928Y191732D02*
X389192D01*
G01X400315Y191831D02*
X396990D01*
G01X404668Y191988D02*
X399712D01*
G01X404721Y192717D02*
X402169D01*
G01X399712Y192854D02*
X404668D01*
G01X400315Y193012D02*
X396990D01*
G01X388011Y193110D02*
X391928D01*
G01X388072Y193150D02*
X390745D01*
G01X396613Y193619D02*
X396416D01*
G01X392322Y193780D02*
X391141D01*
G01X398621Y193898D02*
X401972D01*
G01X396613Y194382D02*
X396416D01*
G01X392322Y183565D02*
X390796Y183156D01*
G01X392322Y188565D02*
X390796Y188156D01*
G01X392322Y193565D02*
X390796Y193156D01*
G01X391962Y196263D02*
X391928Y196260D01*
G01X391995Y196272D02*
X391962Y196263D01*
G01X392026Y196286D02*
X391995Y196272D01*
G01X391962Y199412D02*
X391928Y199409D01*
G01X391995Y199421D02*
X391962Y199412D01*
G01X392026Y199436D02*
X391995Y199421D01*
G01X391962Y205711D02*
X391928Y205709D01*
G01X391995Y205720D02*
X391962Y205711D01*
G01X392026Y205735D02*
X391995Y205720D01*
G01X391962Y208861D02*
X391928Y208858D01*
G01X391995Y208870D02*
X391962Y208861D01*
G01X392026Y208885D02*
X391995Y208870D01*
G01X388035Y196317D02*
G03X388174Y196260I138J140D01*
G01X387953Y196399D02*
G03X387814Y196457I-140J-139D01*
G01X388035Y199467D02*
G03X388174Y199409I140J139D01*
G01X387953Y199548D02*
G03X387814Y199606I-139J-139D01*
G01X387516Y200315D02*
G03X387655Y200372I0J197D01*
G01X388072Y200709D02*
G03X387933Y200651I1J-197D01*
G01Y198207D02*
G03X388072Y198150I138J140D01*
G01X387655Y198485D02*
G03X387516Y198543I-139J-139D01*
G01Y195315D02*
G03X387655Y195372I0J197D01*
G01X388072Y195709D02*
G03X387933Y195651I1J-197D01*
G01X388035Y205766D02*
G03X388174Y205709I138J140D01*
G01X387953Y205848D02*
G03X387814Y205906I-140J-139D01*
G01X388035Y208916D02*
G03X388174Y208858I139J139D01*
G01X387953Y208997D02*
G03X387814Y209055I-140J-139D01*
G01X387516Y210315D02*
G03X387655Y210372I0J197D01*
G01X388072Y210709D02*
G03X387933Y210651I1J-197D01*
G01Y208207D02*
G03X388072Y208150I138J140D01*
G01X387655Y208485D02*
G03X387516Y208543I-139J-139D01*
G01Y205315D02*
G03X387655Y205372I0J197D01*
G01X388072Y205709D02*
G03X387933Y205651I1J-197D01*
G01Y203207D02*
G03X388072Y203150I138J140D01*
G01X387655Y203485D02*
G03X387516Y203543I-139J-139D01*
G01X389273Y194882D02*
G03X389134Y194824I1J-197D01*
G01X392026Y194856D02*
G03X391928Y194882I-98J-171D01*
G01X388913Y197835D02*
G03X389053Y197892I2J197D01*
G01X389273Y198032D02*
G03X389134Y197974I1J-197D01*
G01X392026Y198005D02*
G03X391928Y198032I-100J-170D01*
G01X392026Y201155D02*
G03X391928Y201181I-98J-171D01*
G01X390796Y200702D02*
G03X390745Y200709I-52J-190D01*
G01Y198150D02*
G03X390796Y198156I3J197D01*
G01Y195702D02*
G03X390745Y195709I-52J-190D01*
G01X391928Y202559D02*
G03X392026Y202585I0J197D01*
G01X388913Y204134D02*
G03X389053Y204191I1J197D01*
G01X389273Y204331D02*
G03X389134Y204273I1J-197D01*
G01X392026Y204304D02*
G03X391928Y204331I-100J-170D01*
G01X388913Y207283D02*
G03X389053Y207341I0J197D01*
G01X389273Y207480D02*
G03X389134Y207422I1J-197D01*
G01X392026Y207454D02*
G03X391928Y207480I-98J-171D01*
G01X392026Y210604D02*
G03X391928Y210630I-98J-171D01*
G01X390796Y210702D02*
G03X390745Y210709I-52J-190D01*
G01Y208150D02*
G03X390796Y208156I3J197D01*
G01Y205702D02*
G03X390745Y205709I-52J-190D01*
G01Y203150D02*
G03X390796Y203156I3J197D01*
G01X396990Y198130D02*
G03X396613Y198051I-180J-79D01*
G01Y199390D02*
G03X396990Y199311I197J0D01*
G01Y194980D02*
G03X396613Y194901I-180J-79D01*
G01Y196240D02*
G03X396990Y196161I197J0D01*
G01Y201280D02*
G03X396613Y201201I-180J-79D01*
G01X402169Y201142D02*
G03X401972Y200945I0J-197D01*
G01Y197913D02*
G03X402169Y197717I197J1D01*
G01Y196142D02*
G03X401972Y195945I0J-197D01*
G01X396990Y207579D02*
G03X396613Y207500I-180J-79D01*
G01Y208839D02*
G03X396990Y208760I197J0D01*
G01Y204429D02*
G03X396613Y204350I-180J-79D01*
G01Y205689D02*
G03X396990Y205610I197J0D01*
G01X396613Y202539D02*
G03X396990Y202461I197J1D01*
G01Y210728D02*
G03X396613Y210650I-180J-79D01*
G01X402169Y211142D02*
G03X401972Y210945I0J-197D01*
G01Y207913D02*
G03X402169Y207717I197J1D01*
G01Y206142D02*
G03X401972Y205945I0J-197D01*
G01Y202913D02*
G03X402169Y202717I197J1D01*
G01X387655Y210372D02*
X387933Y210651D01*
G01X388995Y210433D02*
X389192Y210630D01*
G01X389053Y207341D02*
X389134Y207422D01*
G01X387655Y205372D02*
X387933Y205651D01*
G01X392322Y209055D02*
X392026Y208885D01*
G01X392322Y205906D02*
X392026Y205735D01*
G01X392322Y202756D02*
X392026Y202585D01*
G01X389053Y204191D02*
X389134Y204273D01*
G01X387655Y200372D02*
X387933Y200651D01*
G01X388995Y200984D02*
X389192Y201181D01*
G01X389053Y197892D02*
X389134Y197974D01*
G01X387655Y195372D02*
X387933Y195651D01*
G01X399633Y210728D02*
X399712Y210886D01*
G01X400394D02*
X400315Y210728D01*
G01X399633Y207579D02*
X399712Y207736D01*
G01X400394D02*
X400315Y207579D01*
G01X399633Y204429D02*
X399712Y204587D01*
G01X400394D02*
X400315Y204429D01*
G01X399633Y201280D02*
X399712Y201437D01*
G01X400394D02*
X400315Y201280D01*
G01X392322Y199606D02*
X392026Y199436D01*
G01X392322Y196457D02*
X392026Y196286D01*
G01X399633Y198130D02*
X399712Y198287D01*
G01X400394D02*
X400315Y198130D01*
G01X399633Y194980D02*
X399712Y195138D01*
G01X400394D02*
X400315Y194980D01*
G01X391141Y200079D02*
Y198780D01*
G01Y205079D02*
Y203780D01*
G01Y210079D02*
Y208780D01*
G01X396613Y196768D02*
Y196240D01*
G01Y198051D02*
Y197532D01*
G01Y199918D02*
Y199390D01*
G01Y201201D02*
Y200682D01*
G01Y204350D02*
Y203831D01*
G01Y206217D02*
Y205689D01*
G01Y207500D02*
Y206981D01*
G01Y209367D02*
Y208839D01*
G01Y210650D02*
Y210130D01*
G01Y202539D02*
Y203067D01*
G01X397221Y210728D02*
Y211909D01*
G01Y207579D02*
Y208760D01*
G01Y204429D02*
Y205610D01*
G01Y201280D02*
Y202461D01*
G01Y198130D02*
Y199311D01*
G01Y194980D02*
Y196161D01*
G01X398074D02*
Y194980D01*
G01Y199311D02*
Y198130D01*
G01Y202461D02*
Y201280D01*
G01Y205610D02*
Y204429D01*
G01Y208760D02*
Y207579D01*
G01Y211909D02*
Y210728D01*
G01X398601Y196969D02*
Y194882D01*
G01Y199803D02*
Y197598D01*
G01Y203701D02*
Y201496D01*
G01Y205039D02*
Y204764D01*
G01Y205630D02*
Y205236D01*
G01Y206929D02*
Y206102D01*
G01X398756Y210728D02*
Y211909D01*
G01Y207579D02*
Y208760D01*
G01Y204429D02*
Y205610D01*
G01Y201280D02*
Y202461D01*
G01Y198130D02*
Y199311D01*
G01Y194980D02*
Y196161D01*
G01X400378Y210886D02*
Y211752D01*
G01Y207736D02*
Y208602D01*
G01Y204587D02*
Y205453D01*
G01Y201437D02*
Y202303D01*
G01Y198287D02*
Y199154D01*
G01Y195138D02*
Y196004D01*
G01X401059D02*
Y195138D01*
G01Y199154D02*
Y198287D01*
G01Y202303D02*
Y201437D01*
G01Y205453D02*
Y204587D01*
G01Y208602D02*
Y207736D01*
G01Y211752D02*
Y210886D01*
G01X401912D02*
Y211752D01*
G01Y207736D02*
Y208602D01*
G01Y204587D02*
Y205453D01*
G01Y201437D02*
Y202303D01*
G01Y198287D02*
Y199154D01*
G01Y195138D02*
Y196004D01*
G01X401972Y195945D02*
Y194961D01*
G01Y200945D02*
Y199961D01*
G01Y205945D02*
Y204961D01*
G01Y208898D02*
Y207913D01*
G01Y210945D02*
Y209961D01*
G01Y202913D02*
Y203898D01*
G01Y197913D02*
Y198898D01*
G01X399712Y196004D02*
X399633Y196161D01*
G01X400315D02*
X400394Y196004D01*
G01X399712Y199154D02*
X399633Y199311D01*
G01X400315D02*
X400394Y199154D01*
G01X399712Y202303D02*
X399633Y202461D01*
G01X400315D02*
X400394Y202303D01*
G01X399712Y205453D02*
X399633Y205610D01*
G01X400315D02*
X400394Y205453D01*
G01X399712Y208602D02*
X399633Y208760D01*
G01X400315D02*
X400394Y208602D01*
G01X388035Y196317D02*
X387953Y196399D01*
G01X387933Y198207D02*
X387655Y198485D01*
G01X388035Y199467D02*
X387953Y199548D01*
G01X388011Y202559D02*
X387814Y202756D01*
G01X387933Y203207D02*
X387655Y203485D01*
G01X388035Y205766D02*
X387953Y205848D01*
G01X387933Y208207D02*
X387655Y208485D01*
G01X388035Y208916D02*
X387953Y208997D01*
G01X392026Y198005D02*
X392322Y197835D01*
G01X392026Y201155D02*
X392322Y200984D01*
G01X392026Y204304D02*
X392322Y204134D01*
G01X392026Y207454D02*
X392322Y207283D01*
G01X392026Y210604D02*
X392322Y210433D01*
G01X390796Y195702D02*
X392322Y195293D01*
G01X390796Y200702D02*
X392322Y200293D01*
G01X390796Y205702D02*
X392322Y205293D01*
G01X390796Y210702D02*
X392322Y210293D01*
G01X391928Y194882D02*
X389273D01*
G01X401972Y194961D02*
X398621D01*
G01X400315Y194980D02*
X396990D01*
G01X392322Y195079D02*
X391141D01*
G01X404668Y195138D02*
X399712D01*
G01X390745Y195709D02*
X388072D01*
G01X399712Y196004D02*
X404668D01*
G01X404721Y196142D02*
X402169D01*
G01X400315Y196161D02*
X396990D01*
G01X391928Y196260D02*
X388174D01*
G01X396416Y196768D02*
X396613D01*
G01Y197532D02*
X396416D01*
G01X404721Y197717D02*
X402169D01*
G01X391928Y198032D02*
X389273D01*
G01X400315Y198130D02*
X396990D01*
G01X388072Y198150D02*
X390745D01*
G01X404668Y198287D02*
X399712D01*
G01X392322Y198780D02*
X391141D01*
G01X398621Y198898D02*
X401972D01*
G01X399712Y199154D02*
X404668D01*
G01X400315Y199311D02*
X396990D01*
G01X391928Y199409D02*
X388174D01*
G01X396416Y199918D02*
X396613D01*
G01X401972Y199961D02*
X398621D01*
G01X392322Y200079D02*
X391141D01*
G01X396416Y200682D02*
X396613D01*
G01X390745Y200709D02*
X388072D01*
G01X404721Y201142D02*
X402169D01*
G01X391928Y201181D02*
X389192D01*
G01X400315Y201280D02*
X396990D01*
G01X404668Y201437D02*
X399712D01*
G01Y202303D02*
X404668D01*
G01X400315Y202461D02*
X396990D01*
G01X388011Y202559D02*
X391928D01*
G01X404721Y202717D02*
X402169D01*
G01X396613Y203067D02*
X396416D01*
G01X388072Y203150D02*
X390745D01*
G01X392322Y203780D02*
X391141D01*
G01X396613Y203831D02*
X396416D01*
G01X398621Y203898D02*
X401972D01*
G01X391928Y204331D02*
X389273D01*
G01X400315Y204429D02*
X396990D01*
G01X404668Y204587D02*
X399712D01*
G01X401972Y204961D02*
X398621D01*
G01X391141Y205079D02*
X392322D01*
G01X399712Y205453D02*
X404668D01*
G01X400315Y205610D02*
X396990D01*
G01X388174Y205709D02*
X388072D01*
G01X391928D02*
X388174D01*
G01X404721Y206142D02*
X402169D01*
G01X396416Y206217D02*
X396613D01*
G01Y206981D02*
X396416D01*
G01X391928Y207480D02*
X389273D01*
G01X400315Y207579D02*
X396990D01*
G01X404721Y207717D02*
X402169D01*
G01X404668Y207736D02*
X399712D01*
G01X388072Y208150D02*
X390745D01*
G01X399712Y208602D02*
X404668D01*
G01X400315Y208760D02*
X396990D01*
G01X391141Y208780D02*
X392322D01*
G01X391928Y208858D02*
X388174D01*
G01X401972Y208898D02*
X398621D01*
G01X396416Y209367D02*
X396613D01*
G01X401972Y209961D02*
X398621D01*
G01X391141Y210079D02*
X392322D01*
G01X396416Y210130D02*
X396613D01*
G01X391928Y210630D02*
X389192D01*
G01X390745Y210709D02*
X388072D01*
G01X400315Y210728D02*
X396990D01*
G01X404668Y210886D02*
X399712D01*
G01X404721Y211142D02*
X402169D01*
G01X392322Y198565D02*
X390796Y198156D01*
G01X392322Y203565D02*
X390796Y203156D01*
G01X392322Y208565D02*
X390796Y208156D01*
G01X391928Y212008D02*
G03X392026Y212034I0J197D01*
G01X396613Y211988D02*
G03X396990Y211909I197J0D01*
G01X396259Y214035D02*
G03X394290Y212067I-1J-1968D01*
G01X396259Y214035D02*
G03X394290Y212067I-1J-1968D01*
G01X401972Y212913D02*
G03X402169Y212717I197J1D01*
G01X390745Y213150D02*
G03X390796Y213156I3J197D01*
G01X387933Y213207D02*
G03X388072Y213150I138J140D01*
G01X387655Y213485D02*
G03X387516Y213543I-139J-139D01*
G01X401377Y214035D02*
G03X403345Y216004I0J1968D01*
G01X401804Y214120D02*
G03X402164Y215256I-1609J1135D01*
G01X401377Y214035D02*
G03X403345Y216004I0J1968D01*
G01X400196Y213287D02*
G03X401804Y214120I0J1969D01*
G01X396259Y214035D02*
G03X394290Y212067I-1J-1968D01*
G01X396259Y214035D02*
G03X394290Y212067I-1J-1968D01*
G01X401377Y214035D02*
G03X403345Y216004I0J1968D01*
G01X401377Y214035D02*
G03X403345Y216004I0J1968D01*
G01X399802Y219012D02*
X392322Y215524D01*
G01Y212205D02*
X392026Y212034D01*
G01X399408Y215236D02*
X402164Y217992D01*
G01X391141Y213780D02*
Y215236D01*
G01X396416D02*
Y214035D01*
G01X396613Y212516D02*
Y211988D01*
G01X398621Y214035D02*
Y215236D01*
G01X399802Y219012D02*
Y230394D01*
G01X401972Y213898D02*
Y212913D01*
G01X402164Y217992D02*
Y230787D01*
G01X399712Y211752D02*
X399633Y211909D01*
G01X400315D02*
X400394Y211752D01*
G01X388011Y212008D02*
X387814Y212205D01*
G01X387933Y213207D02*
X387655Y213485D01*
G01X390353Y222638D02*
X392322Y220669D01*
G01X399712Y211752D02*
X404668D01*
G01X400315Y211909D02*
X396990D01*
G01X388011Y212008D02*
X391928D01*
G01X396416Y212516D02*
X396613D01*
G01X404721Y212717D02*
X402169D01*
G01X388072Y213150D02*
X390745D01*
G01X392322Y213780D02*
X391141D01*
G01X401972Y213898D02*
X398621D01*
G01X396259Y214035D02*
X401377D01*
G01X396259D02*
X401377D01*
G01X392322Y213565D02*
X390796Y213156D01*
G01X396259Y214035D02*
X401377D01*
G01X396259D02*
X401377D01*
G01X396259Y214036D02*
G03X394289Y212067I-1J-1969D01*
G01X401377Y214036D02*
X396259D01*
G01X401377D02*
G03X403346Y216004I0J1969D01*
G01X391935Y238929D02*
X391929Y238956D01*
G01X392007Y238883D02*
X391935Y238929D01*
G01X392139Y238863D02*
X392007Y238883D01*
G01X392320Y238858D02*
X392139Y238863D01*
G01X392105Y240044D02*
X392286Y240040D01*
G01X391985Y240059D02*
X392105Y240044D01*
G01X391930Y240089D02*
X391985Y240059D01*
G01X391928Y240100D02*
X391930Y240089D01*
G01X392510Y241368D02*
X392500Y241330D01*
G01X392516Y241407D02*
X392510Y241368D01*
G01X392519Y241446D02*
X392516Y241407D01*
G01X392517Y241047D02*
X392519Y241110D01*
G01X392510Y240985D02*
X392517Y241047D01*
G01X392500Y240924D02*
X392510Y240985D01*
G01X392131Y240400D02*
X391946Y240135D01*
G01X392315Y240810D02*
X392131Y240400D01*
G01X392500Y241330D02*
X392315Y240810D01*
G01Y240092D02*
X392500Y240924D01*
G01X392131Y239435D02*
X392315Y240092D01*
G01X391946Y239011D02*
X392131Y239435D01*
G01X403345Y232736D02*
G03X401377Y234705I-1969J0D01*
G01X403345Y232736D02*
G03X401377Y234705I-1969J0D01*
G01X403345Y232736D02*
G03X401377Y234705I-1969J0D01*
G01X403345Y232736D02*
G03X401377Y234705I-1969J0D01*
G01X395432Y240472D02*
X395038Y240079D01*
G01X391946Y240135D02*
X391928Y240100D01*
G01X391929Y238956D02*
X391946Y239011D01*
G01X386298Y238858D02*
Y240039D01*
G01X390078Y238858D02*
Y240039D01*
G01X390865Y238858D02*
Y240039D01*
G01X391259Y238858D02*
Y240039D01*
G01X391928Y240100D02*
Y238956D01*
G01X391946Y239011D02*
Y240135D01*
G01X392500Y241330D02*
Y240924D01*
G01X392519Y247874D02*
Y241111D01*
G01Y238858D02*
Y240039D01*
G01X393109Y240079D02*
Y244370D01*
G01X393306Y238858D02*
Y240039D01*
G01X393383D02*
Y238858D01*
G01X394387D02*
Y240039D01*
G01X394633D02*
Y238858D01*
G01X394718D02*
Y240039D01*
G01X395038Y240472D02*
Y238425D01*
G01X395196Y240039D02*
Y238858D01*
G01X395432Y238425D02*
Y240472D01*
G01X396495Y240039D02*
Y238858D01*
G01X397046Y234705D02*
Y244370D01*
G01Y233543D02*
Y234705D01*
G01X397085Y240039D02*
Y238858D01*
G01X402164Y230787D02*
X399408Y233543D01*
G01X395432Y238425D02*
X395038Y238819D01*
G01X399802Y229606D02*
X402952D01*
G01X395038Y238425D02*
X395432D01*
G01Y240472D02*
X395038D01*
G01X393109Y240669D02*
X402952D01*
G01X393109Y241260D02*
X402952D01*
G01X403346Y232736D02*
G03X401377Y234705I-1969J0D01*
G01X392519Y247874D02*
G03X391337Y249055I-1181J0D01*
G01X393109Y244370D02*
X402952D01*
G01X386622Y258071D02*
G03Y265945I0J3937D01*
G01X405609Y316181D02*
G03X391634I-6988J0D01*
G03X405609I6987J0D01*
G01D02*
G03X391634I-6988J0D01*
G03X405609I6987J0D01*
G01D02*
G03X391634I-6988J0D01*
G03X405609I6987J0D01*
G01X398622Y323169D02*
G03Y309193I0J-6988D01*
G01D02*
G03Y323169I0J6988D01*
G01X410826Y-105354D02*
Y-62047D01*
G01X403345Y232736D02*
Y-105354D01*
G01X410826Y-62047D02*
X458070D01*
G01X455904Y984D02*
X403345D01*
G01X402952Y64964D02*
Y54488D01*
G01X413385Y72657D02*
G03X408266I-2560J0D01*
G03X413385I2560J0D01*
G01X413778D02*
G03X407873I-2953J0D01*
G03X413778I2952J0D01*
G01X414045D02*
G03X407606I-3219J0D01*
G03X414045I3219J0D01*
G01X419093Y65315D02*
G03X420274Y66496I0J1181D01*
G01X402952Y65315D02*
Y64964D01*
G01Y83622D02*
Y65315D01*
G01X403345Y66083D02*
Y82815D01*
G01Y66083D02*
Y82815D01*
G01X404920Y65315D02*
Y83622D01*
G01X405314Y77382D02*
Y67933D01*
G01X414763Y77382D02*
Y67933D01*
G01X415550Y82835D02*
Y78898D01*
G01X419093Y65315D02*
X403186D01*
G01X414763Y67933D02*
X405314D01*
G01X414045Y72658D02*
X413385D01*
G01X407606D02*
X408267D01*
G01X414763Y77382D02*
X405314D01*
G01X415550Y78898D02*
X419487D01*
G01X403345Y66083D02*
Y82815D01*
G01X403346D02*
Y66083D01*
G01X409471Y95578D02*
X409498Y95609D01*
G01X409441Y95558D02*
X409471Y95578D01*
G01X409408Y95551D02*
X409441Y95558D01*
G01X404388Y93281D02*
X404362Y93249D01*
G01X404419Y93300D02*
X404388Y93281D01*
G01X404452Y93307D02*
X404419Y93300D01*
G01X404784Y92743D02*
X404811Y92774D01*
G01X404754Y92723D02*
X404784Y92743D01*
G01X404721Y92717D02*
X404754Y92723D01*
G01X410583Y91115D02*
X410557Y91084D01*
G01X410614Y91135D02*
X410583Y91115D01*
G01X410646Y91142D02*
X410614Y91135D01*
G01X409471Y90578D02*
X409498Y90609D01*
G01X409441Y90558D02*
X409471Y90578D01*
G01X409408Y90551D02*
X409441Y90558D01*
G01X404388Y88281D02*
X404362Y88249D01*
G01X404419Y88300D02*
X404388Y88281D01*
G01X404452Y88307D02*
X404419Y88300D01*
G01X404784Y87743D02*
X404811Y87774D01*
G01X404754Y87723D02*
X404784Y87743D01*
G01X404721Y87717D02*
X404754Y87723D01*
G01X410583Y86115D02*
X410557Y86084D01*
G01X410614Y86135D02*
X410583Y86115D01*
G01X410646Y86142D02*
X410614Y86135D01*
G01X409471Y85578D02*
X409498Y85609D01*
G01X409441Y85558D02*
X409471Y85578D01*
G01X409408Y85551D02*
X409441Y85558D01*
G01X405142Y95578D02*
X405116Y95609D01*
G01X405173Y95558D02*
X405142Y95578D01*
G01X405206Y95551D02*
X405173Y95558D01*
G01X410225Y93281D02*
X410252Y93249D01*
G01X410195Y93300D02*
X410225Y93281D01*
G01X410162Y93307D02*
X410195Y93300D01*
G01X409829Y92743D02*
X409803Y92774D01*
G01X409860Y92723D02*
X409829Y92743D01*
G01X409893Y92717D02*
X409860Y92723D01*
G01X404030Y91115D02*
X404057Y91084D01*
G01X404000Y91135D02*
X404030Y91115D01*
G01X403967Y91142D02*
X404000Y91135D01*
G01X405142Y90578D02*
X405116Y90609D01*
G01X405173Y90558D02*
X405142Y90578D01*
G01X405206Y90551D02*
X405173Y90558D01*
G01X410225Y88281D02*
X410252Y88249D01*
G01X410195Y88300D02*
X410225Y88281D01*
G01X410162Y88307D02*
X410195Y88300D01*
G01X409829Y87743D02*
X409803Y87774D01*
G01X409860Y87723D02*
X409829Y87743D01*
G01X409893Y87717D02*
X409860Y87723D01*
G01X404030Y86115D02*
X404057Y86084D01*
G01X404000Y86135D02*
X404030Y86115D01*
G01X403967Y86142D02*
X404000Y86135D01*
G01X405142Y85578D02*
X405116Y85609D01*
G01X405173Y85558D02*
X405142Y85578D01*
G01X405206Y85551D02*
X405173Y85558D01*
G01X410614Y92723D02*
X410646Y92717D01*
G01X410583Y92743D02*
X410614Y92723D01*
G01X410557Y92774D02*
X410583Y92743D01*
G01X409441Y93300D02*
X409408Y93307D01*
G01X409471Y93281D02*
X409441Y93300D01*
G01X409498Y93249D02*
X409471Y93281D01*
G01X404419Y95558D02*
X404452Y95551D01*
G01X404388Y95578D02*
X404419Y95558D01*
G01X404362Y95609D02*
X404388Y95578D01*
G01X410614Y87723D02*
X410646Y87717D01*
G01X410583Y87743D02*
X410614Y87723D01*
G01X410557Y87774D02*
X410583Y87743D01*
G01X409441Y88300D02*
X409408Y88307D01*
G01X409471Y88281D02*
X409441Y88300D01*
G01X409498Y88249D02*
X409471Y88281D01*
G01X404754Y91135D02*
X404721Y91142D01*
G01X404784Y91115D02*
X404754Y91135D01*
G01X404811Y91084D02*
X404784Y91115D01*
G01X404419Y90558D02*
X404452Y90551D01*
G01X404388Y90578D02*
X404419Y90558D01*
G01X404362Y90609D02*
X404388Y90578D01*
G01X410195Y85558D02*
X410162Y85551D01*
G01X410225Y85578D02*
X410195Y85558D01*
G01X410252Y85609D02*
X410225Y85578D01*
G01X409860Y86135D02*
X409893Y86142D01*
G01X409829Y86115D02*
X409860Y86135D01*
G01X409803Y86084D02*
X409829Y86115D01*
G01X410195Y90558D02*
X410162Y90551D01*
G01X410225Y90578D02*
X410195Y90558D01*
G01X410252Y90609D02*
X410225Y90578D01*
G01X409860Y91135D02*
X409893Y91142D01*
G01X409829Y91115D02*
X409860Y91135D01*
G01X409803Y91084D02*
X409829Y91115D01*
G01X405173Y88300D02*
X405206Y88307D01*
G01X405142Y88281D02*
X405173Y88300D01*
G01X405116Y88249D02*
X405142Y88281D01*
G01X404000Y87723D02*
X403967Y87717D01*
G01X404030Y87743D02*
X404000Y87723D01*
G01X404057Y87774D02*
X404030Y87743D01*
G01X410195Y95558D02*
X410162Y95551D01*
G01X410225Y95578D02*
X410195Y95558D01*
G01X410252Y95609D02*
X410225Y95578D01*
G01X404754Y86135D02*
X404721Y86142D01*
G01X404784Y86115D02*
X404754Y86135D01*
G01X404811Y86084D02*
X404784Y86115D01*
G01X404419Y85558D02*
X404452Y85551D01*
G01X404388Y85578D02*
X404419Y85558D01*
G01X404362Y85609D02*
X404388Y85578D01*
G01X405173Y93300D02*
X405206Y93307D01*
G01X405142Y93281D02*
X405173Y93300D01*
G01X405116Y93249D02*
X405142Y93281D01*
G01X404000Y92723D02*
X403967Y92717D01*
G01X404030Y92743D02*
X404000Y92723D01*
G01X404057Y92774D02*
X404030Y92743D01*
G01X420274Y82441D02*
G03X419093Y83622I-1181J0D01*
G01X402759Y87717D02*
Y86142D01*
G01Y91142D02*
Y92717D01*
G01X403513Y91142D02*
Y92717D01*
G01Y86142D02*
Y87717D01*
G01X404267D02*
Y86142D01*
G01Y92717D02*
Y91142D01*
G01X404668Y95217D02*
Y94350D01*
G01Y91201D02*
Y92067D01*
G01Y88051D02*
Y88917D01*
G01X410370Y87717D02*
Y86142D01*
G01Y92717D02*
Y91142D01*
G01X414100Y87244D02*
X414119Y87163D01*
G01X414001Y87143D02*
X413981Y87204D01*
G01X404362Y93249D02*
X404057Y92774D01*
G01X404811D02*
X405116Y93249D01*
G01X404362Y88249D02*
X404057Y87774D01*
G01X409498Y95609D02*
X409803Y96084D01*
G01X404811Y87774D02*
X405116Y88249D01*
G01X410557Y96084D02*
X410252Y95609D01*
G01X409498Y90609D02*
X409803Y91084D01*
G01X410557D02*
X410252Y90609D01*
G01X409498Y85609D02*
X409803Y86084D01*
G01X410557D02*
X410252Y85609D01*
G01X414159Y86620D02*
X414100Y86520D01*
G01X413647Y87204D02*
X413627Y87163D01*
G01X413450Y86761D02*
X413489Y86841D01*
G01X413509Y87163D02*
X413529Y87224D01*
G01X413981Y87043D02*
X414001Y87103D01*
G01X414041Y86641D02*
X414060Y86701D01*
G01X414119Y87083D02*
X414100Y87002D01*
G01X414178Y86701D02*
X414159Y86620D01*
G01X411124Y91142D02*
Y92717D01*
G01Y86142D02*
Y87717D01*
G01X411878Y91142D02*
Y92717D01*
G01Y86142D02*
Y87717D01*
G01X413056Y87384D02*
Y86439D01*
G01X413174D02*
Y87224D01*
G01X413293Y87083D02*
Y87244D01*
G01X413450Y86661D02*
Y86761D01*
G01X413568Y86741D02*
Y86681D01*
G01X414001Y87103D02*
Y87143D01*
G01X414119Y87163D02*
Y87083D01*
G01X414634Y91142D02*
Y92717D01*
G01Y86142D02*
Y87717D01*
G01X413489Y86580D02*
X413450Y86661D01*
G01X404057Y86084D02*
X404362Y85609D01*
G01X405116D02*
X404811Y86084D01*
G01X404057Y91084D02*
X404362Y90609D01*
G01X405116D02*
X404811Y91084D01*
G01X404057Y96084D02*
X404362Y95609D01*
G01X409803Y87774D02*
X409498Y88249D01*
G01X405116Y95609D02*
X404811Y96084D01*
G01X410252Y88249D02*
X410557Y87774D01*
G01X409803Y92774D02*
X409498Y93249D01*
G01X410252D02*
X410557Y92774D01*
G01X413568Y86681D02*
X413607Y86620D01*
G01X413686Y87244D02*
X413647Y87204D01*
G01X413489Y86841D02*
X413568Y86922D01*
G01X413529Y87224D02*
X413588Y87304D01*
G01X413607Y86801D02*
X413568Y86741D01*
G01X413174Y87224D02*
X413293Y87083D01*
G01Y87244D02*
X413174Y87384D01*
G01X413568Y86500D02*
X413489Y86580D01*
G01X414021Y87324D02*
X414100Y87244D01*
G01X413588Y87304D02*
X413667Y87364D01*
G01X414100Y87002D02*
X414021Y86922D01*
G01X413981Y86580D02*
X414041Y86641D01*
G01X413568Y86922D02*
X413647Y86962D01*
G01X414021Y86922D02*
X413942Y86882D01*
G01X414100Y86520D02*
X414001Y86459D01*
G01X413667Y86841D02*
X413607Y86801D01*
G01X413922Y87002D02*
X413981Y87043D01*
G01X413607Y86620D02*
X413667Y86580D01*
G01X413981Y87204D02*
X413922Y87244D01*
G01X413745Y87264D02*
X413686Y87244D01*
G01X413863Y86982D02*
X413922Y87002D01*
G01X413647Y86459D02*
X413568Y86500D01*
G01X413942Y87364D02*
X414021Y87324D01*
G01X413922Y87244D02*
X413863Y87264D01*
G01X413667Y86580D02*
X413745Y86560D01*
G01X413863Y87384D02*
X413942Y87364D01*
G01X413745Y86439D02*
X413647Y86459D01*
G01X419487Y82835D02*
X415550D01*
G01X403159Y83622D02*
X419093D01*
G01X410162Y85551D02*
X404452D01*
G01X409498Y85609D02*
X410252D01*
G01X404362D02*
X405116D01*
G01X410557Y86084D02*
X409803D01*
G01X404057D02*
X404811D01*
G01X414634Y86142D02*
X409893D01*
G01X413903Y86439D02*
X413745D01*
G01X413056D02*
X413174D01*
G01X413745Y86560D02*
X413903D01*
G01X414060Y86701D02*
X414178D01*
G01X413863Y86862D02*
X413745D01*
G01Y86982D02*
X413863D01*
G01X413627Y87163D02*
X413509D01*
G01X413863Y87264D02*
X413745D01*
G01X413174Y87384D02*
X413056D01*
G01X413765D02*
X413863D01*
G01X414634Y87717D02*
X409893D01*
G01X410557Y87774D02*
X409803D01*
G01X404057D02*
X404811D01*
G01X405116Y88249D02*
X404362D01*
G01X409498D02*
X410252D01*
G01X404452Y88307D02*
X410162D01*
G01Y90551D02*
X404452D01*
G01X409498Y90609D02*
X410252D01*
G01X404362D02*
X405116D01*
G01X410557Y91084D02*
X409803D01*
G01X404057D02*
X404811D01*
G01X414634Y91142D02*
X409893D01*
G01X414634Y92717D02*
X409893D01*
G01X410557Y92774D02*
X409803D01*
G01X404057D02*
X404811D01*
G01X405116Y93249D02*
X404362D01*
G01X409498D02*
X410252D01*
G01X404452Y93307D02*
X410162D01*
G01Y95551D02*
X404452D01*
G01X405116Y95609D02*
X404362D01*
G01X409498D02*
X410252D01*
G01X414001Y86459D02*
X413903Y86439D01*
G01X413647Y86962D02*
X413745Y86982D01*
G01X413667Y87364D02*
X413765Y87384D01*
G01X413903Y86560D02*
X413981Y86580D01*
G01X413942Y86882D02*
X413863Y86862D01*
G01X413745D02*
X413667Y86841D01*
G01X410583Y111115D02*
X410557Y111084D01*
G01X410614Y111135D02*
X410583Y111115D01*
G01X410646Y111142D02*
X410614Y111135D01*
G01X409471Y110578D02*
X409498Y110609D01*
G01X409441Y110558D02*
X409471Y110578D01*
G01X409408Y110551D02*
X409441Y110558D01*
G01X404388Y108281D02*
X404362Y108249D01*
G01X404419Y108300D02*
X404388Y108281D01*
G01X404452Y108307D02*
X404419Y108300D01*
G01X404784Y107743D02*
X404811Y107774D01*
G01X404754Y107723D02*
X404784Y107743D01*
G01X404721Y107717D02*
X404754Y107723D01*
G01X410583Y106115D02*
X410557Y106084D01*
G01X410614Y106135D02*
X410583Y106115D01*
G01X410646Y106142D02*
X410614Y106135D01*
G01X409471Y105578D02*
X409498Y105609D01*
G01X409441Y105558D02*
X409471Y105578D01*
G01X409408Y105551D02*
X409441Y105558D01*
G01X404388Y103281D02*
X404362Y103249D01*
G01X404419Y103300D02*
X404388Y103281D01*
G01X404452Y103307D02*
X404419Y103300D01*
G01X404784Y102743D02*
X404811Y102774D01*
G01X404754Y102723D02*
X404784Y102743D01*
G01X404721Y102717D02*
X404754Y102723D01*
G01X410583Y101115D02*
X410557Y101084D01*
G01X410614Y101135D02*
X410583Y101115D01*
G01X410646Y101142D02*
X410614Y101135D01*
G01X409471Y100578D02*
X409498Y100609D01*
G01X409441Y100558D02*
X409471Y100578D01*
G01X409408Y100551D02*
X409441Y100558D01*
G01X404388Y98281D02*
X404362Y98249D01*
G01X404419Y98300D02*
X404388Y98281D01*
G01X404452Y98307D02*
X404419Y98300D01*
G01X404784Y97743D02*
X404811Y97774D01*
G01X404754Y97723D02*
X404784Y97743D01*
G01X404721Y97717D02*
X404754Y97723D01*
G01X410583Y96115D02*
X410557Y96084D01*
G01X410614Y96135D02*
X410583Y96115D01*
G01X410646Y96142D02*
X410614Y96135D01*
G01X404030Y111115D02*
X404057Y111084D01*
G01X404000Y111135D02*
X404030Y111115D01*
G01X403967Y111142D02*
X404000Y111135D01*
G01X405142Y110578D02*
X405116Y110609D01*
G01X405173Y110558D02*
X405142Y110578D01*
G01X405206Y110551D02*
X405173Y110558D01*
G01X410225Y108281D02*
X410252Y108249D01*
G01X410195Y108300D02*
X410225Y108281D01*
G01X410162Y108307D02*
X410195Y108300D01*
G01X409829Y107743D02*
X409803Y107774D01*
G01X409860Y107723D02*
X409829Y107743D01*
G01X409893Y107717D02*
X409860Y107723D01*
G01X404030Y106115D02*
X404057Y106084D01*
G01X404000Y106135D02*
X404030Y106115D01*
G01X403967Y106142D02*
X404000Y106135D01*
G01X405142Y105578D02*
X405116Y105609D01*
G01X405173Y105558D02*
X405142Y105578D01*
G01X405206Y105551D02*
X405173Y105558D01*
G01X410225Y103281D02*
X410252Y103249D01*
G01X410195Y103300D02*
X410225Y103281D01*
G01X410162Y103307D02*
X410195Y103300D01*
G01X409829Y102743D02*
X409803Y102774D01*
G01X409860Y102723D02*
X409829Y102743D01*
G01X409893Y102717D02*
X409860Y102723D01*
G01X404030Y101115D02*
X404057Y101084D01*
G01X404000Y101135D02*
X404030Y101115D01*
G01X403967Y101142D02*
X404000Y101135D01*
G01X405142Y100578D02*
X405116Y100609D01*
G01X405173Y100558D02*
X405142Y100578D01*
G01X405206Y100551D02*
X405173Y100558D01*
G01X410225Y98281D02*
X410252Y98249D01*
G01X410195Y98300D02*
X410225Y98281D01*
G01X410162Y98307D02*
X410195Y98300D01*
G01X409829Y97743D02*
X409803Y97774D01*
G01X409860Y97723D02*
X409829Y97743D01*
G01X409893Y97717D02*
X409860Y97723D01*
G01X404030Y96115D02*
X404057Y96084D01*
G01X404000Y96135D02*
X404030Y96115D01*
G01X403967Y96142D02*
X404000Y96135D01*
G01X410614Y107723D02*
X410646Y107717D01*
G01X410583Y107743D02*
X410614Y107723D01*
G01X410557Y107774D02*
X410583Y107743D01*
G01X409441Y108300D02*
X409408Y108307D01*
G01X409471Y108281D02*
X409441Y108300D01*
G01X409498Y108249D02*
X409471Y108281D01*
G01X404754Y111135D02*
X404721Y111142D01*
G01X404784Y111115D02*
X404754Y111135D01*
G01X404811Y111084D02*
X404784Y111115D01*
G01X404419Y110558D02*
X404452Y110551D01*
G01X404388Y110578D02*
X404419Y110558D01*
G01X404362Y110609D02*
X404388Y110578D01*
G01X410614Y102723D02*
X410646Y102717D01*
G01X410583Y102743D02*
X410614Y102723D01*
G01X410557Y102774D02*
X410583Y102743D01*
G01X409441Y103300D02*
X409408Y103307D01*
G01X409471Y103281D02*
X409441Y103300D01*
G01X409498Y103249D02*
X409471Y103281D01*
G01X404754Y106135D02*
X404721Y106142D01*
G01X404784Y106115D02*
X404754Y106135D01*
G01X404811Y106084D02*
X404784Y106115D01*
G01X404419Y105558D02*
X404452Y105551D01*
G01X404388Y105578D02*
X404419Y105558D01*
G01X404362Y105609D02*
X404388Y105578D01*
G01X410614Y97723D02*
X410646Y97717D01*
G01X410583Y97743D02*
X410614Y97723D01*
G01X410557Y97774D02*
X410583Y97743D01*
G01X409441Y98300D02*
X409408Y98307D01*
G01X409471Y98281D02*
X409441Y98300D01*
G01X409498Y98249D02*
X409471Y98281D01*
G01X404754Y101135D02*
X404721Y101142D01*
G01X404784Y101115D02*
X404754Y101135D01*
G01X404811Y101084D02*
X404784Y101115D01*
G01X404419Y100558D02*
X404452Y100551D01*
G01X404388Y100578D02*
X404419Y100558D01*
G01X404362Y100609D02*
X404388Y100578D01*
G01X404754Y96135D02*
X404721Y96142D01*
G01X404784Y96115D02*
X404754Y96135D01*
G01X404811Y96084D02*
X404784Y96115D01*
G01X409860Y96135D02*
X409893Y96142D01*
G01X409829Y96115D02*
X409860Y96135D01*
G01X409803Y96084D02*
X409829Y96115D01*
G01X410195Y100558D02*
X410162Y100551D01*
G01X410225Y100578D02*
X410195Y100558D01*
G01X410252Y100609D02*
X410225Y100578D01*
G01X409860Y101135D02*
X409893Y101142D01*
G01X409829Y101115D02*
X409860Y101135D01*
G01X409803Y101084D02*
X409829Y101115D01*
G01X405173Y98300D02*
X405206Y98307D01*
G01X405142Y98281D02*
X405173Y98300D01*
G01X405116Y98249D02*
X405142Y98281D01*
G01X404000Y97723D02*
X403967Y97717D01*
G01X404030Y97743D02*
X404000Y97723D01*
G01X404057Y97774D02*
X404030Y97743D01*
G01X410195Y105558D02*
X410162Y105551D01*
G01X410225Y105578D02*
X410195Y105558D01*
G01X410252Y105609D02*
X410225Y105578D01*
G01X409860Y106135D02*
X409893Y106142D01*
G01X409829Y106115D02*
X409860Y106135D01*
G01X409803Y106084D02*
X409829Y106115D01*
G01X405173Y103300D02*
X405206Y103307D01*
G01X405142Y103281D02*
X405173Y103300D01*
G01X405116Y103249D02*
X405142Y103281D01*
G01X404000Y102723D02*
X403967Y102717D01*
G01X404030Y102743D02*
X404000Y102723D01*
G01X404057Y102774D02*
X404030Y102743D01*
G01X410195Y110558D02*
X410162Y110551D01*
G01X410225Y110578D02*
X410195Y110558D01*
G01X410252Y110609D02*
X410225Y110578D01*
G01X409860Y111135D02*
X409893Y111142D01*
G01X409829Y111115D02*
X409860Y111135D01*
G01X409803Y111084D02*
X409829Y111115D01*
G01X405173Y108300D02*
X405206Y108307D01*
G01X405142Y108281D02*
X405173Y108300D01*
G01X405116Y108249D02*
X405142Y108281D01*
G01X404000Y107723D02*
X403967Y107717D01*
G01X404030Y107743D02*
X404000Y107723D01*
G01X404057Y107774D02*
X404030Y107743D01*
G01X404362Y108249D02*
X404057Y107774D01*
G01X404811D02*
X405116Y108249D01*
G01X402759Y102717D02*
Y101142D01*
G01Y111142D02*
Y112717D01*
G01Y106142D02*
Y107717D01*
G01Y96142D02*
Y97717D01*
G01X403513Y111142D02*
Y112717D01*
G01Y106142D02*
Y107717D01*
G01Y101142D02*
Y102717D01*
G01Y96142D02*
Y97717D01*
G01X404267D02*
Y96142D01*
G01Y102717D02*
Y101142D01*
G01Y107717D02*
Y106142D01*
G01Y112717D02*
Y111142D01*
G01X404668Y104665D02*
Y103799D01*
G01Y110098D02*
Y110965D01*
G01Y106949D02*
Y107815D01*
G01Y100650D02*
Y101516D01*
G01Y97500D02*
Y98366D01*
G01X410370Y97717D02*
Y96142D01*
G01Y102717D02*
Y101142D01*
G01Y107717D02*
Y106142D01*
G01Y112717D02*
Y111142D01*
G01X404362Y103249D02*
X404057Y102774D01*
G01X409498Y110609D02*
X409803Y111084D01*
G01X404811Y102774D02*
X405116Y103249D01*
G01X410557Y111084D02*
X410252Y110609D01*
G01X404362Y98249D02*
X404057Y97774D01*
G01X409498Y105609D02*
X409803Y106084D01*
G01X404811Y97774D02*
X405116Y98249D01*
G01X410557Y106084D02*
X410252Y105609D01*
G01X409498Y100609D02*
X409803Y101084D01*
G01X410557D02*
X410252Y100609D01*
G01X411124Y111142D02*
Y112717D01*
G01Y106142D02*
Y107717D01*
G01Y101142D02*
Y102717D01*
G01Y96142D02*
Y97717D01*
G01X411878Y111142D02*
Y112717D01*
G01Y106142D02*
Y107717D01*
G01Y101142D02*
Y102717D01*
G01Y96142D02*
Y97717D01*
G01X414634Y111142D02*
Y112717D01*
G01Y106142D02*
Y107717D01*
G01Y101142D02*
Y102717D01*
G01Y96142D02*
Y97717D01*
G01X404057Y101084D02*
X404362Y100609D01*
G01X405116D02*
X404811Y101084D01*
G01X404057Y106084D02*
X404362Y105609D01*
G01X409803Y97774D02*
X409498Y98249D01*
G01X405116Y105609D02*
X404811Y106084D01*
G01X410252Y98249D02*
X410557Y97774D01*
G01X404057Y111084D02*
X404362Y110609D01*
G01X409803Y102774D02*
X409498Y103249D01*
G01X405116Y110609D02*
X404811Y111084D01*
G01X410252Y103249D02*
X410557Y102774D01*
G01X409803Y107774D02*
X409498Y108249D01*
G01X410252D02*
X410557Y107774D01*
G01X409803Y96084D02*
X410557D01*
G01X404057D02*
X404811D01*
G01X414634Y96142D02*
X409893D01*
G01X414634Y97717D02*
X409893D01*
G01X410557Y97774D02*
X409803D01*
G01X404057D02*
X404811D01*
G01X405116Y98249D02*
X404362D01*
G01X409498D02*
X410252D01*
G01X404452Y98307D02*
X410162D01*
G01Y100551D02*
X404452D01*
G01X409498Y100609D02*
X410252D01*
G01X404362D02*
X405116D01*
G01X410557Y101084D02*
X409803D01*
G01X404057D02*
X404811D01*
G01X414634Y101142D02*
X409893D01*
G01X414634Y102717D02*
X409893D01*
G01X410557Y102774D02*
X409803D01*
G01X404057D02*
X404811D01*
G01X405116Y103249D02*
X404362D01*
G01X409498D02*
X410252D01*
G01X404452Y103307D02*
X410162D01*
G01Y105551D02*
X404452D01*
G01X409498Y105609D02*
X410252D01*
G01X404362D02*
X405116D01*
G01X410557Y106084D02*
X409803D01*
G01X404057D02*
X404811D01*
G01X414634Y106142D02*
X409893D01*
G01X414634Y107717D02*
X409893D01*
G01X410557Y107774D02*
X409803D01*
G01X404057D02*
X404811D01*
G01X405116Y108249D02*
X404362D01*
G01X409498D02*
X410252D01*
G01X404452Y108307D02*
X410162D01*
G01Y110551D02*
X404452D01*
G01X405116Y110609D02*
X404362D01*
G01X409498D02*
X410252D01*
G01X409803Y111084D02*
X410557D01*
G01X404057D02*
X404811D01*
G01X414634Y111142D02*
X409893D01*
G01X410579Y127493D02*
X410553Y127462D01*
G01X410609Y127513D02*
X410579Y127493D01*
G01X410642Y127520D02*
X410609Y127513D01*
G01X409770Y127192D02*
X409796Y127223D01*
G01X409739Y127172D02*
X409770Y127192D01*
G01X409706Y127165D02*
X409739Y127172D01*
G01X410579Y124344D02*
X410553Y124312D01*
G01X410609Y124363D02*
X410579Y124344D01*
G01X410642Y124370D02*
X410609Y124363D01*
G01X409770Y124042D02*
X409796Y124073D01*
G01X409739Y124022D02*
X409770Y124042D01*
G01X409706Y124016D02*
X409739Y124022D01*
G01X410579Y121194D02*
X410553Y121163D01*
G01X410609Y121214D02*
X410579Y121194D01*
G01X410642Y121220D02*
X410609Y121214D01*
G01X409770Y120893D02*
X409796Y120924D01*
G01X409739Y120873D02*
X409770Y120893D01*
G01X409706Y120866D02*
X409739Y120873D01*
G01X404388Y118281D02*
X404362Y118249D01*
G01X404419Y118300D02*
X404388Y118281D01*
G01X404452Y118307D02*
X404419Y118300D01*
G01X404784Y117743D02*
X404811Y117774D01*
G01X404754Y117723D02*
X404784Y117743D01*
G01X404721Y117717D02*
X404754Y117723D01*
G01X410583Y116115D02*
X410557Y116084D01*
G01X410614Y116135D02*
X410583Y116115D01*
G01X410646Y116142D02*
X410614Y116135D01*
G01X409471Y115578D02*
X409498Y115609D01*
G01X409441Y115558D02*
X409471Y115578D01*
G01X409408Y115551D02*
X409441Y115558D01*
G01X404388Y113281D02*
X404362Y113249D01*
G01X404419Y113300D02*
X404388Y113281D01*
G01X404452Y113307D02*
X404419Y113300D01*
G01X404784Y112743D02*
X404811Y112774D01*
G01X404754Y112723D02*
X404784Y112743D01*
G01X404721Y112717D02*
X404754Y112723D01*
G01X410373Y128714D02*
X410399Y128682D01*
G01X410342Y128733D02*
X410373Y128714D01*
G01X410309Y128740D02*
X410342Y128733D01*
G01X409976Y128412D02*
X409949Y128443D01*
G01X410006Y128393D02*
X409976Y128412D01*
G01X410039Y128386D02*
X410006Y128393D01*
G01X410373Y125564D02*
X410399Y125533D01*
G01X410342Y125584D02*
X410373Y125564D01*
G01X410309Y125591D02*
X410342Y125584D01*
G01X409976Y125263D02*
X409949Y125294D01*
G01X410006Y125243D02*
X409976Y125263D01*
G01X410039Y125236D02*
X410006Y125243D01*
G01X410373Y122415D02*
X410399Y122383D01*
G01X410342Y122434D02*
X410373Y122415D01*
G01X410309Y122441D02*
X410342Y122434D01*
G01X409976Y122113D02*
X409949Y122144D01*
G01X410006Y122093D02*
X409976Y122113D01*
G01X410039Y122087D02*
X410006Y122093D01*
G01X410225Y118281D02*
X410252Y118249D01*
G01X410195Y118300D02*
X410225Y118281D01*
G01X410162Y118307D02*
X410195Y118300D01*
G01X409829Y117743D02*
X409803Y117774D01*
G01X409860Y117723D02*
X409829Y117743D01*
G01X409893Y117717D02*
X409860Y117723D01*
G01X404030Y116115D02*
X404057Y116084D01*
G01X404000Y116135D02*
X404030Y116115D01*
G01X403967Y116142D02*
X404000Y116135D01*
G01X405142Y115578D02*
X405116Y115609D01*
G01X405173Y115558D02*
X405142Y115578D01*
G01X405206Y115551D02*
X405173Y115558D01*
G01X410225Y113281D02*
X410252Y113249D01*
G01X410195Y113300D02*
X410225Y113281D01*
G01X410162Y113307D02*
X410195Y113300D01*
G01X409829Y112743D02*
X409803Y112774D01*
G01X409860Y112723D02*
X409829Y112743D01*
G01X409893Y112717D02*
X409860Y112723D01*
G01X410609Y128393D02*
X410642Y128386D01*
G01X410579Y128412D02*
X410609Y128393D01*
G01X410553Y128443D02*
X410579Y128412D01*
G01X409739Y128733D02*
X409706Y128740D01*
G01X409770Y128714D02*
X409739Y128733D01*
G01X409796Y128682D02*
X409770Y128714D01*
G01X410609Y125243D02*
X410642Y125236D01*
G01X410579Y125263D02*
X410609Y125243D01*
G01X410553Y125294D02*
X410579Y125263D01*
G01X409739Y125584D02*
X409706Y125591D01*
G01X409770Y125564D02*
X409739Y125584D01*
G01X409796Y125533D02*
X409770Y125564D01*
G01X410609Y122093D02*
X410642Y122087D01*
G01X410579Y122113D02*
X410609Y122093D01*
G01X410553Y122144D02*
X410579Y122113D01*
G01X409739Y122434D02*
X409706Y122441D01*
G01X409770Y122415D02*
X409739Y122434D01*
G01X409796Y122383D02*
X409770Y122415D01*
G01X410614Y117723D02*
X410646Y117717D01*
G01X410583Y117743D02*
X410614Y117723D01*
G01X410557Y117774D02*
X410583Y117743D01*
G01X409441Y118300D02*
X409408Y118307D01*
G01X409471Y118281D02*
X409441Y118300D01*
G01X409498Y118249D02*
X409471Y118281D01*
G01X410614Y112723D02*
X410646Y112717D01*
G01X410583Y112743D02*
X410614Y112723D01*
G01X410557Y112774D02*
X410583Y112743D01*
G01X409441Y113300D02*
X409408Y113307D01*
G01X409471Y113281D02*
X409441Y113300D01*
G01X409498Y113249D02*
X409471Y113281D01*
G01X404754Y116135D02*
X404721Y116142D01*
G01X404784Y116115D02*
X404754Y116135D01*
G01X404811Y116084D02*
X404784Y116115D01*
G01X404419Y115558D02*
X404452Y115551D01*
G01X404388Y115578D02*
X404419Y115558D01*
G01X404362Y115609D02*
X404388Y115578D01*
G01X410195Y115558D02*
X410162Y115551D01*
G01X410225Y115578D02*
X410195Y115558D01*
G01X410252Y115609D02*
X410225Y115578D01*
G01X409860Y116135D02*
X409893Y116142D01*
G01X409829Y116115D02*
X409860Y116135D01*
G01X409803Y116084D02*
X409829Y116115D01*
G01X405173Y113300D02*
X405206Y113307D01*
G01X405142Y113281D02*
X405173Y113300D01*
G01X405116Y113249D02*
X405142Y113281D01*
G01X404000Y112723D02*
X403967Y112717D01*
G01X404030Y112743D02*
X404000Y112723D01*
G01X404057Y112774D02*
X404030Y112743D01*
G01X410342Y120873D02*
X410309Y120866D01*
G01X410373Y120893D02*
X410342Y120873D01*
G01X410399Y120924D02*
X410373Y120893D01*
G01X410006Y121214D02*
X410039Y121220D01*
G01X409976Y121194D02*
X410006Y121214D01*
G01X409949Y121163D02*
X409976Y121194D01*
G01X410342Y124022D02*
X410309Y124016D01*
G01X410373Y124042D02*
X410342Y124022D01*
G01X410399Y124073D02*
X410373Y124042D01*
G01X405173Y118300D02*
X405206Y118307D01*
G01X405142Y118281D02*
X405173Y118300D01*
G01X405116Y118249D02*
X405142Y118281D01*
G01X410006Y124363D02*
X410039Y124370D01*
G01X409976Y124344D02*
X410006Y124363D01*
G01X409949Y124312D02*
X409976Y124344D01*
G01X404000Y117723D02*
X403967Y117717D01*
G01X404030Y117743D02*
X404000Y117723D01*
G01X404057Y117774D02*
X404030Y117743D01*
G01X410342Y127172D02*
X410309Y127165D01*
G01X410373Y127192D02*
X410342Y127172D01*
G01X410399Y127223D02*
X410373Y127192D01*
G01X410006Y127513D02*
X410039Y127520D01*
G01X409976Y127493D02*
X410006Y127513D01*
G01X409949Y127462D02*
X409976Y127493D01*
G01X409796Y127223D02*
X409949Y127462D01*
G01X404362Y118249D02*
X404057Y117774D01*
G01X410553Y127462D02*
X410399Y127223D01*
G01X404811Y117774D02*
X405116Y118249D01*
G01X409796Y124073D02*
X409949Y124312D01*
G01X410553D02*
X410399Y124073D01*
G01X404362Y113249D02*
X404057Y112774D01*
G01X409796Y120924D02*
X409949Y121163D01*
G01X404811Y112774D02*
X405116Y113249D01*
G01X410553Y121163D02*
X410399Y120924D01*
G01X409498Y115609D02*
X409803Y116084D01*
G01X410557D02*
X410252Y115609D01*
G01X402759Y117717D02*
Y116142D01*
G01X403513D02*
Y117717D01*
G01X403604Y125936D02*
Y126820D01*
G01Y122786D02*
Y123670D01*
G01Y120079D02*
Y120520D01*
G01X403802Y122559D02*
Y120748D01*
G01Y125709D02*
Y123898D01*
G01Y127047D02*
Y128858D01*
G01X404196D02*
Y127047D01*
G01Y123898D02*
Y125709D01*
G01Y120748D02*
Y122559D01*
G01X404267Y116142D02*
Y117717D01*
G01X404526Y120079D02*
Y138976D01*
G01X404668Y114114D02*
Y113248D01*
G01Y120413D02*
Y119547D01*
G01Y125846D02*
Y126713D01*
G01Y122697D02*
Y123563D01*
G01Y116398D02*
Y117264D01*
G01X410370Y117717D02*
Y116142D01*
G01X411124D02*
Y117717D01*
G01X411203Y122087D02*
Y121220D01*
G01Y125236D02*
Y124370D01*
G01Y128386D02*
Y127520D01*
G01X411806Y122087D02*
Y121220D01*
G01Y125236D02*
Y124370D01*
G01Y128386D02*
Y127520D01*
G01X411878Y116142D02*
Y117717D01*
G01X412561Y127520D02*
Y128386D01*
G01Y124370D02*
Y125236D01*
G01Y121220D02*
Y122087D01*
G01X413798Y121914D02*
Y121402D01*
G01X413862D02*
Y121827D01*
G01X413926Y121750D02*
Y121838D01*
G01X414011Y121914D02*
Y121848D01*
G01Y121467D02*
Y121402D01*
G01X414054Y121707D02*
Y121642D01*
G01X414331D02*
Y121467D01*
G01Y121848D02*
Y121707D01*
G01X414395Y121402D02*
Y121914D01*
G01X414634Y116142D02*
Y117717D01*
G01X414720Y122087D02*
Y121220D01*
G01Y125236D02*
Y124370D01*
G01Y128386D02*
Y127520D01*
G01X404057Y116084D02*
X404362Y115609D01*
G01X405116D02*
X404811Y116084D01*
G01X409803Y112774D02*
X409498Y113249D01*
G01X410252D02*
X410557Y112774D01*
G01X409803Y117774D02*
X409498Y118249D01*
G01X410252D02*
X410557Y117774D01*
G01X409949Y122144D02*
X409796Y122383D01*
G01X410399D02*
X410553Y122144D01*
G01X409949Y125294D02*
X409796Y125533D01*
G01X410399D02*
X410553Y125294D01*
G01X409949Y128443D02*
X409796Y128682D01*
G01X410399D02*
X410553Y128443D01*
G01X403047Y125709D02*
X403604Y125936D01*
G01X403047Y122559D02*
X403604Y122786D01*
G01X413862Y121827D02*
X413926Y121750D01*
G01Y121838D02*
X413862Y121914D01*
G01X403604Y120520D02*
X403047Y120748D01*
G01X403604Y123670D02*
X403047Y123898D01*
G01X403604Y126820D02*
X403047Y127047D01*
G01X414634Y112717D02*
X409893D01*
G01X410557Y112774D02*
X409803D01*
G01X404057D02*
X404811D01*
G01X405116Y113249D02*
X404668Y113248D01*
G01X409498Y113249D02*
X410252D01*
G01X404452Y113307D02*
X410162D01*
G01Y115551D02*
X404452D01*
G01X405116Y115609D02*
X404362D01*
G01X409498D02*
X410252D01*
G01X409803Y116084D02*
X410557D01*
G01X404057D02*
X404811D01*
G01X414634Y116142D02*
X409893D01*
G01X414634Y117717D02*
X409893D01*
G01X410557Y117774D02*
X409803D01*
G01X404057D02*
X404811D01*
G01X405116Y118249D02*
X404362D01*
G01X409498D02*
X410252D01*
G01X404452Y118307D02*
X410162D01*
G01X403604Y120520D02*
X404526D01*
G01X410399Y120924D02*
X409796D01*
G01X409949Y121163D02*
X410553D01*
G01X414720Y121220D02*
X410039D01*
G01X414011Y121402D02*
X414395D01*
G01X413798D02*
X413862D01*
G01X414331Y121467D02*
X414011D01*
G01X414054Y121642D02*
X414331D01*
G01Y121707D02*
X414054D01*
G01X414011Y121848D02*
X414331D01*
G01X414395Y121914D02*
X414011D01*
G01X413862D02*
X413798D01*
G01X410039Y122087D02*
X414719D01*
G01X410553Y122144D02*
X409949D01*
G01X409796Y122383D02*
X410399D01*
G01X404526Y122786D02*
X403604D01*
G01X404526Y123670D02*
X403604D01*
G01X410399Y124073D02*
X409796D01*
G01X409949Y124312D02*
X410553D01*
G01X414720Y124370D02*
X410039D01*
G01Y125236D02*
X414719D01*
G01X410553Y125294D02*
X409949D01*
G01X409796Y125533D02*
X410399D01*
G01X404526Y125936D02*
X403604D01*
G01X404526Y126820D02*
X403604D01*
G01X410399Y127223D02*
X409796D01*
G01X409949Y127462D02*
X410553D01*
G01X414720Y127520D02*
X410039D01*
G01Y128386D02*
X414719D01*
G01X410553Y128443D02*
X409949D01*
G01X409796Y128682D02*
X410399D01*
G01X404388Y143281D02*
X404362Y143249D01*
G01X404419Y143300D02*
X404388Y143281D01*
G01X404452Y143307D02*
X404419Y143300D01*
G01X404784Y142743D02*
X404811Y142774D01*
G01X404754Y142723D02*
X404784Y142743D01*
G01X404721Y142717D02*
X404754Y142723D01*
G01X410583Y141115D02*
X410557Y141084D01*
G01X410614Y141135D02*
X410583Y141115D01*
G01X410646Y141142D02*
X410614Y141135D01*
G01X409471Y140578D02*
X409498Y140609D01*
G01X409441Y140558D02*
X409471Y140578D01*
G01X409408Y140551D02*
X409441Y140558D01*
G01X410579Y136942D02*
X410553Y136911D01*
G01X410609Y136962D02*
X410579Y136942D01*
G01X410642Y136969D02*
X410609Y136962D01*
G01X409770Y136641D02*
X409796Y136672D01*
G01X409739Y136621D02*
X409770Y136641D01*
G01X409706Y136614D02*
X409739Y136621D01*
G01X410579Y133793D02*
X410553Y133761D01*
G01X410609Y133812D02*
X410579Y133793D01*
G01X410642Y133819D02*
X410609Y133812D01*
G01X409770Y133491D02*
X409796Y133522D01*
G01X409739Y133471D02*
X409770Y133491D01*
G01X409706Y133465D02*
X409739Y133471D01*
G01X410579Y130643D02*
X410553Y130611D01*
G01X410609Y130663D02*
X410579Y130643D01*
G01X410642Y130669D02*
X410609Y130663D01*
G01X409770Y130341D02*
X409796Y130372D01*
G01X409739Y130322D02*
X409770Y130341D01*
G01X409706Y130315D02*
X409739Y130322D01*
G01X410225Y143281D02*
X410252Y143249D01*
G01X410195Y143300D02*
X410225Y143281D01*
G01X410162Y143307D02*
X410195Y143300D01*
G01X409829Y142743D02*
X409803Y142774D01*
G01X409860Y142723D02*
X409829Y142743D01*
G01X409893Y142717D02*
X409860Y142723D01*
G01X404030Y141115D02*
X404057Y141084D01*
G01X404000Y141135D02*
X404030Y141115D01*
G01X403967Y141142D02*
X404000Y141135D01*
G01X405142Y140578D02*
X405116Y140609D01*
G01X405173Y140558D02*
X405142Y140578D01*
G01X405206Y140551D02*
X405173Y140558D01*
G01X410373Y138163D02*
X410399Y138131D01*
G01X410342Y138182D02*
X410373Y138163D01*
G01X410309Y138189D02*
X410342Y138182D01*
G01X409976Y137861D02*
X409949Y137892D01*
G01X410006Y137841D02*
X409976Y137861D01*
G01X410039Y137835D02*
X410006Y137841D01*
G01X410373Y135013D02*
X410399Y134982D01*
G01X410342Y135033D02*
X410373Y135013D01*
G01X410309Y135039D02*
X410342Y135033D01*
G01X409976Y134711D02*
X409949Y134743D01*
G01X410006Y134692D02*
X409976Y134711D01*
G01X410039Y134685D02*
X410006Y134692D01*
G01X410373Y131863D02*
X410399Y131832D01*
G01X410342Y131883D02*
X410373Y131863D01*
G01X410309Y131890D02*
X410342Y131883D01*
G01X409976Y131562D02*
X409949Y131593D01*
G01X410006Y131542D02*
X409976Y131562D01*
G01X410039Y131535D02*
X410006Y131542D01*
G01X410614Y142723D02*
X410646Y142717D01*
G01X410583Y142743D02*
X410614Y142723D01*
G01X410557Y142774D02*
X410583Y142743D01*
G01X409441Y143300D02*
X409408Y143307D01*
G01X409471Y143281D02*
X409441Y143300D01*
G01X409498Y143249D02*
X409471Y143281D01*
G01X410609Y137841D02*
X410642Y137835D01*
G01X410579Y137861D02*
X410609Y137841D01*
G01X410553Y137892D02*
X410579Y137861D01*
G01X409739Y138182D02*
X409706Y138189D01*
G01X409770Y138163D02*
X409739Y138182D01*
G01X409796Y138131D02*
X409770Y138163D01*
G01X410609Y134692D02*
X410642Y134685D01*
G01X410579Y134711D02*
X410609Y134692D01*
G01X410553Y134743D02*
X410579Y134711D01*
G01X404754Y141135D02*
X404721Y141142D01*
G01X404784Y141115D02*
X404754Y141135D01*
G01X404811Y141084D02*
X404784Y141115D01*
G01X409739Y135033D02*
X409706Y135039D01*
G01X409770Y135013D02*
X409739Y135033D01*
G01X409796Y134982D02*
X409770Y135013D01*
G01X404419Y140558D02*
X404452Y140551D01*
G01X404388Y140578D02*
X404419Y140558D01*
G01X404362Y140609D02*
X404388Y140578D01*
G01X410609Y131542D02*
X410642Y131535D01*
G01X410579Y131562D02*
X410609Y131542D01*
G01X410553Y131593D02*
X410579Y131562D01*
G01X409739Y131883D02*
X409706Y131890D01*
G01X409770Y131863D02*
X409739Y131883D01*
G01X409796Y131832D02*
X409770Y131863D01*
G01X410342Y130322D02*
X410309Y130315D01*
G01X410373Y130341D02*
X410342Y130322D01*
G01X410399Y130372D02*
X410373Y130341D01*
G01X410006Y130663D02*
X410039Y130669D01*
G01X409976Y130643D02*
X410006Y130663D01*
G01X409949Y130611D02*
X409976Y130643D01*
G01X410342Y133471D02*
X410309Y133465D01*
G01X410373Y133491D02*
X410342Y133471D01*
G01X410399Y133522D02*
X410373Y133491D01*
G01X410006Y133812D02*
X410039Y133819D01*
G01X409976Y133793D02*
X410006Y133812D01*
G01X409949Y133761D02*
X409976Y133793D01*
G01X410342Y136621D02*
X410309Y136614D01*
G01X410373Y136641D02*
X410342Y136621D01*
G01X410399Y136672D02*
X410373Y136641D01*
G01X410006Y136962D02*
X410039Y136969D01*
G01X409976Y136942D02*
X410006Y136962D01*
G01X409949Y136911D02*
X409976Y136942D01*
G01X410195Y140558D02*
X410162Y140551D01*
G01X410225Y140578D02*
X410195Y140558D01*
G01X410252Y140609D02*
X410225Y140578D01*
G01X409860Y141135D02*
X409893Y141142D01*
G01X409829Y141115D02*
X409860Y141135D01*
G01X409803Y141084D02*
X409829Y141115D01*
G01X405173Y143300D02*
X405206Y143307D01*
G01X405142Y143281D02*
X405173Y143300D01*
G01X405116Y143249D02*
X405142Y143281D01*
G01X404000Y142723D02*
X403967Y142717D01*
G01X404030Y142743D02*
X404000Y142723D01*
G01X404057Y142774D02*
X404030Y142743D01*
G01X404362Y143249D02*
X404057Y142774D01*
G01X404811D02*
X405116Y143249D01*
G01X413430Y142154D02*
X413469Y142195D01*
G01X413371Y142235D02*
X413312Y142154D01*
G01X409498Y140609D02*
X409803Y141084D01*
G01X410557D02*
X410252Y140609D01*
G01X409796Y136672D02*
X409949Y136911D01*
G01X410553D02*
X410399Y136672D01*
G01X409796Y133522D02*
X409949Y133761D01*
G01X410553D02*
X410399Y133522D01*
G01X409796Y130372D02*
X409949Y130611D01*
G01X410553D02*
X410399Y130372D01*
G01X413312Y142154D02*
X413292Y142094D01*
G01X413410D02*
X413430Y142154D01*
G01X402759Y141142D02*
Y142717D01*
G01X403513Y141142D02*
Y142717D01*
G01X403604Y138534D02*
Y138976D01*
G01Y135385D02*
Y136269D01*
G01Y132235D02*
Y133119D01*
G01Y129085D02*
Y129969D01*
G01X403802Y135158D02*
Y133346D01*
G01Y136496D02*
Y138307D01*
G01Y130197D02*
Y132008D01*
G01X404196D02*
Y130197D01*
G01Y136496D02*
Y138307D01*
G01Y133346D02*
Y135158D01*
G01X404267Y142717D02*
Y141142D01*
G01X404668Y129862D02*
Y128996D01*
G01Y139311D02*
Y138445D01*
G01Y145610D02*
Y144744D01*
G01Y141595D02*
Y142461D01*
G01Y135295D02*
Y136161D01*
G01Y132146D02*
Y133012D01*
G01X410370Y142717D02*
Y141142D01*
G01X413450Y142295D02*
X413371Y142235D01*
G01X411124Y141142D02*
Y142717D01*
G01X411203Y131535D02*
Y130669D01*
G01Y134685D02*
Y133819D01*
G01Y137835D02*
Y136969D01*
G01X411806Y131535D02*
Y130669D01*
G01Y134685D02*
Y133819D01*
G01Y137835D02*
Y136969D01*
G01X411878Y141142D02*
Y142717D01*
G01X412561Y136969D02*
Y137835D01*
G01Y133819D02*
Y134685D01*
G01Y130669D02*
Y131535D01*
G01X412898Y142315D02*
Y141370D01*
G01X413017D02*
Y142154D01*
G01X413135Y142014D02*
Y142174D01*
G01X413292Y142094D02*
Y142014D01*
G01X413410Y142034D02*
Y142094D01*
G01X413902Y142215D02*
Y141913D01*
G01Y141793D02*
Y141370D01*
G01X414020D02*
Y142315D01*
G01X414634Y141142D02*
Y142717D01*
G01X414720Y131535D02*
Y130669D01*
G01Y134685D02*
Y133819D01*
G01Y137835D02*
Y136969D01*
G01X413292Y142014D02*
X413312Y141953D01*
G01X413430Y141974D02*
X413410Y142034D01*
G01X413469Y142195D02*
X413528Y142215D01*
G01X403047Y138307D02*
X403604Y138534D01*
G01X403047Y135158D02*
X403604Y135385D01*
G01X403047Y132008D02*
X403604Y132235D01*
G01X403047Y128858D02*
X403604Y129085D01*
G01X409949Y131593D02*
X409796Y131832D01*
G01X404057Y141084D02*
X404362Y140609D01*
G01X410399Y131832D02*
X410553Y131593D01*
G01X405116Y140609D02*
X404811Y141084D01*
G01X409949Y134743D02*
X409796Y134982D01*
G01X410399D02*
X410553Y134743D01*
G01X409949Y137892D02*
X409796Y138131D01*
G01X410399D02*
X410553Y137892D01*
G01X409803Y142774D02*
X409498Y143249D01*
G01X410252D02*
X410557Y142774D01*
G01X413312Y141953D02*
X413371Y141873D01*
G01X413017Y142154D02*
X413135Y142014D01*
G01Y142174D02*
X413017Y142315D01*
G01X413469Y141933D02*
X413430Y141974D01*
G01X413371Y141873D02*
X413450Y141813D01*
G01X403604Y129969D02*
X403047Y130197D01*
G01X403604Y133119D02*
X403047Y133346D01*
G01X403604Y136269D02*
X403047Y136496D01*
G01X413528Y141913D02*
X413469Y141933D01*
G01X413450Y141813D02*
X413548Y141793D01*
G01X404526Y129085D02*
X403604D01*
G01Y129969D02*
X404526D01*
G01X410399Y130372D02*
X409796D01*
G01X409949Y130611D02*
X410553D01*
G01X414720Y130669D02*
X410039D01*
G01Y131535D02*
X414719D01*
G01X410553Y131593D02*
X409949D01*
G01X409796Y131832D02*
X410399D01*
G01X403604Y132235D02*
X404526D01*
G01Y133119D02*
X403604D01*
G01X410399Y133522D02*
X409796D01*
G01X409949Y133761D02*
X410553D01*
G01X414720Y133819D02*
X410039D01*
G01Y134685D02*
X414719D01*
G01X410553Y134743D02*
X409949D01*
G01X409796Y134982D02*
X410399D01*
G01X403604Y135385D02*
X404526D01*
G01Y136269D02*
X403604D01*
G01X410399Y136672D02*
X409796D01*
G01X409949Y136911D02*
X410553D01*
G01X414720Y136969D02*
X410039D01*
G01Y137835D02*
X414719D01*
G01X410553Y137892D02*
X409949D01*
G01X409796Y138131D02*
X410399D01*
G01X404526Y138534D02*
X403604D01*
G01X410162Y140551D02*
X404452D01*
G01X409498Y140609D02*
X410252D01*
G01X404362D02*
X405116D01*
G01X410557Y141084D02*
X409803D01*
G01X404057D02*
X404811D01*
G01X414634Y141142D02*
X409893D01*
G01X412898Y141370D02*
X413017D01*
G01X413902D02*
X414020D01*
G01X413548Y141793D02*
X413902D01*
G01Y141913D02*
X413528D01*
G01Y142215D02*
X413902D01*
G01X413017Y142315D02*
X412898D01*
G01X414020D02*
X413548D01*
G01X414634Y142717D02*
X409893D01*
G01X410557Y142774D02*
X409803D01*
G01X404057D02*
X404811D01*
G01X405116Y143249D02*
X404362D01*
G01X409498D02*
X410252D01*
G01X404452Y143307D02*
X410162D01*
G01X413548Y142315D02*
X413450Y142295D01*
G01X410583Y161115D02*
X410557Y161084D01*
G01X410614Y161135D02*
X410583Y161115D01*
G01X410646Y161142D02*
X410614Y161135D01*
G01X409471Y160578D02*
X409498Y160609D01*
G01X409441Y160558D02*
X409471Y160578D01*
G01X409408Y160551D02*
X409441Y160558D01*
G01X404388Y158281D02*
X404362Y158249D01*
G01X404419Y158300D02*
X404388Y158281D01*
G01X404452Y158307D02*
X404419Y158300D01*
G01X404784Y157743D02*
X404811Y157774D01*
G01X404754Y157723D02*
X404784Y157743D01*
G01X404721Y157717D02*
X404754Y157723D01*
G01X410583Y156115D02*
X410557Y156084D01*
G01X410614Y156135D02*
X410583Y156115D01*
G01X410646Y156142D02*
X410614Y156135D01*
G01X409471Y155578D02*
X409498Y155609D01*
G01X409441Y155558D02*
X409471Y155578D01*
G01X409408Y155551D02*
X409441Y155558D01*
G01X404388Y153281D02*
X404362Y153249D01*
G01X404419Y153300D02*
X404388Y153281D01*
G01X404452Y153307D02*
X404419Y153300D01*
G01X404784Y152743D02*
X404811Y152774D01*
G01X404754Y152723D02*
X404784Y152743D01*
G01X404721Y152717D02*
X404754Y152723D01*
G01X410583Y151115D02*
X410557Y151084D01*
G01X410614Y151135D02*
X410583Y151115D01*
G01X410646Y151142D02*
X410614Y151135D01*
G01X409471Y150578D02*
X409498Y150609D01*
G01X409441Y150558D02*
X409471Y150578D01*
G01X409408Y150551D02*
X409441Y150558D01*
G01X404388Y148281D02*
X404362Y148249D01*
G01X404419Y148300D02*
X404388Y148281D01*
G01X404452Y148307D02*
X404419Y148300D01*
G01X404784Y147743D02*
X404811Y147774D01*
G01X404754Y147723D02*
X404784Y147743D01*
G01X404721Y147717D02*
X404754Y147723D01*
G01X410583Y146115D02*
X410557Y146084D01*
G01X410614Y146135D02*
X410583Y146115D01*
G01X410646Y146142D02*
X410614Y146135D01*
G01X409471Y145578D02*
X409498Y145609D01*
G01X409441Y145558D02*
X409471Y145578D01*
G01X409408Y145551D02*
X409441Y145558D01*
G01X404030Y161115D02*
X404057Y161084D01*
G01X404000Y161135D02*
X404030Y161115D01*
G01X403967Y161142D02*
X404000Y161135D01*
G01X405142Y160578D02*
X405116Y160609D01*
G01X405173Y160558D02*
X405142Y160578D01*
G01X405206Y160551D02*
X405173Y160558D01*
G01X410225Y158281D02*
X410252Y158249D01*
G01X410195Y158300D02*
X410225Y158281D01*
G01X410162Y158307D02*
X410195Y158300D01*
G01X409829Y157743D02*
X409803Y157774D01*
G01X409860Y157723D02*
X409829Y157743D01*
G01X409893Y157717D02*
X409860Y157723D01*
G01X404030Y156115D02*
X404057Y156084D01*
G01X404000Y156135D02*
X404030Y156115D01*
G01X403967Y156142D02*
X404000Y156135D01*
G01X405142Y155578D02*
X405116Y155609D01*
G01X405173Y155558D02*
X405142Y155578D01*
G01X405206Y155551D02*
X405173Y155558D01*
G01X410225Y153281D02*
X410252Y153249D01*
G01X410195Y153300D02*
X410225Y153281D01*
G01X410162Y153307D02*
X410195Y153300D01*
G01X409829Y152743D02*
X409803Y152774D01*
G01X409860Y152723D02*
X409829Y152743D01*
G01X409893Y152717D02*
X409860Y152723D01*
G01X404030Y151115D02*
X404057Y151084D01*
G01X404000Y151135D02*
X404030Y151115D01*
G01X403967Y151142D02*
X404000Y151135D01*
G01X405142Y150578D02*
X405116Y150609D01*
G01X405173Y150558D02*
X405142Y150578D01*
G01X405206Y150551D02*
X405173Y150558D01*
G01X410225Y148281D02*
X410252Y148249D01*
G01X410195Y148300D02*
X410225Y148281D01*
G01X410162Y148307D02*
X410195Y148300D01*
G01X409829Y147743D02*
X409803Y147774D01*
G01X409860Y147723D02*
X409829Y147743D01*
G01X409893Y147717D02*
X409860Y147723D01*
G01X404030Y146115D02*
X404057Y146084D01*
G01X404000Y146135D02*
X404030Y146115D01*
G01X403967Y146142D02*
X404000Y146135D01*
G01X405142Y145578D02*
X405116Y145609D01*
G01X405173Y145558D02*
X405142Y145578D01*
G01X405206Y145551D02*
X405173Y145558D01*
G01X410614Y157723D02*
X410646Y157717D01*
G01X410583Y157743D02*
X410614Y157723D01*
G01X410557Y157774D02*
X410583Y157743D01*
G01X409441Y158300D02*
X409408Y158307D01*
G01X409471Y158281D02*
X409441Y158300D01*
G01X409498Y158249D02*
X409471Y158281D01*
G01X404754Y161135D02*
X404721Y161142D01*
G01X404784Y161115D02*
X404754Y161135D01*
G01X404811Y161084D02*
X404784Y161115D01*
G01X404419Y160558D02*
X404452Y160551D01*
G01X404388Y160578D02*
X404419Y160558D01*
G01X404362Y160609D02*
X404388Y160578D01*
G01X410614Y152723D02*
X410646Y152717D01*
G01X410583Y152743D02*
X410614Y152723D01*
G01X410557Y152774D02*
X410583Y152743D01*
G01X409441Y153300D02*
X409408Y153307D01*
G01X409471Y153281D02*
X409441Y153300D01*
G01X409498Y153249D02*
X409471Y153281D01*
G01X404754Y156135D02*
X404721Y156142D01*
G01X404784Y156115D02*
X404754Y156135D01*
G01X404811Y156084D02*
X404784Y156115D01*
G01X404419Y155558D02*
X404452Y155551D01*
G01X404388Y155578D02*
X404419Y155558D01*
G01X404362Y155609D02*
X404388Y155578D01*
G01X410614Y147723D02*
X410646Y147717D01*
G01X410583Y147743D02*
X410614Y147723D01*
G01X410557Y147774D02*
X410583Y147743D01*
G01X409441Y148300D02*
X409408Y148307D01*
G01X409471Y148281D02*
X409441Y148300D01*
G01X409498Y148249D02*
X409471Y148281D01*
G01X404754Y151135D02*
X404721Y151142D01*
G01X404784Y151115D02*
X404754Y151135D01*
G01X404811Y151084D02*
X404784Y151115D01*
G01X404419Y150558D02*
X404452Y150551D01*
G01X404388Y150578D02*
X404419Y150558D01*
G01X404362Y150609D02*
X404388Y150578D01*
G01X404754Y146135D02*
X404721Y146142D01*
G01X404784Y146115D02*
X404754Y146135D01*
G01X404811Y146084D02*
X404784Y146115D01*
G01X404419Y145558D02*
X404452Y145551D01*
G01X404388Y145578D02*
X404419Y145558D01*
G01X404362Y145609D02*
X404388Y145578D01*
G01X410195Y145558D02*
X410162Y145551D01*
G01X410225Y145578D02*
X410195Y145558D01*
G01X410252Y145609D02*
X410225Y145578D01*
G01X409860Y146135D02*
X409893Y146142D01*
G01X409829Y146115D02*
X409860Y146135D01*
G01X409803Y146084D02*
X409829Y146115D01*
G01X410195Y150558D02*
X410162Y150551D01*
G01X410225Y150578D02*
X410195Y150558D01*
G01X410252Y150609D02*
X410225Y150578D01*
G01X409860Y151135D02*
X409893Y151142D01*
G01X409829Y151115D02*
X409860Y151135D01*
G01X409803Y151084D02*
X409829Y151115D01*
G01X405173Y148300D02*
X405206Y148307D01*
G01X405142Y148281D02*
X405173Y148300D01*
G01X405116Y148249D02*
X405142Y148281D01*
G01X404000Y147723D02*
X403967Y147717D01*
G01X404030Y147743D02*
X404000Y147723D01*
G01X404057Y147774D02*
X404030Y147743D01*
G01X410195Y155558D02*
X410162Y155551D01*
G01X410225Y155578D02*
X410195Y155558D01*
G01X410252Y155609D02*
X410225Y155578D01*
G01X409860Y156135D02*
X409893Y156142D01*
G01X409829Y156115D02*
X409860Y156135D01*
G01X409803Y156084D02*
X409829Y156115D01*
G01X405173Y153300D02*
X405206Y153307D01*
G01X405142Y153281D02*
X405173Y153300D01*
G01X405116Y153249D02*
X405142Y153281D01*
G01X404000Y152723D02*
X403967Y152717D01*
G01X404030Y152743D02*
X404000Y152723D01*
G01X404057Y152774D02*
X404030Y152743D01*
G01X410195Y160558D02*
X410162Y160551D01*
G01X410225Y160578D02*
X410195Y160558D01*
G01X410252Y160609D02*
X410225Y160578D01*
G01X409860Y161135D02*
X409893Y161142D01*
G01X409829Y161115D02*
X409860Y161135D01*
G01X409803Y161084D02*
X409829Y161115D01*
G01X405173Y158300D02*
X405206Y158307D01*
G01X405142Y158281D02*
X405173Y158300D01*
G01X405116Y158249D02*
X405142Y158281D01*
G01X404000Y157723D02*
X403967Y157717D01*
G01X404030Y157743D02*
X404000Y157723D01*
G01X404057Y157774D02*
X404030Y157743D01*
G01X404362Y158249D02*
X404057Y157774D01*
G01X404811D02*
X405116Y158249D01*
G01X404362Y153249D02*
X404057Y152774D01*
G01X409498Y160609D02*
X409803Y161084D01*
G01X404811Y152774D02*
X405116Y153249D01*
G01X410557Y161084D02*
X410252Y160609D01*
G01X404362Y148249D02*
X404057Y147774D01*
G01X409498Y155609D02*
X409803Y156084D01*
G01X404811Y147774D02*
X405116Y148249D01*
G01X410557Y156084D02*
X410252Y155609D01*
G01X409498Y150609D02*
X409803Y151084D01*
G01X410557D02*
X410252Y150609D01*
G01X409498Y145609D02*
X409803Y146084D01*
G01X410557D02*
X410252Y145609D01*
G01X402759Y152717D02*
Y151142D01*
G01Y157717D02*
Y156142D01*
G01Y162717D02*
Y161142D01*
G01Y146142D02*
Y147717D01*
G01X403513Y161142D02*
Y162717D01*
G01Y156142D02*
Y157717D01*
G01Y151142D02*
Y152717D01*
G01Y146142D02*
Y147717D01*
G01X404267D02*
Y146142D01*
G01Y152717D02*
Y151142D01*
G01Y161142D02*
Y162717D01*
G01Y156142D02*
Y157717D01*
G01X404668Y155059D02*
Y154193D01*
G01Y160492D02*
Y161358D01*
G01Y157343D02*
Y158209D01*
G01Y151043D02*
Y151909D01*
G01Y147894D02*
Y148760D01*
G01X410370Y147717D02*
Y146142D01*
G01Y152717D02*
Y151142D01*
G01Y157717D02*
Y156142D01*
G01Y162717D02*
Y161142D01*
G01X411124D02*
Y162717D01*
G01Y156142D02*
Y157717D01*
G01Y151142D02*
Y152717D01*
G01Y146142D02*
Y147717D01*
G01X411878Y161142D02*
Y162717D01*
G01Y156142D02*
Y157717D01*
G01Y151142D02*
Y152717D01*
G01Y146142D02*
Y147717D01*
G01X414634Y161142D02*
Y162717D01*
G01Y156142D02*
Y157717D01*
G01Y151142D02*
Y152717D01*
G01Y146142D02*
Y147717D01*
G01X404057Y146084D02*
X404362Y145609D01*
G01X405116D02*
X404811Y146084D01*
G01X404057Y151084D02*
X404362Y150609D01*
G01X405116D02*
X404811Y151084D01*
G01X404057Y156084D02*
X404362Y155609D01*
G01X409803Y147774D02*
X409498Y148249D01*
G01X405116Y155609D02*
X404811Y156084D01*
G01X410252Y148249D02*
X410557Y147774D01*
G01X404057Y161084D02*
X404362Y160609D01*
G01X409803Y152774D02*
X409498Y153249D01*
G01X405116Y160609D02*
X404811Y161084D01*
G01X410252Y153249D02*
X410557Y152774D01*
G01X409803Y157774D02*
X409498Y158249D01*
G01X410252D02*
X410557Y157774D01*
G01X410162Y145551D02*
X404452D01*
G01X405116Y145609D02*
X404668Y145610D01*
G01X409498Y145609D02*
X410252D01*
G01X409803Y146084D02*
X410557D01*
G01X404057D02*
X404811D01*
G01X414634Y146142D02*
X409893D01*
G01X414634Y147717D02*
X409893D01*
G01X410557Y147774D02*
X409803D01*
G01X404057D02*
X404811D01*
G01X405116Y148249D02*
X404362D01*
G01X409498D02*
X410252D01*
G01X404452Y148307D02*
X410162D01*
G01Y150551D02*
X404452D01*
G01X409498Y150609D02*
X410252D01*
G01X404362D02*
X405116D01*
G01X410557Y151084D02*
X409803D01*
G01X404057D02*
X404811D01*
G01X414634Y151142D02*
X409893D01*
G01X414634Y152717D02*
X409893D01*
G01X410557Y152774D02*
X409803D01*
G01X404057D02*
X404811D01*
G01X405116Y153249D02*
X404362D01*
G01X409498D02*
X410252D01*
G01X404452Y153307D02*
X410162D01*
G01Y155551D02*
X404452D01*
G01X405116Y155609D02*
X404362D01*
G01X409498D02*
X410252D01*
G01X409803Y156084D02*
X410557D01*
G01X404057D02*
X404811D01*
G01X414634Y156142D02*
X409893D01*
G01X414634Y157717D02*
X409893D01*
G01X410557Y157774D02*
X409803D01*
G01X404057D02*
X404811D01*
G01X405116Y158249D02*
X404362D01*
G01X409498D02*
X410252D01*
G01X404452Y158307D02*
X410162D01*
G01Y160551D02*
X404452D01*
G01X405116Y160609D02*
X404362D01*
G01X409498D02*
X410252D01*
G01X409803Y161084D02*
X410557D01*
G01X404057D02*
X404811D01*
G01X414634Y161142D02*
X409893D01*
G01X404388Y178281D02*
X404362Y178249D01*
G01X404784Y177743D02*
X404811Y177774D01*
G01X404754Y177723D02*
X404784Y177743D01*
G01X404721Y177717D02*
X404754Y177723D01*
G01X410583Y176115D02*
X410557Y176084D01*
G01X410614Y176135D02*
X410583Y176115D01*
G01X410646Y176142D02*
X410614Y176135D01*
G01X409471Y175578D02*
X409498Y175609D01*
G01X409441Y175558D02*
X409471Y175578D01*
G01X409408Y175551D02*
X409441Y175558D01*
G01X404388Y173281D02*
X404362Y173249D01*
G01X404419Y173300D02*
X404388Y173281D01*
G01X404452Y173307D02*
X404419Y173300D01*
G01X404784Y172743D02*
X404811Y172774D01*
G01X404754Y172723D02*
X404784Y172743D01*
G01X404721Y172717D02*
X404754Y172723D01*
G01X410583Y171115D02*
X410557Y171084D01*
G01X410614Y171135D02*
X410583Y171115D01*
G01X410646Y171142D02*
X410614Y171135D01*
G01X409471Y170578D02*
X409498Y170609D01*
G01X409441Y170558D02*
X409471Y170578D01*
G01X409408Y170551D02*
X409441Y170558D01*
G01X404388Y168281D02*
X404362Y168249D01*
G01X404419Y168300D02*
X404388Y168281D01*
G01X404452Y168307D02*
X404419Y168300D01*
G01X404784Y167743D02*
X404811Y167774D01*
G01X404754Y167723D02*
X404784Y167743D01*
G01X404721Y167717D02*
X404754Y167723D01*
G01X410583Y166115D02*
X410557Y166084D01*
G01X410614Y166135D02*
X410583Y166115D01*
G01X410646Y166142D02*
X410614Y166135D01*
G01X409471Y165578D02*
X409498Y165609D01*
G01X409441Y165558D02*
X409471Y165578D01*
G01X409408Y165551D02*
X409441Y165558D01*
G01X404388Y163281D02*
X404362Y163249D01*
G01X404419Y163300D02*
X404388Y163281D01*
G01X404452Y163307D02*
X404419Y163300D01*
G01X404784Y162743D02*
X404811Y162774D01*
G01X404754Y162723D02*
X404784Y162743D01*
G01X404721Y162717D02*
X404754Y162723D01*
G01X410225Y178281D02*
X410252Y178249D01*
G01X409829Y177743D02*
X409803Y177774D01*
G01X409860Y177723D02*
X409829Y177743D01*
G01X409893Y177717D02*
X409860Y177723D01*
G01X404030Y176115D02*
X404057Y176084D01*
G01X404000Y176135D02*
X404030Y176115D01*
G01X403967Y176142D02*
X404000Y176135D01*
G01X405142Y175578D02*
X405116Y175609D01*
G01X405173Y175558D02*
X405142Y175578D01*
G01X405206Y175551D02*
X405173Y175558D01*
G01X410225Y173281D02*
X410252Y173249D01*
G01X410195Y173300D02*
X410225Y173281D01*
G01X410162Y173307D02*
X410195Y173300D01*
G01X409829Y172743D02*
X409803Y172774D01*
G01X409860Y172723D02*
X409829Y172743D01*
G01X409893Y172717D02*
X409860Y172723D01*
G01X404030Y171115D02*
X404057Y171084D01*
G01X404000Y171135D02*
X404030Y171115D01*
G01X403967Y171142D02*
X404000Y171135D01*
G01X405142Y170578D02*
X405116Y170609D01*
G01X405173Y170558D02*
X405142Y170578D01*
G01X405206Y170551D02*
X405173Y170558D01*
G01X410225Y168281D02*
X410252Y168249D01*
G01X410195Y168300D02*
X410225Y168281D01*
G01X410162Y168307D02*
X410195Y168300D01*
G01X409829Y167743D02*
X409803Y167774D01*
G01X409860Y167723D02*
X409829Y167743D01*
G01X409893Y167717D02*
X409860Y167723D01*
G01X404030Y166115D02*
X404057Y166084D01*
G01X404000Y166135D02*
X404030Y166115D01*
G01X403967Y166142D02*
X404000Y166135D01*
G01X405142Y165578D02*
X405116Y165609D01*
G01X405173Y165558D02*
X405142Y165578D01*
G01X405206Y165551D02*
X405173Y165558D01*
G01X410225Y163281D02*
X410252Y163249D01*
G01X410195Y163300D02*
X410225Y163281D01*
G01X410162Y163307D02*
X410195Y163300D01*
G01X409829Y162743D02*
X409803Y162774D01*
G01X409860Y162723D02*
X409829Y162743D01*
G01X409893Y162717D02*
X409860Y162723D01*
G01X410614Y177723D02*
X410646Y177717D01*
G01X410583Y177743D02*
X410614Y177723D01*
G01X410557Y177774D02*
X410583Y177743D01*
G01X409498Y178249D02*
X409471Y178281D01*
G01X410614Y172723D02*
X410646Y172717D01*
G01X410583Y172743D02*
X410614Y172723D01*
G01X410557Y172774D02*
X410583Y172743D01*
G01X409441Y173300D02*
X409408Y173307D01*
G01X409471Y173281D02*
X409441Y173300D01*
G01X409498Y173249D02*
X409471Y173281D01*
G01X404754Y176135D02*
X404721Y176142D01*
G01X404784Y176115D02*
X404754Y176135D01*
G01X404811Y176084D02*
X404784Y176115D01*
G01X404419Y175558D02*
X404452Y175551D01*
G01X404388Y175578D02*
X404419Y175558D01*
G01X404362Y175609D02*
X404388Y175578D01*
G01X410614Y167723D02*
X410646Y167717D01*
G01X410583Y167743D02*
X410614Y167723D01*
G01X410557Y167774D02*
X410583Y167743D01*
G01X409441Y168300D02*
X409408Y168307D01*
G01X409471Y168281D02*
X409441Y168300D01*
G01X409498Y168249D02*
X409471Y168281D01*
G01X404754Y171135D02*
X404721Y171142D01*
G01X404784Y171115D02*
X404754Y171135D01*
G01X404811Y171084D02*
X404784Y171115D01*
G01X404419Y170558D02*
X404452Y170551D01*
G01X404388Y170578D02*
X404419Y170558D01*
G01X404362Y170609D02*
X404388Y170578D01*
G01X410614Y162723D02*
X410646Y162717D01*
G01X410583Y162743D02*
X410614Y162723D01*
G01X410557Y162774D02*
X410583Y162743D01*
G01X409441Y163300D02*
X409408Y163307D01*
G01X409471Y163281D02*
X409441Y163300D01*
G01X409498Y163249D02*
X409471Y163281D01*
G01X404754Y166135D02*
X404721Y166142D01*
G01X404784Y166115D02*
X404754Y166135D01*
G01X404811Y166084D02*
X404784Y166115D01*
G01X404419Y165558D02*
X404452Y165551D01*
G01X404388Y165578D02*
X404419Y165558D01*
G01X404362Y165609D02*
X404388Y165578D01*
G01X410195Y165558D02*
X410162Y165551D01*
G01X410225Y165578D02*
X410195Y165558D01*
G01X410252Y165609D02*
X410225Y165578D01*
G01X409860Y166135D02*
X409893Y166142D01*
G01X409829Y166115D02*
X409860Y166135D01*
G01X409803Y166084D02*
X409829Y166115D01*
G01X405173Y163300D02*
X405206Y163307D01*
G01X405142Y163281D02*
X405173Y163300D01*
G01X405116Y163249D02*
X405142Y163281D01*
G01X404000Y162723D02*
X403967Y162717D01*
G01X404030Y162743D02*
X404000Y162723D01*
G01X404057Y162774D02*
X404030Y162743D01*
G01X410195Y170558D02*
X410162Y170551D01*
G01X410225Y170578D02*
X410195Y170558D01*
G01X410252Y170609D02*
X410225Y170578D01*
G01X409860Y171135D02*
X409893Y171142D01*
G01X409829Y171115D02*
X409860Y171135D01*
G01X409803Y171084D02*
X409829Y171115D01*
G01X405173Y168300D02*
X405206Y168307D01*
G01X405142Y168281D02*
X405173Y168300D01*
G01X405116Y168249D02*
X405142Y168281D01*
G01X404000Y167723D02*
X403967Y167717D01*
G01X404030Y167743D02*
X404000Y167723D01*
G01X404057Y167774D02*
X404030Y167743D01*
G01X410195Y175558D02*
X410162Y175551D01*
G01X410225Y175578D02*
X410195Y175558D01*
G01X410252Y175609D02*
X410225Y175578D01*
G01X409860Y176135D02*
X409893Y176142D01*
G01X409829Y176115D02*
X409860Y176135D01*
G01X409803Y176084D02*
X409829Y176115D01*
G01X405173Y173300D02*
X405206Y173307D01*
G01X405142Y173281D02*
X405173Y173300D01*
G01X405116Y173249D02*
X405142Y173281D01*
G01X404000Y172723D02*
X403967Y172717D01*
G01X404030Y172743D02*
X404000Y172723D01*
G01X404057Y172774D02*
X404030Y172743D01*
G01X405116Y178249D02*
X405142Y178281D01*
G01X404000Y177723D02*
X403967Y177717D01*
G01X404030Y177743D02*
X404000Y177723D01*
G01X404057Y177774D02*
X404030Y177743D01*
G01X404362Y178249D02*
X404057Y177774D01*
G01X404811D02*
X405116Y178249D01*
G01X404362Y173249D02*
X404057Y172774D01*
G01X404811D02*
X405116Y173249D01*
G01X404362Y168249D02*
X404057Y167774D01*
G01X409498Y175609D02*
X409803Y176084D01*
G01X404811Y167774D02*
X405116Y168249D01*
G01X410557Y176084D02*
X410252Y175609D01*
G01X404362Y163249D02*
X404057Y162774D01*
G01X409498Y170609D02*
X409803Y171084D01*
G01X404811Y162774D02*
X405116Y163249D01*
G01X410557Y171084D02*
X410252Y170609D01*
G01X409498Y165609D02*
X409803Y166084D01*
G01X410557D02*
X410252Y165609D01*
G01X402759Y167717D02*
Y166142D01*
G01Y172717D02*
Y171142D01*
G01Y176142D02*
Y177717D01*
G01X403513Y176142D02*
Y177717D01*
G01Y171142D02*
Y172717D01*
G01Y166142D02*
Y167717D01*
G01X404267Y172717D02*
Y171142D01*
G01Y177717D02*
Y176142D01*
G01Y166142D02*
Y167717D01*
G01X404668Y164508D02*
Y163642D01*
G01Y173957D02*
Y173091D01*
G01Y176240D02*
Y177106D01*
G01Y169941D02*
Y170807D01*
G01Y166791D02*
Y167658D01*
G01X410370Y167717D02*
Y166142D01*
G01Y172717D02*
Y171142D01*
G01Y177717D02*
Y176142D01*
G01X411124D02*
Y177717D01*
G01Y171142D02*
Y172717D01*
G01Y166142D02*
Y167717D01*
G01X411878Y176142D02*
Y177717D01*
G01Y171142D02*
Y172717D01*
G01Y166142D02*
Y167717D01*
G01X414634Y176142D02*
Y177717D01*
G01Y171142D02*
Y172717D01*
G01Y166142D02*
Y167717D01*
G01X404057Y166084D02*
X404362Y165609D01*
G01X405116D02*
X404811Y166084D01*
G01X404057Y171084D02*
X404362Y170609D01*
G01X409803Y162774D02*
X409498Y163249D01*
G01X405116Y170609D02*
X404811Y171084D01*
G01X410252Y163249D02*
X410557Y162774D01*
G01X404057Y176084D02*
X404362Y175609D01*
G01X409803Y167774D02*
X409498Y168249D01*
G01X405116Y175609D02*
X404811Y176084D01*
G01X410252Y168249D02*
X410557Y167774D01*
G01X409803Y172774D02*
X409498Y173249D01*
G01X410252D02*
X410557Y172774D01*
G01X409803Y177774D02*
X409498Y178249D01*
G01X410252D02*
X410557Y177774D01*
G01X414634Y162717D02*
X409893D01*
G01X410557Y162774D02*
X409803D01*
G01X404057D02*
X404811D01*
G01X405116Y163249D02*
X404362D01*
G01X409498D02*
X410252D01*
G01X404452Y163307D02*
X410162D01*
G01Y165551D02*
X404452D01*
G01X405116Y165609D02*
X404362D01*
G01X409498D02*
X410252D01*
G01X409803Y166084D02*
X410557D01*
G01X404057D02*
X404811D01*
G01X414634Y166142D02*
X409893D01*
G01X414634Y167717D02*
X409893D01*
G01X410557Y167774D02*
X409803D01*
G01X404057D02*
X404811D01*
G01X405116Y168249D02*
X404362D01*
G01X409498D02*
X410252D01*
G01X404452Y168307D02*
X410162D01*
G01Y170551D02*
X404452D01*
G01X409498Y170609D02*
X410252D01*
G01X404362D02*
X405116D01*
G01X410557Y171084D02*
X409803D01*
G01X404057D02*
X404811D01*
G01X414634Y171142D02*
X409893D01*
G01X414634Y172717D02*
X409893D01*
G01X410557Y172774D02*
X409803D01*
G01X404057D02*
X404811D01*
G01X405116Y173249D02*
X404362D01*
G01X409498D02*
X410252D01*
G01X404452Y173307D02*
X410162D01*
G01Y175551D02*
X404452D01*
G01X405116Y175609D02*
X404362D01*
G01X409498D02*
X410252D01*
G01X409803Y176084D02*
X410557D01*
G01X404057D02*
X404811D01*
G01X414634Y176142D02*
X409893D01*
G01X414634Y177717D02*
X409893D01*
G01X410557Y177774D02*
X409803D01*
G01X404057D02*
X404811D01*
G01X405116Y178249D02*
X404362D01*
G01X409498D02*
X410252D01*
G01X404388Y193281D02*
X404362Y193249D01*
G01X404419Y193300D02*
X404388Y193281D01*
G01X404452Y193307D02*
X404419Y193300D01*
G01X404784Y192743D02*
X404811Y192774D01*
G01X404754Y192723D02*
X404784Y192743D01*
G01X404721Y192717D02*
X404754Y192723D01*
G01X410583Y191115D02*
X410557Y191084D01*
G01X410614Y191135D02*
X410583Y191115D01*
G01X410646Y191142D02*
X410614Y191135D01*
G01X409471Y190578D02*
X409498Y190609D01*
G01X409441Y190558D02*
X409471Y190578D01*
G01X409408Y190551D02*
X409441Y190558D01*
G01X404388Y188281D02*
X404362Y188249D01*
G01X404419Y188300D02*
X404388Y188281D01*
G01X404452Y188307D02*
X404419Y188300D01*
G01X404784Y187743D02*
X404811Y187774D01*
G01X404754Y187723D02*
X404784Y187743D01*
G01X404721Y187717D02*
X404754Y187723D01*
G01X410583Y186115D02*
X410557Y186084D01*
G01X410614Y186135D02*
X410583Y186115D01*
G01X410646Y186142D02*
X410614Y186135D01*
G01X409471Y185578D02*
X409498Y185609D01*
G01X409441Y185558D02*
X409471Y185578D01*
G01X409408Y185551D02*
X409441Y185558D01*
G01X404388Y183281D02*
X404362Y183249D01*
G01X404419Y183300D02*
X404388Y183281D01*
G01X404452Y183307D02*
X404419Y183300D01*
G01X404784Y182743D02*
X404811Y182774D01*
G01X404754Y182723D02*
X404784Y182743D01*
G01X404721Y182717D02*
X404754Y182723D01*
G01X410583Y181115D02*
X410557Y181084D01*
G01X410614Y181135D02*
X410583Y181115D01*
G01X410646Y181142D02*
X410614Y181135D01*
G01X409471Y180578D02*
X409498Y180609D01*
G01X409441Y180558D02*
X409471Y180578D01*
G01X409408Y180551D02*
X409441Y180558D01*
G01X404419Y178300D02*
X404388Y178281D01*
G01X404452Y178307D02*
X404419Y178300D01*
G01X410225Y193281D02*
X410252Y193249D01*
G01X410195Y193300D02*
X410225Y193281D01*
G01X410162Y193307D02*
X410195Y193300D01*
G01X409829Y192743D02*
X409803Y192774D01*
G01X409860Y192723D02*
X409829Y192743D01*
G01X409893Y192717D02*
X409860Y192723D01*
G01X404030Y191115D02*
X404057Y191084D01*
G01X404000Y191135D02*
X404030Y191115D01*
G01X403967Y191142D02*
X404000Y191135D01*
G01X405142Y190578D02*
X405116Y190609D01*
G01X405173Y190558D02*
X405142Y190578D01*
G01X405206Y190551D02*
X405173Y190558D01*
G01X410225Y188281D02*
X410252Y188249D01*
G01X410195Y188300D02*
X410225Y188281D01*
G01X410162Y188307D02*
X410195Y188300D01*
G01X409829Y187743D02*
X409803Y187774D01*
G01X409860Y187723D02*
X409829Y187743D01*
G01X409893Y187717D02*
X409860Y187723D01*
G01X404030Y186115D02*
X404057Y186084D01*
G01X404000Y186135D02*
X404030Y186115D01*
G01X403967Y186142D02*
X404000Y186135D01*
G01X405142Y185578D02*
X405116Y185609D01*
G01X405173Y185558D02*
X405142Y185578D01*
G01X405206Y185551D02*
X405173Y185558D01*
G01X410225Y183281D02*
X410252Y183249D01*
G01X410195Y183300D02*
X410225Y183281D01*
G01X410162Y183307D02*
X410195Y183300D01*
G01X409829Y182743D02*
X409803Y182774D01*
G01X409860Y182723D02*
X409829Y182743D01*
G01X409893Y182717D02*
X409860Y182723D01*
G01X404030Y181115D02*
X404057Y181084D01*
G01X404000Y181135D02*
X404030Y181115D01*
G01X403967Y181142D02*
X404000Y181135D01*
G01X405142Y180578D02*
X405116Y180609D01*
G01X405173Y180558D02*
X405142Y180578D01*
G01X405206Y180551D02*
X405173Y180558D01*
G01X410195Y178300D02*
X410225Y178281D01*
G01X410162Y178307D02*
X410195Y178300D01*
G01X410614Y192723D02*
X410646Y192717D01*
G01X410583Y192743D02*
X410614Y192723D01*
G01X410557Y192774D02*
X410583Y192743D01*
G01X409441Y193300D02*
X409408Y193307D01*
G01X409471Y193281D02*
X409441Y193300D01*
G01X409498Y193249D02*
X409471Y193281D01*
G01X410614Y187723D02*
X410646Y187717D01*
G01X410583Y187743D02*
X410614Y187723D01*
G01X410557Y187774D02*
X410583Y187743D01*
G01X409441Y188300D02*
X409408Y188307D01*
G01X409471Y188281D02*
X409441Y188300D01*
G01X409498Y188249D02*
X409471Y188281D01*
G01X404754Y191135D02*
X404721Y191142D01*
G01X404784Y191115D02*
X404754Y191135D01*
G01X404811Y191084D02*
X404784Y191115D01*
G01X404419Y190558D02*
X404452Y190551D01*
G01X404388Y190578D02*
X404419Y190558D01*
G01X404362Y190609D02*
X404388Y190578D01*
G01X410614Y182723D02*
X410646Y182717D01*
G01X410583Y182743D02*
X410614Y182723D01*
G01X410557Y182774D02*
X410583Y182743D01*
G01X409441Y183300D02*
X409408Y183307D01*
G01X409471Y183281D02*
X409441Y183300D01*
G01X409498Y183249D02*
X409471Y183281D01*
G01X404754Y186135D02*
X404721Y186142D01*
G01X404784Y186115D02*
X404754Y186135D01*
G01X404811Y186084D02*
X404784Y186115D01*
G01X404419Y185558D02*
X404452Y185551D01*
G01X404388Y185578D02*
X404419Y185558D01*
G01X404362Y185609D02*
X404388Y185578D01*
G01X409441Y178300D02*
X409408Y178307D01*
G01X409471Y178281D02*
X409441Y178300D01*
G01X404754Y181135D02*
X404721Y181142D01*
G01X404784Y181115D02*
X404754Y181135D01*
G01X404811Y181084D02*
X404784Y181115D01*
G01X404419Y180558D02*
X404452Y180551D01*
G01X404388Y180578D02*
X404419Y180558D01*
G01X404362Y180609D02*
X404388Y180578D01*
G01X410195Y180558D02*
X410162Y180551D01*
G01X410225Y180578D02*
X410195Y180558D01*
G01X410252Y180609D02*
X410225Y180578D01*
G01X409860Y181135D02*
X409893Y181142D01*
G01X409829Y181115D02*
X409860Y181135D01*
G01X409803Y181084D02*
X409829Y181115D01*
G01X405173Y178300D02*
X405206Y178307D01*
G01X405142Y178281D02*
X405173Y178300D01*
G01X410195Y185558D02*
X410162Y185551D01*
G01X410225Y185578D02*
X410195Y185558D01*
G01X410252Y185609D02*
X410225Y185578D01*
G01X409860Y186135D02*
X409893Y186142D01*
G01X409829Y186115D02*
X409860Y186135D01*
G01X409803Y186084D02*
X409829Y186115D01*
G01X405173Y183300D02*
X405206Y183307D01*
G01X405142Y183281D02*
X405173Y183300D01*
G01X405116Y183249D02*
X405142Y183281D01*
G01X404000Y182723D02*
X403967Y182717D01*
G01X404030Y182743D02*
X404000Y182723D01*
G01X404057Y182774D02*
X404030Y182743D01*
G01X410195Y190558D02*
X410162Y190551D01*
G01X410225Y190578D02*
X410195Y190558D01*
G01X410252Y190609D02*
X410225Y190578D01*
G01X409860Y191135D02*
X409893Y191142D01*
G01X409829Y191115D02*
X409860Y191135D01*
G01X409803Y191084D02*
X409829Y191115D01*
G01X405173Y188300D02*
X405206Y188307D01*
G01X405142Y188281D02*
X405173Y188300D01*
G01X405116Y188249D02*
X405142Y188281D01*
G01X404000Y187723D02*
X403967Y187717D01*
G01X404030Y187743D02*
X404000Y187723D01*
G01X404057Y187774D02*
X404030Y187743D01*
G01X405173Y193300D02*
X405206Y193307D01*
G01X405142Y193281D02*
X405173Y193300D01*
G01X405116Y193249D02*
X405142Y193281D01*
G01X404000Y192723D02*
X403967Y192717D01*
G01X404030Y192743D02*
X404000Y192723D01*
G01X404057Y192774D02*
X404030Y192743D01*
G01X404362Y193249D02*
X404057Y192774D01*
G01X404811D02*
X405116Y193249D01*
G01X404362Y188249D02*
X404057Y187774D01*
G01X404811D02*
X405116Y188249D01*
G01X404362Y183249D02*
X404057Y182774D01*
G01X409498Y190609D02*
X409803Y191084D01*
G01X404811Y182774D02*
X405116Y183249D01*
G01X410557Y191084D02*
X410252Y190609D01*
G01X409498Y185609D02*
X409803Y186084D01*
G01X410557D02*
X410252Y185609D01*
G01X409498Y180609D02*
X409803Y181084D01*
G01X410557D02*
X410252Y180609D01*
G01X402759Y187717D02*
Y186142D01*
G01Y191142D02*
Y192717D01*
G01Y181142D02*
Y182717D01*
G01X403513Y191142D02*
Y192717D01*
G01Y186142D02*
Y187717D01*
G01Y181142D02*
Y182717D01*
G01X404267D02*
Y181142D01*
G01Y192717D02*
Y191142D01*
G01Y186142D02*
Y187717D01*
G01X404668Y183406D02*
Y182539D01*
G01Y192854D02*
Y191988D01*
G01Y188839D02*
Y189705D01*
G01Y185689D02*
Y186555D01*
G01Y179390D02*
Y180256D01*
G01X410370Y182717D02*
Y181142D01*
G01Y187717D02*
Y186142D01*
G01Y192717D02*
Y191142D01*
G01X411124D02*
Y192717D01*
G01Y186142D02*
Y187717D01*
G01Y181142D02*
Y182717D01*
G01X411878Y191142D02*
Y192717D01*
G01Y186142D02*
Y187717D01*
G01Y181142D02*
Y182717D01*
G01X414634Y191142D02*
Y192717D01*
G01Y186142D02*
Y187717D01*
G01Y181142D02*
Y182717D01*
G01X404057Y181084D02*
X404362Y180609D01*
G01X405116D02*
X404811Y181084D01*
G01X404057Y186084D02*
X404362Y185609D01*
G01X405116D02*
X404811Y186084D01*
G01X404057Y191084D02*
X404362Y190609D01*
G01X409803Y182774D02*
X409498Y183249D01*
G01X405116Y190609D02*
X404811Y191084D01*
G01X410252Y183249D02*
X410557Y182774D01*
G01X409803Y187774D02*
X409498Y188249D01*
G01X410252D02*
X410557Y187774D01*
G01X409803Y192774D02*
X409498Y193249D01*
G01X410252D02*
X410557Y192774D01*
G01X404452Y178307D02*
X410162D01*
G01Y180551D02*
X404452D01*
G01X405116Y180609D02*
X404362D01*
G01X409498D02*
X410252D01*
G01X409803Y181084D02*
X410557D01*
G01X404057D02*
X404811D01*
G01X414634Y181142D02*
X409893D01*
G01X414634Y182717D02*
X409893D01*
G01X410557Y182774D02*
X409803D01*
G01X404057D02*
X404811D01*
G01X405116Y183249D02*
X404362D01*
G01X409498D02*
X410252D01*
G01X404452Y183307D02*
X410162D01*
G01Y185551D02*
X404452D01*
G01X405116Y185609D02*
X404362D01*
G01X409498D02*
X410252D01*
G01X409803Y186084D02*
X410557D01*
G01X404057D02*
X404811D01*
G01X414634Y186142D02*
X409893D01*
G01X414634Y187717D02*
X409893D01*
G01X410557Y187774D02*
X409803D01*
G01X404057D02*
X404811D01*
G01X405116Y188249D02*
X404362D01*
G01X409498D02*
X410252D01*
G01X404452Y188307D02*
X410162D01*
G01Y190551D02*
X404452D01*
G01X405116Y190609D02*
X404362D01*
G01X409498D02*
X410252D01*
G01X409803Y191084D02*
X410557D01*
G01X404057D02*
X404811D01*
G01X414634Y191142D02*
X409893D01*
G01X414634Y192717D02*
X409893D01*
G01X410557Y192774D02*
X409803D01*
G01X404057D02*
X404811D01*
G01X405116Y193249D02*
X404362D01*
G01X409498D02*
X410252D01*
G01X404452Y193307D02*
X410162D01*
G01X410583Y211115D02*
X410557Y211084D01*
G01X410614Y211135D02*
X410583Y211115D01*
G01X410646Y211142D02*
X410614Y211135D01*
G01X409471Y210578D02*
X409498Y210609D01*
G01X409441Y210558D02*
X409471Y210578D01*
G01X409408Y210551D02*
X409441Y210558D01*
G01X404388Y208281D02*
X404362Y208249D01*
G01X404419Y208300D02*
X404388Y208281D01*
G01X404452Y208307D02*
X404419Y208300D01*
G01X404784Y207743D02*
X404811Y207774D01*
G01X404754Y207723D02*
X404784Y207743D01*
G01X404721Y207717D02*
X404754Y207723D01*
G01X410583Y206115D02*
X410557Y206084D01*
G01X410614Y206135D02*
X410583Y206115D01*
G01X410646Y206142D02*
X410614Y206135D01*
G01X409471Y205578D02*
X409498Y205609D01*
G01X409441Y205558D02*
X409471Y205578D01*
G01X409408Y205551D02*
X409441Y205558D01*
G01X404388Y203281D02*
X404362Y203249D01*
G01X404419Y203300D02*
X404388Y203281D01*
G01X404452Y203307D02*
X404419Y203300D01*
G01X404784Y202743D02*
X404811Y202774D01*
G01X404754Y202723D02*
X404784Y202743D01*
G01X404721Y202717D02*
X404754Y202723D01*
G01X410583Y201115D02*
X410557Y201084D01*
G01X410614Y201135D02*
X410583Y201115D01*
G01X410646Y201142D02*
X410614Y201135D01*
G01X409471Y200578D02*
X409498Y200609D01*
G01X409441Y200558D02*
X409471Y200578D01*
G01X409408Y200551D02*
X409441Y200558D01*
G01X404388Y198281D02*
X404362Y198249D01*
G01X404419Y198300D02*
X404388Y198281D01*
G01X404452Y198307D02*
X404419Y198300D01*
G01X404784Y197743D02*
X404811Y197774D01*
G01X404754Y197723D02*
X404784Y197743D01*
G01X404721Y197717D02*
X404754Y197723D01*
G01X410583Y196115D02*
X410557Y196084D01*
G01X410614Y196135D02*
X410583Y196115D01*
G01X410646Y196142D02*
X410614Y196135D01*
G01X409471Y195578D02*
X409498Y195609D01*
G01X409441Y195558D02*
X409471Y195578D01*
G01X409408Y195551D02*
X409441Y195558D01*
G01X404030Y211115D02*
X404057Y211084D01*
G01X404000Y211135D02*
X404030Y211115D01*
G01X403967Y211142D02*
X404000Y211135D01*
G01X405142Y210578D02*
X405116Y210609D01*
G01X405173Y210558D02*
X405142Y210578D01*
G01X405206Y210551D02*
X405173Y210558D01*
G01X410225Y208281D02*
X410252Y208249D01*
G01X410195Y208300D02*
X410225Y208281D01*
G01X410162Y208307D02*
X410195Y208300D01*
G01X409829Y207743D02*
X409803Y207774D01*
G01X409860Y207723D02*
X409829Y207743D01*
G01X409893Y207717D02*
X409860Y207723D01*
G01X404030Y206115D02*
X404057Y206084D01*
G01X404000Y206135D02*
X404030Y206115D01*
G01X403967Y206142D02*
X404000Y206135D01*
G01X405142Y205578D02*
X405116Y205609D01*
G01X405173Y205558D02*
X405142Y205578D01*
G01X405206Y205551D02*
X405173Y205558D01*
G01X410225Y203281D02*
X410252Y203249D01*
G01X410195Y203300D02*
X410225Y203281D01*
G01X410162Y203307D02*
X410195Y203300D01*
G01X409829Y202743D02*
X409803Y202774D01*
G01X409860Y202723D02*
X409829Y202743D01*
G01X409893Y202717D02*
X409860Y202723D01*
G01X404030Y201115D02*
X404057Y201084D01*
G01X404000Y201135D02*
X404030Y201115D01*
G01X403967Y201142D02*
X404000Y201135D01*
G01X405142Y200578D02*
X405116Y200609D01*
G01X405173Y200558D02*
X405142Y200578D01*
G01X405206Y200551D02*
X405173Y200558D01*
G01X410225Y198281D02*
X410252Y198249D01*
G01X410195Y198300D02*
X410225Y198281D01*
G01X410162Y198307D02*
X410195Y198300D01*
G01X409829Y197743D02*
X409803Y197774D01*
G01X409860Y197723D02*
X409829Y197743D01*
G01X409893Y197717D02*
X409860Y197723D01*
G01X404030Y196115D02*
X404057Y196084D01*
G01X404000Y196135D02*
X404030Y196115D01*
G01X403967Y196142D02*
X404000Y196135D01*
G01X405142Y195578D02*
X405116Y195609D01*
G01X405173Y195558D02*
X405142Y195578D01*
G01X405206Y195551D02*
X405173Y195558D01*
G01X410614Y207723D02*
X410646Y207717D01*
G01X410583Y207743D02*
X410614Y207723D01*
G01X410557Y207774D02*
X410583Y207743D01*
G01X409441Y208300D02*
X409408Y208307D01*
G01X409471Y208281D02*
X409441Y208300D01*
G01X409498Y208249D02*
X409471Y208281D01*
G01X404754Y211135D02*
X404721Y211142D01*
G01X404784Y211115D02*
X404754Y211135D01*
G01X404811Y211084D02*
X404784Y211115D01*
G01X404419Y210558D02*
X404452Y210551D01*
G01X404388Y210578D02*
X404419Y210558D01*
G01X404362Y210609D02*
X404388Y210578D01*
G01X410614Y202723D02*
X410646Y202717D01*
G01X410583Y202743D02*
X410614Y202723D01*
G01X410557Y202774D02*
X410583Y202743D01*
G01X409441Y203300D02*
X409408Y203307D01*
G01X409471Y203281D02*
X409441Y203300D01*
G01X409498Y203249D02*
X409471Y203281D01*
G01X404754Y206135D02*
X404721Y206142D01*
G01X404784Y206115D02*
X404754Y206135D01*
G01X404811Y206084D02*
X404784Y206115D01*
G01X404419Y205558D02*
X404452Y205551D01*
G01X404388Y205578D02*
X404419Y205558D01*
G01X404362Y205609D02*
X404388Y205578D01*
G01X410614Y197723D02*
X410646Y197717D01*
G01X410583Y197743D02*
X410614Y197723D01*
G01X410557Y197774D02*
X410583Y197743D01*
G01X409441Y198300D02*
X409408Y198307D01*
G01X409471Y198281D02*
X409441Y198300D01*
G01X409498Y198249D02*
X409471Y198281D01*
G01X404754Y201135D02*
X404721Y201142D01*
G01X404784Y201115D02*
X404754Y201135D01*
G01X404811Y201084D02*
X404784Y201115D01*
G01X404419Y200558D02*
X404452Y200551D01*
G01X404388Y200578D02*
X404419Y200558D01*
G01X404362Y200609D02*
X404388Y200578D01*
G01X404754Y196135D02*
X404721Y196142D01*
G01X404784Y196115D02*
X404754Y196135D01*
G01X404811Y196084D02*
X404784Y196115D01*
G01X404419Y195558D02*
X404452Y195551D01*
G01X404388Y195578D02*
X404419Y195558D01*
G01X404362Y195609D02*
X404388Y195578D01*
G01X410195Y195558D02*
X410162Y195551D01*
G01X410225Y195578D02*
X410195Y195558D01*
G01X410252Y195609D02*
X410225Y195578D01*
G01X409860Y196135D02*
X409893Y196142D01*
G01X409829Y196115D02*
X409860Y196135D01*
G01X409803Y196084D02*
X409829Y196115D01*
G01X410195Y200558D02*
X410162Y200551D01*
G01X410225Y200578D02*
X410195Y200558D01*
G01X410252Y200609D02*
X410225Y200578D01*
G01X409860Y201135D02*
X409893Y201142D01*
G01X409829Y201115D02*
X409860Y201135D01*
G01X409803Y201084D02*
X409829Y201115D01*
G01X405173Y198300D02*
X405206Y198307D01*
G01X405142Y198281D02*
X405173Y198300D01*
G01X405116Y198249D02*
X405142Y198281D01*
G01X404000Y197723D02*
X403967Y197717D01*
G01X404030Y197743D02*
X404000Y197723D01*
G01X404057Y197774D02*
X404030Y197743D01*
G01X410195Y205558D02*
X410162Y205551D01*
G01X410225Y205578D02*
X410195Y205558D01*
G01X410252Y205609D02*
X410225Y205578D01*
G01X409860Y206135D02*
X409893Y206142D01*
G01X409829Y206115D02*
X409860Y206135D01*
G01X409803Y206084D02*
X409829Y206115D01*
G01X405173Y203300D02*
X405206Y203307D01*
G01X405142Y203281D02*
X405173Y203300D01*
G01X405116Y203249D02*
X405142Y203281D01*
G01X404000Y202723D02*
X403967Y202717D01*
G01X404030Y202743D02*
X404000Y202723D01*
G01X404057Y202774D02*
X404030Y202743D01*
G01X410195Y210558D02*
X410162Y210551D01*
G01X410225Y210578D02*
X410195Y210558D01*
G01X410252Y210609D02*
X410225Y210578D01*
G01X409860Y211135D02*
X409893Y211142D01*
G01X409829Y211115D02*
X409860Y211135D01*
G01X409803Y211084D02*
X409829Y211115D01*
G01X405173Y208300D02*
X405206Y208307D01*
G01X405142Y208281D02*
X405173Y208300D01*
G01X405116Y208249D02*
X405142Y208281D01*
G01X404000Y207723D02*
X403967Y207717D01*
G01X404030Y207743D02*
X404000Y207723D01*
G01X404057Y207774D02*
X404030Y207743D01*
G01X404362Y208249D02*
X404057Y207774D01*
G01X404811D02*
X405116Y208249D01*
G01X404362Y203249D02*
X404057Y202774D01*
G01X409498Y210609D02*
X409803Y211084D01*
G01X404811Y202774D02*
X405116Y203249D01*
G01X410557Y211084D02*
X410252Y210609D01*
G01X404362Y198249D02*
X404057Y197774D01*
G01X409498Y205609D02*
X409803Y206084D01*
G01X404811Y197774D02*
X405116Y198249D01*
G01X410557Y206084D02*
X410252Y205609D01*
G01X409498Y200609D02*
X409803Y201084D01*
G01X410557D02*
X410252Y200609D01*
G01X409498Y195609D02*
X409803Y196084D01*
G01X410557D02*
X410252Y195609D01*
G01X402759Y197717D02*
Y196142D01*
G01Y202717D02*
Y201142D01*
G01Y211142D02*
Y212717D01*
G01Y206142D02*
Y207717D01*
G01X403513Y211142D02*
Y212717D01*
G01Y206142D02*
Y207717D01*
G01Y201142D02*
Y202717D01*
G01Y196142D02*
Y197717D01*
G01X404267Y207717D02*
Y206142D01*
G01Y212717D02*
Y211142D01*
G01Y201142D02*
Y202717D01*
G01Y196142D02*
Y197717D01*
G01X404668Y202303D02*
Y201437D01*
G01Y211752D02*
Y210886D01*
G01Y207736D02*
Y208602D01*
G01Y204587D02*
Y205453D01*
G01Y198287D02*
Y199154D01*
G01Y195138D02*
Y196004D01*
G01X410370Y197717D02*
Y196142D01*
G01Y202717D02*
Y201142D01*
G01Y207717D02*
Y206142D01*
G01Y212717D02*
Y211142D01*
G01X411124D02*
Y212717D01*
G01Y206142D02*
Y207717D01*
G01Y201142D02*
Y202717D01*
G01Y196142D02*
Y197717D01*
G01X411878Y211142D02*
Y212717D01*
G01Y206142D02*
Y207717D01*
G01Y201142D02*
Y202717D01*
G01Y196142D02*
Y197717D01*
G01X414634Y211142D02*
Y212717D01*
G01Y206142D02*
Y207717D01*
G01Y201142D02*
Y202717D01*
G01Y196142D02*
Y197717D01*
G01X404057Y196084D02*
X404362Y195609D01*
G01X405116D02*
X404811Y196084D01*
G01X404057Y201084D02*
X404362Y200609D01*
G01X405116D02*
X404811Y201084D01*
G01X404057Y206084D02*
X404362Y205609D01*
G01X409803Y197774D02*
X409498Y198249D01*
G01X405116Y205609D02*
X404811Y206084D01*
G01X410252Y198249D02*
X410557Y197774D01*
G01X404057Y211084D02*
X404362Y210609D01*
G01X409803Y202774D02*
X409498Y203249D01*
G01X405116Y210609D02*
X404811Y211084D01*
G01X410252Y203249D02*
X410557Y202774D01*
G01X409803Y207774D02*
X409498Y208249D01*
G01X410252D02*
X410557Y207774D01*
G01X410162Y195551D02*
X404452D01*
G01X405116Y195609D02*
X404362D01*
G01X409498D02*
X410252D01*
G01X409803Y196084D02*
X410557D01*
G01X404057D02*
X404811D01*
G01X414634Y196142D02*
X409893D01*
G01X414634Y197717D02*
X409893D01*
G01X410557Y197774D02*
X409803D01*
G01X404057D02*
X404811D01*
G01X405116Y198249D02*
X404362D01*
G01X409498D02*
X410252D01*
G01X404452Y198307D02*
X410162D01*
G01Y200551D02*
X404452D01*
G01X405116Y200609D02*
X404362D01*
G01X409498D02*
X410252D01*
G01X409803Y201084D02*
X410557D01*
G01X404057D02*
X404811D01*
G01X414634Y201142D02*
X409893D01*
G01X414634Y202717D02*
X409893D01*
G01X410557Y202774D02*
X409803D01*
G01X404057D02*
X404811D01*
G01X405116Y203249D02*
X404362D01*
G01X409498D02*
X410252D01*
G01X404452Y203307D02*
X410162D01*
G01Y205551D02*
X404452D01*
G01X409498Y205609D02*
X410252D01*
G01X404362D02*
X405116D01*
G01X410557Y206084D02*
X409803D01*
G01X404057D02*
X404811D01*
G01X414634Y206142D02*
X409893D01*
G01X414634Y207717D02*
X409893D01*
G01X410557Y207774D02*
X409803D01*
G01X404057D02*
X404811D01*
G01X405116Y208249D02*
X404362D01*
G01X409498D02*
X410252D01*
G01X404452Y208307D02*
X410162D01*
G01Y210551D02*
X404452D01*
G01X409498Y210609D02*
X410252D01*
G01X404362D02*
X405116D01*
G01X410557Y211084D02*
X409803D01*
G01X404057D02*
X404811D01*
G01X414634Y211142D02*
X409893D01*
G01X506495Y200197D02*
X403345D01*
G01X404388Y213281D02*
X404362Y213249D01*
G01X404419Y213300D02*
X404388Y213281D01*
G01X404452Y213307D02*
X404419Y213300D01*
G01X404784Y212743D02*
X404811Y212774D01*
G01X404754Y212723D02*
X404784Y212743D01*
G01X404721Y212717D02*
X404754Y212723D01*
G01X410225Y213281D02*
X410252Y213249D01*
G01X410195Y213300D02*
X410225Y213281D01*
G01X410162Y213307D02*
X410195Y213300D01*
G01X409829Y212743D02*
X409803Y212774D01*
G01X409860Y212723D02*
X409829Y212743D01*
G01X409893Y212717D02*
X409860Y212723D01*
G01X410614D02*
X410646Y212717D01*
G01X410583Y212743D02*
X410614Y212723D01*
G01X410557Y212774D02*
X410583Y212743D01*
G01X409441Y213300D02*
X409408Y213307D01*
G01X409471Y213281D02*
X409441Y213300D01*
G01X409498Y213249D02*
X409471Y213281D01*
G01X405173Y213300D02*
X405206Y213307D01*
G01X405142Y213281D02*
X405173Y213300D01*
G01X405116Y213249D02*
X405142Y213281D01*
G01X404000Y212723D02*
X403967Y212717D01*
G01X404030Y212743D02*
X404000Y212723D01*
G01X404057Y212774D02*
X404030Y212743D01*
G01X419093Y215236D02*
G03X420274Y216417I0J1181D01*
G01X409841Y227579D02*
G03Y224823I0J-1378D01*
G01X411810D02*
G03Y227579I0J1378D01*
G01Y224429D02*
G03Y227972I0J1772D01*
G01X409841D02*
G03Y224429I0J-1771D01*
G01X411810Y223642D02*
G03Y228760I0J2559D01*
G01X409841D02*
G03Y223642I0J-2559D01*
G01X404362Y213249D02*
X404057Y212774D01*
G01X404811D02*
X405116Y213249D01*
G01X402952Y233543D02*
Y215236D01*
G01X403345Y232736D02*
Y216004D01*
G01Y232736D02*
Y216004D01*
G01X404920Y215236D02*
Y233543D01*
G01X405314Y230945D02*
Y221496D01*
G01X409841Y228760D02*
Y227579D01*
G01Y223642D02*
Y224823D01*
G01X411810D02*
Y223642D01*
G01Y228760D02*
Y227579D01*
G01X414763Y221496D02*
Y230945D01*
G01X415550Y222333D02*
Y218396D01*
G01X409803Y212774D02*
X409498Y213249D01*
G01X410252D02*
X410557Y212774D01*
G01X414634Y212717D02*
X409893D01*
G01X410557Y212774D02*
X409803D01*
G01X404057D02*
X404811D01*
G01X405116Y213249D02*
X404362D01*
G01X409498D02*
X410252D01*
G01X404452Y213307D02*
X410162D01*
G01X419093Y215236D02*
X403186D01*
G01X419487Y218396D02*
X415550D01*
G01X405314Y221496D02*
X414763D01*
G01X419487Y222333D02*
X415550D01*
G01X411810Y223642D02*
X409841D01*
G01Y224429D02*
X411810D01*
G01Y224823D02*
X409841D01*
G01Y227579D02*
X411810D01*
G01X403345Y232736D02*
Y216004D01*
G01X403346Y232736D02*
Y216004D01*
G01X420274Y232362D02*
G03X419093Y233543I-1181J0D01*
G01X402952Y233854D02*
Y233543D01*
G01Y244370D02*
Y233854D01*
G01X410240Y235236D02*
Y258071D01*
G01X411810Y227972D02*
X409841D01*
G01Y228760D02*
X411810D01*
G01X405314Y230945D02*
X414763D01*
G01X419093Y233543D02*
X403159D01*
G01X418901Y235236D02*
X410240D01*
G01X411819Y265945D02*
G03Y258071I0J-3937D01*
G01X407157Y381710D02*
Y384510D01*
G01X450786Y-87638D02*
G03X419290I-15748J0D01*
G03X450786I15748J0D01*
G01D02*
G03X419290I-15748J0D01*
G03X450786I15748J0D01*
G01X442026D02*
G03X428050I-6988J0D01*
G03X442026I6988J0D01*
G01D02*
G03X428050I-6988J0D01*
G03X442026I6988J0D01*
G01D02*
G03X428050I-6988J0D01*
G03X442026I6988J0D01*
G01X435038Y-94626D02*
G03Y-80649I0J6988D01*
G01D02*
G03Y-94626I0J-6988D01*
G01X434251Y-7874D02*
Y984D01*
G01X714566Y-7874D02*
X434251D01*
G01X434448Y2795D02*
G03X435235Y2008I787J0D01*
G01X434448Y6929D02*
Y2795D01*
G01X466534Y2008D02*
X435235D01*
G01X434448Y5158D02*
X439763D01*
G01X434448Y6339D02*
X437400D01*
G01Y6929D02*
X434448D01*
G01X419487Y78898D02*
Y82835D01*
G01X420274Y82441D02*
Y66496D01*
G01X435235Y88622D02*
G03X434448Y87835I0J-787D01*
G01D02*
Y83701D01*
G01X437400D02*
X434448D01*
G01X437400Y84291D02*
X434448D01*
G01X439763Y85472D02*
X434448D01*
G01X466534Y88622D02*
X435235D01*
G01X434448Y111457D02*
G03X435235Y110669I787J-1D01*
G01X434448Y115591D02*
Y111457D01*
G01X466534Y110669D02*
X435235D01*
G01X434448Y113819D02*
X439763D01*
G01X434448Y115000D02*
X437400D01*
G01Y115591D02*
X434448D01*
G01Y196496D02*
Y192362D01*
G01X437400D02*
X434448D01*
G01X437400Y192953D02*
X434448D01*
G01X439763Y194134D02*
X434448D01*
G01X435235Y197283D02*
G03X434448Y196496I0J-787D01*
G01X466534Y197283D02*
X435235D01*
G01X420145Y235236D02*
G03X435038Y224606I14893J5118D01*
G01X419487Y218396D02*
Y222333D01*
G01X420274Y216417D02*
Y232362D01*
G01X435038Y223425D02*
Y217520D01*
G01D02*
X506495D01*
G01X428149Y363425D02*
Y265945D01*
G01X437724Y-740940D02*
Y-758263D01*
G01X436139Y13228D02*
G03X435942Y13032I0J-197D01*
G01Y12638D02*
G03X436139Y12441I197J0D01*
G01Y11260D02*
G03X435942Y11063I0J-197D01*
G01Y10669D02*
G03X436139Y10472I197J0D01*
G01Y9291D02*
G03X435942Y9095I0J-197D01*
G01Y8701D02*
G03X436139Y8504I197J0D01*
G01X442440Y7244D02*
G03X443227Y6457I787J0D01*
G01X452085D02*
G03X452873Y7244I1J787D01*
G01X444776Y12309D02*
X444843Y12178D01*
G01X444575Y11128D02*
X444508Y11325D01*
G01X444776D02*
X444843Y11128D01*
G01X444575Y12178D02*
X444508Y12375D01*
G01X444709Y10997D02*
X444575Y11128D01*
G01X444843D02*
X444977Y10997D01*
G01X444776Y11982D02*
X444575Y12178D01*
G01X444843D02*
X444910Y12113D01*
G01X435942Y12638D02*
Y13032D01*
G01Y10669D02*
Y11063D01*
G01Y8701D02*
Y9095D01*
G01X437400Y5158D02*
Y85472D01*
G01X439763Y5158D02*
Y85472D01*
G01X442440Y26890D02*
Y7244D01*
G01X443503Y8569D02*
Y9095D01*
G01X444508Y12375D02*
Y12638D01*
G01Y11325D02*
Y11588D01*
G01Y10669D02*
Y10997D01*
G01X444910Y12113D02*
X445044Y12047D01*
G01X446652Y7520D02*
X443503Y8569D01*
G01X443771Y8832D02*
X445580Y8241D01*
G01X445848Y8176D02*
X446652Y7913D01*
G01X444776Y11457D02*
Y11325D01*
G01Y12506D02*
Y12309D01*
G01X445580Y8241D02*
Y9422D01*
G01X445848Y9488D02*
Y8176D01*
G01X446652Y7913D02*
Y7520D01*
G01Y10144D02*
Y9750D01*
G01Y12047D02*
Y11719D01*
G01Y13097D02*
Y12769D01*
G01Y10997D02*
Y10669D01*
G01X443227Y6457D02*
X452085D01*
G01X444508Y12638D02*
X444575Y12835D01*
G01X444508Y11588D02*
X444575Y11785D01*
G01X437400Y8504D02*
X436139D01*
G01X437400Y9291D02*
X436139D01*
G01X437400Y10472D02*
X436139D01*
G01X446652Y10669D02*
X444508D01*
G01X444977Y10997D02*
X446652D01*
G01X444508D02*
X444709D01*
G01X437400Y11260D02*
X436139D01*
G01X446652Y11719D02*
X445044D01*
G01Y12047D02*
X446652D01*
G01X437400Y12441D02*
X436139D01*
G01X446652Y12769D02*
X445044D01*
G01Y13097D02*
X446652D01*
G01X437400Y13228D02*
X436139D01*
G01X444843Y12638D02*
X444776Y12506D01*
G01X444843Y11588D02*
X444776Y11457D01*
G01X444575Y12835D02*
X444709Y12966D01*
G01X444910Y12703D02*
X444843Y12638D01*
G01X444575Y11785D02*
X444776Y11982D01*
G01X444910Y11654D02*
X444843Y11588D01*
G01X445044Y12769D02*
X444910Y12703D01*
G01X445044Y11719D02*
X444910Y11654D01*
G01X443503Y9095D02*
X446652Y10144D01*
G01X444709Y12966D02*
X445044Y13097D01*
G01X445580Y9422D02*
X443771Y8832D01*
G01X446652Y9750D02*
X445848Y9488D01*
G01X436139Y28976D02*
G03X435942Y28780I0J-197D01*
G01Y28386D02*
G03X436139Y28189I197J0D01*
G01Y27008D02*
G03X435942Y26811I0J-197D01*
G01Y26417D02*
G03X436139Y26220I197J0D01*
G01Y25039D02*
G03X435942Y24843I0J-197D01*
G01Y24449D02*
G03X436139Y24252I197J0D01*
G01Y23071D02*
G03X435942Y22874I0J-197D01*
G01Y22480D02*
G03X436139Y22283I197J0D01*
G01Y21102D02*
G03X435942Y20906I0J-197D01*
G01Y20512D02*
G03X436139Y20315I197J0D01*
G01Y19134D02*
G03X435942Y18937I0J-197D01*
G01Y18543D02*
G03X436139Y18346I197J0D01*
G01Y17165D02*
G03X435942Y16969I0J-197D01*
G01Y16575D02*
G03X436139Y16378I197J0D01*
G01Y15197D02*
G03X435942Y15000I0J-197D01*
G01Y14606D02*
G03X436139Y14409I197J0D01*
G01X443227Y27677D02*
G03X442440Y26890I0J-787D01*
G01X452873D02*
G03X452085Y27677I-787J0D01*
G01X444642Y14147D02*
X444575Y14278D01*
G01X444910D02*
X445044Y14081D01*
G01X446384Y19659D02*
X446317Y20118D01*
G01X446585Y20183D02*
X446652Y19724D01*
G01X444575Y19331D02*
X444508Y19724D01*
G01X444575Y14278D02*
X444508Y14541D01*
G01X444843D02*
X444910Y14278D01*
G01X444575Y16903D02*
X444508Y17165D01*
G01X444776D02*
X444843Y16903D01*
G01X444776Y19659D02*
X444843Y19396D01*
G01X446317Y14803D02*
X446250Y15065D01*
G01X444575Y21890D02*
X444508Y22152D01*
G01X444776D02*
X444843Y21890D01*
G01X446585Y15197D02*
X446652Y14934D01*
G01X444575Y24120D02*
X444508Y24383D01*
G01X444776Y24514D02*
X444843Y24252D01*
G01X446384Y24777D02*
X446317Y25039D01*
G01X446585Y25170D02*
X446652Y24908D01*
G01X444642Y19134D02*
X444575Y19331D01*
G01X444843Y19396D02*
X444910Y19265D01*
G01X446451Y20446D02*
X446585Y20183D01*
G01X444642Y23989D02*
X444575Y24120D01*
G01X446518Y25302D02*
X446585Y25170D01*
G01X444709Y16706D02*
X444575Y16903D01*
G01X444843D02*
X444977Y16706D01*
G01X446250Y15065D02*
X446116Y15262D01*
G01X446451Y15394D02*
X446585Y15197D01*
G01X444776Y18937D02*
X444642Y19134D01*
G01X444709Y21693D02*
X444575Y21890D01*
G01X444843D02*
X444977Y21693D01*
G01X446317Y20118D02*
X446183Y20315D01*
G01X444776Y14016D02*
X444642Y14147D01*
G01X444843Y16575D02*
X444709Y16706D01*
G01X444977D02*
X445111Y16575D01*
G01X444910Y18806D02*
X444776Y18937D01*
G01X444910Y19265D02*
X445111Y19068D01*
G01X444843Y21561D02*
X444709Y21693D01*
G01X444977D02*
X445111Y21561D01*
G01X446250Y20643D02*
X446451Y20446D01*
G01X444776Y23858D02*
X444642Y23989D01*
G01X444843Y24252D02*
X444977Y24120D01*
G01X446317Y25039D02*
X446183Y25170D01*
G01X446384Y25433D02*
X446518Y25302D01*
G01X446116Y15656D02*
X446451Y15394D01*
G01X445044Y14081D02*
X445245Y13950D01*
G01X435942Y28386D02*
Y28780D01*
G01Y26417D02*
Y26811D01*
G01Y24449D02*
Y24843D01*
G01Y22480D02*
Y22874D01*
G01Y20512D02*
Y20906D01*
G01Y18543D02*
Y18937D01*
G01Y16575D02*
Y16969D01*
G01Y14606D02*
Y15000D01*
G01X443503Y26220D02*
Y26548D01*
G01Y16246D02*
Y16575D01*
G01X444508Y24383D02*
Y24908D01*
G01Y22152D02*
Y22415D01*
G01Y21233D02*
Y21561D01*
G01Y17165D02*
Y17428D01*
G01Y14541D02*
Y14934D01*
G01Y13622D02*
Y13950D01*
G01X444977Y23727D02*
X444776Y23858D01*
G01X444977Y24120D02*
X445178Y23989D01*
G01X446183Y25170D02*
X445982Y25302D01*
G01X446183Y25564D02*
X446384Y25433D01*
G01X444910Y13950D02*
X444776Y14016D01*
G01X446116Y15262D02*
X445982Y15328D01*
G01X445178Y18674D02*
X444910Y18806D01*
G01X445111Y19068D02*
X445245Y19002D01*
G01X449409Y18150D02*
X451889Y17231D01*
G01X451554Y16969D02*
X448739Y17953D01*
G01X445982Y15328D02*
X445781Y15394D01*
G01X444508Y24908D02*
X444575Y25170D01*
G01X444843Y25039D02*
X444776Y24777D01*
G01X444843Y22415D02*
X444776Y22152D01*
G01X444508Y19724D02*
X444575Y20118D01*
G01X444843Y20052D02*
X444776Y19659D01*
G01X446652Y19724D02*
X446585Y19331D01*
G01X444776Y24777D02*
Y24514D01*
G01X444843Y14934D02*
Y14541D01*
G01X445312Y19002D02*
Y20380D01*
G01X445580Y20709D02*
Y18937D01*
G01X445982Y20380D02*
Y20709D01*
G01X446317Y14541D02*
Y14803D01*
G01X446384Y24514D02*
Y24777D01*
G01X446652Y14934D02*
Y14541D01*
G01Y16575D02*
Y16246D01*
G01Y18084D02*
Y17756D01*
G01Y21561D02*
Y21233D01*
G01Y24908D02*
Y24383D01*
G01Y23071D02*
Y22743D01*
G01Y26548D02*
Y26220D01*
G01X447724Y13950D02*
Y13622D01*
G01X448739Y17953D02*
Y18543D01*
G01Y15394D02*
Y15984D01*
G01X451889Y15787D02*
Y15394D01*
G01Y17231D02*
Y16706D01*
G01Y18543D02*
Y18150D01*
G01X446183Y20315D02*
X445982Y20380D01*
G01X445178Y23661D02*
X444977Y23727D01*
G01X445714Y25695D02*
X446183Y25564D01*
G01X445848Y15722D02*
X446116Y15656D01*
G01X445982Y20709D02*
X446250Y20643D01*
G01X445446Y23596D02*
X445178Y23661D01*
G01Y23989D02*
X445446Y23924D01*
G01X445982Y25302D02*
X445714Y25367D01*
G01X445580Y18609D02*
X445178Y18674D01*
G01X444508Y22415D02*
X444575Y22611D01*
G01X444508Y17428D02*
X444575Y17624D01*
G01X446585Y19331D02*
X446518Y19134D01*
G01X446317Y24252D02*
X446384Y24514D01*
G01X444843Y17428D02*
X444776Y17165D01*
G01X446652Y24383D02*
X446585Y24120D01*
G01X444508Y14934D02*
X444575Y15197D01*
G01X446317Y19396D02*
X446384Y19659D01*
G01X446250Y14278D02*
X446317Y14541D01*
G01X446652D02*
X446585Y14278D01*
G01X447724Y13622D02*
X444508D01*
G01X446250Y13950D02*
X447724D01*
G01X445245D02*
X445915D01*
G01X444508D02*
X444910D01*
G01X437400Y14409D02*
X436139D01*
G01X437400Y15197D02*
X436139D01*
G01X445781Y15394D02*
X445379D01*
G01X451889D02*
X448739D01*
G01X445312Y15722D02*
X445848D01*
G01X449409Y15787D02*
X451889D01*
G01X446652Y16246D02*
X443503D01*
G01X437400Y16378D02*
X436139D01*
G01X445111Y16575D02*
X446652D01*
G01X443503D02*
X444843D01*
G01X437400Y17165D02*
X436139D01*
G01X446652Y17756D02*
X445312D01*
G01Y18084D02*
X446652D01*
G01X451889Y18150D02*
X449409D01*
G01X437400Y18346D02*
X436139D01*
G01X448739Y18543D02*
X451889D01*
G01X445580Y18937D02*
X445714D01*
G01X445245Y19002D02*
X445312D01*
G01X437400Y19134D02*
X436139D01*
G01X437400Y20315D02*
X436139D01*
G01X445312Y20380D02*
X445178D01*
G01X445312Y20709D02*
X445580D01*
G01X437400Y21102D02*
X436139D01*
G01X446652Y21233D02*
X444508D01*
G01X445111Y21561D02*
X446652D01*
G01X444508D02*
X444843D01*
G01X437400Y22283D02*
X436139D01*
G01X446652Y22743D02*
X445379D01*
G01X437400Y23071D02*
X436139D01*
G01X445379D02*
X446652D01*
G01X445714Y23596D02*
X445446D01*
G01X444575Y22611D02*
X444709Y22808D01*
G01X444977Y20249D02*
X444843Y20052D01*
G01X444575Y20118D02*
X444776Y20446D01*
G01X444575Y25170D02*
X444642Y25302D01*
G01X444910Y22546D02*
X444843Y22415D01*
G01X446585Y24120D02*
X446518Y23989D01*
G01X444910Y17559D02*
X444843Y17428D01*
G01X446250Y19265D02*
X446317Y19396D01*
G01X444977Y15197D02*
X444843Y14934D01*
G01X446585Y14278D02*
X446518Y14147D01*
G01X445446Y23924D02*
X445714D01*
G01X437400Y24252D02*
X436139D01*
G01X437400Y25039D02*
X436139D01*
G01X445714Y25367D02*
X445446D01*
G01Y25695D02*
X445714D01*
G01X437400Y26220D02*
X436139D01*
G01X446652D02*
X443503D01*
G01Y26548D02*
X446652D01*
G01X437400Y27008D02*
X436139D01*
G01X452085Y27677D02*
X443227D01*
G01X437400Y28189D02*
X436139D01*
G01X437400Y28976D02*
X436139D01*
G01X445982Y18674D02*
X445580Y18609D01*
G01X444977Y18018D02*
X445312Y18084D01*
G01X444575Y17624D02*
X444709Y17821D01*
G01X446518Y19134D02*
X446384Y18937D01*
G01X444575Y15197D02*
X444709Y15394D01*
G01X446116Y14081D02*
X446250Y14278D01*
G01X445379Y22743D02*
X445044Y22677D01*
G01Y23005D02*
X445379Y23071D01*
G01X445044Y15656D02*
X445312Y15722D01*
G01Y17756D02*
X445044Y17690D01*
G01Y20643D02*
X445312Y20709D01*
G01X445714Y23924D02*
X445982Y23989D01*
G01X445446Y25367D02*
X445178Y25302D01*
G01Y25630D02*
X445446Y25695D01*
G01X446183Y23727D02*
X445714Y23596D01*
G01X444642Y25302D02*
X444776Y25433D01*
G01X444977Y25170D02*
X444843Y25039D01*
G01X444709Y22808D02*
X444843Y22939D01*
G01X446183Y24120D02*
X446317Y24252D01*
G01X445044Y22677D02*
X444910Y22546D01*
G01X446518Y23989D02*
X446384Y23858D01*
G01X444709Y17821D02*
X444843Y17953D01*
G01X446049Y19068D02*
X446250Y19265D01*
G01X445044Y17690D02*
X444910Y17559D01*
G01X446384Y18937D02*
X446250Y18806D01*
G01X444709Y15394D02*
X444910Y15591D01*
G01X446518Y14147D02*
X446384Y14016D01*
G01X444776Y25433D02*
X444977Y25564D01*
G01X445178Y25302D02*
X444977Y25170D01*
G01X445982Y23989D02*
X446183Y24120D01*
G01X446384Y23858D02*
X446183Y23727D01*
G01X445178Y20380D02*
X444977Y20249D01*
G01X445178Y15328D02*
X444977Y15197D01*
G01X445915Y13950D02*
X446116Y14081D01*
G01X444776Y20446D02*
X445044Y20643D01*
G01X445915Y19002D02*
X446049Y19068D01*
G01X446250Y18806D02*
X445982Y18674D01*
G01X444843Y17953D02*
X444977Y18018D01*
G01X444910Y15591D02*
X445044Y15656D01*
G01X446384Y14016D02*
X446250Y13950D01*
G01X444977Y25564D02*
X445178Y25630D01*
G01X444843Y22939D02*
X445044Y23005D01*
G01X445714Y18937D02*
X445915Y19002D01*
G01X445379Y15394D02*
X445178Y15328D01*
G01X448739Y15984D02*
X451554Y16969D01*
G01X451889Y16706D02*
X449409Y15787D01*
G01X436139Y36850D02*
G03X435942Y36654I0J-197D01*
G01Y36260D02*
G03X436139Y36063I197J0D01*
G01Y34882D02*
G03X435942Y34685I0J-197D01*
G01Y34291D02*
G03X436139Y34095I197J1D01*
G01Y32913D02*
G03X435942Y32717I0J-197D01*
G01Y32323D02*
G03X436139Y32126I197J0D01*
G01Y30945D02*
G03X435942Y30748I0J-197D01*
G01Y30354D02*
G03X436139Y30158I197J1D01*
G01X435942Y40197D02*
G03X436139Y40000I197J0D01*
G01Y38819D02*
G03X435942Y38622I0J-197D01*
G01Y38228D02*
G03X436139Y38032I197J1D01*
G01X435942Y46102D02*
G03X436139Y45906I197J1D01*
G01Y44724D02*
G03X435942Y44528I0J-197D01*
G01Y44134D02*
G03X436139Y43937I197J0D01*
G01Y42756D02*
G03X435942Y42559I0J-197D01*
G01Y42165D02*
G03X436139Y41969I197J1D01*
G01Y40787D02*
G03X435942Y40591I0J-197D01*
G01Y46102D02*
Y46496D01*
G01Y44134D02*
Y44528D01*
G01Y42165D02*
Y42559D01*
G01Y40197D02*
Y40591D01*
G01Y36260D02*
Y36654D01*
G01Y38228D02*
Y38622D01*
G01Y34291D02*
Y34685D01*
G01Y32323D02*
Y32717D01*
G01Y30354D02*
Y30748D01*
G01X437400Y30158D02*
X436139D01*
G01X437400Y30945D02*
X436139D01*
G01X437400Y32126D02*
X436139D01*
G01X437400Y32913D02*
X436139D01*
G01X437400Y34095D02*
X436139D01*
G01X437400Y34882D02*
X436139D01*
G01X437400Y36063D02*
X436139D01*
G01X437400Y36850D02*
X436139D01*
G01X437400Y38032D02*
X436139D01*
G01X437400Y38819D02*
X436139D01*
G01X437400Y40000D02*
X436139D01*
G01X437400Y40787D02*
X436139D01*
G01X437400Y41969D02*
X436139D01*
G01X437400Y42756D02*
X436139D01*
G01X437400Y43937D02*
X436139D01*
G01X437400Y44724D02*
X436139D01*
G01X437400Y45906D02*
X436139D01*
G01Y62441D02*
G03X435942Y62244I0J-197D01*
G01Y61850D02*
G03X436139Y61654I197J1D01*
G01Y60472D02*
G03X435942Y60276I0J-197D01*
G01Y59882D02*
G03X436139Y59685I197J0D01*
G01Y58504D02*
G03X435942Y58307I0J-197D01*
G01Y57913D02*
G03X436139Y57717I197J1D01*
G01Y56535D02*
G03X435942Y56339I0J-197D01*
G01Y55945D02*
G03X436139Y55748I197J0D01*
G01Y54567D02*
G03X435942Y54370I0J-197D01*
G01Y53976D02*
G03X436139Y53780I197J1D01*
G01Y52598D02*
G03X435942Y52402I0J-197D01*
G01Y52008D02*
G03X436139Y51811I197J0D01*
G01Y50630D02*
G03X435942Y50433I0J-197D01*
G01Y50039D02*
G03X436139Y49843I197J1D01*
G01Y48661D02*
G03X435942Y48465I0J-197D01*
G01Y48071D02*
G03X436139Y47874I197J0D01*
G01Y46693D02*
G03X435942Y46496I0J-197D01*
G01Y61850D02*
Y62244D01*
G01Y59882D02*
Y60276D01*
G01Y57913D02*
Y58307D01*
G01Y55945D02*
Y56339D01*
G01Y53976D02*
Y54370D01*
G01Y52008D02*
Y52402D01*
G01Y50039D02*
Y50433D01*
G01Y48071D02*
Y48465D01*
G01X437400Y46693D02*
X436139D01*
G01X437400Y47874D02*
X436139D01*
G01X437400Y48661D02*
X436139D01*
G01X437400Y49843D02*
X436139D01*
G01X437400Y50630D02*
X436139D01*
G01X437400Y51811D02*
X436139D01*
G01X437400Y52598D02*
X436139D01*
G01X437400Y53780D02*
X436139D01*
G01X437400Y54567D02*
X436139D01*
G01X437400Y55748D02*
X436139D01*
G01X437400Y56535D02*
X436139D01*
G01X437400Y57717D02*
X436139D01*
G01X437400Y58504D02*
X436139D01*
G01X437400Y59685D02*
X436139D01*
G01X437400Y60472D02*
X436139D01*
G01X437400Y61654D02*
X436139D01*
G01X437400Y62441D02*
X436139D01*
G01Y78189D02*
G03X435942Y77992I0J-197D01*
G01Y77598D02*
G03X436139Y77402I197J1D01*
G01Y76220D02*
G03X435942Y76024I0J-197D01*
G01Y75630D02*
G03X436139Y75433I197J0D01*
G01Y74252D02*
G03X435942Y74055I0J-197D01*
G01Y73661D02*
G03X436139Y73465I197J1D01*
G01Y64409D02*
G03X435942Y64213I0J-197D01*
G01Y63819D02*
G03X436139Y63622I197J0D01*
G01X435942Y77598D02*
Y77992D01*
G01Y75630D02*
Y76024D01*
G01Y73661D02*
Y74055D01*
G01Y63819D02*
Y64213D01*
G01X437400Y63622D02*
X436139D01*
G01X437400Y64409D02*
X436139D01*
G01X437400Y73465D02*
X436139D01*
G01X437400Y74252D02*
X436139D01*
G01X437400Y75433D02*
X436139D01*
G01X437400Y76220D02*
X436139D01*
G01X437400Y77402D02*
X436139D01*
G01X437400Y78189D02*
X436139D01*
G01Y82126D02*
G03X435942Y81929I0J-197D01*
G01Y81535D02*
G03X436139Y81339I197J1D01*
G01Y80158D02*
G03X435942Y79961I0J-197D01*
G01Y79567D02*
G03X436139Y79370I197J0D01*
G01X435942Y81535D02*
Y81929D01*
G01Y79567D02*
Y79961D01*
G01X437400Y79370D02*
X436139D01*
G01X437400Y80158D02*
X436139D01*
G01X437400Y81339D02*
X436139D01*
G01X437400Y82126D02*
X436139D01*
G01X435942Y123268D02*
G03X436139Y123071I197J0D01*
G01Y121890D02*
G03X435942Y121693I0J-197D01*
G01Y121299D02*
G03X436139Y121102I197J0D01*
G01Y119921D02*
G03X435942Y119724I0J-197D01*
G01Y119331D02*
G03X436139Y119134I197J0D01*
G01Y117953D02*
G03X435942Y117756I0J-197D01*
G01Y117362D02*
G03X436139Y117165I197J0D01*
G01Y127795D02*
G03X435942Y127598I0J-197D01*
G01Y127205D02*
G03X436139Y127008I197J0D01*
G01Y125827D02*
G03X435942Y125630I0J-197D01*
G01Y125236D02*
G03X436139Y125039I197J0D01*
G01Y123858D02*
G03X435942Y123661I0J-197D01*
G01X442440Y115906D02*
G03X443227Y115118I787J-1D01*
G01X452085D02*
G03X452873Y115906I1J787D01*
G01X444709Y126483D02*
X444843Y126614D01*
G01X446049Y127730D02*
X446250Y127926D01*
G01X445044Y126352D02*
X444910Y126220D01*
G01X446384Y127598D02*
X446250Y127467D01*
G01X444709Y124055D02*
X444910Y124252D01*
G01X444575Y121496D02*
X444709Y121627D01*
G01X444910Y121365D02*
X444843Y121299D01*
G01X446518Y122808D02*
X446384Y122677D01*
G01X444575Y120446D02*
X444776Y120643D01*
G01X444910Y120315D02*
X444843Y120249D01*
G01X444977Y128911D02*
X444843Y128714D01*
G01X444575Y126286D02*
X444709Y126483D01*
G01X446518Y127795D02*
X446384Y127598D01*
G01X444575Y123858D02*
X444709Y124055D01*
G01X446116Y122743D02*
X446250Y122939D01*
G01X444910Y126220D02*
X444843Y126089D01*
G01X446250Y127926D02*
X446317Y128058D01*
G01X444977Y123858D02*
X444843Y123596D01*
G01Y121299D02*
X444776Y121168D01*
G01X444843Y120249D02*
X444776Y120118D01*
G01X446585Y122939D02*
X446518Y122808D01*
G01X444508Y126089D02*
X444575Y126286D01*
G01X446585Y127992D02*
X446518Y127795D01*
G01X444508Y121299D02*
X444575Y121496D01*
G01X444508Y120249D02*
X444575Y120446D01*
G01X444843Y126089D02*
X444776Y125827D01*
G01X444508Y123596D02*
X444575Y123858D01*
G01X446317Y128058D02*
X446384Y128320D01*
G01X446250Y122939D02*
X446317Y123202D01*
G01X446652D02*
X446585Y122939D01*
G01X444508Y128386D02*
X444575Y128780D01*
G01X444843Y128714D02*
X444776Y128320D01*
G01X446652Y128386D02*
X446585Y127992D01*
G01X435942Y127205D02*
Y127598D01*
G01Y125236D02*
Y125630D01*
G01Y123268D02*
Y123661D01*
G01Y121299D02*
Y121693D01*
G01Y119331D02*
Y119724D01*
G01Y117362D02*
Y117756D01*
G01X437400Y113819D02*
Y194134D01*
G01X439763Y113819D02*
Y194134D01*
G01X442440Y135551D02*
Y115906D01*
G01X443503Y124908D02*
Y125236D01*
G01Y117231D02*
Y117756D01*
G01X444508Y125827D02*
Y126089D01*
G01Y123202D02*
Y123596D01*
G01Y122283D02*
Y122611D01*
G01Y121037D02*
Y121299D01*
G01Y119987D02*
Y120249D01*
G01Y119331D02*
Y119659D01*
G01X446384Y128320D02*
X446317Y128780D01*
G01X446585Y128845D02*
X446652Y128386D01*
G01X444575Y127992D02*
X444508Y128386D01*
G01X444575Y122939D02*
X444508Y123202D01*
G01X444843D02*
X444910Y122939D01*
G01X444575Y125564D02*
X444508Y125827D01*
G01X444776D02*
X444843Y125564D01*
G01X444776Y128320D02*
X444843Y128058D01*
G01X446317Y123465D02*
X446250Y123727D01*
G01X445915Y127664D02*
X446049Y127730D01*
G01X446250Y127467D02*
X445982Y127336D01*
G01X444843Y126614D02*
X444977Y126680D01*
G01X444910Y124252D02*
X445044Y124317D01*
G01X445178Y123989D02*
X444977Y123858D01*
G01X445915Y122611D02*
X446116Y122743D01*
G01X444776Y120118D02*
Y119987D01*
G01Y121168D02*
Y120971D01*
G01X444843Y123596D02*
Y123202D01*
G01X445312Y127664D02*
Y129042D01*
G01X445580Y129370D02*
Y127598D01*
G01Y116903D02*
Y118084D01*
G01X445848Y118150D02*
Y116837D01*
G01X446317Y123202D02*
Y123465D01*
G01X446652Y116575D02*
Y116181D01*
G01Y120709D02*
Y120380D01*
G01Y119659D02*
Y119331D01*
G01Y118806D02*
Y118412D01*
G01Y121758D02*
Y121430D01*
G01Y125236D02*
Y124908D01*
G01Y123596D02*
Y123202D01*
G01Y126745D02*
Y126417D01*
G01X447724Y122611D02*
Y122283D01*
G01X448739Y126614D02*
Y127205D01*
G01Y124055D02*
Y124646D01*
G01X451889Y124449D02*
Y124055D01*
G01Y127205D02*
Y126811D01*
G01Y125892D02*
Y125367D01*
G01X446585Y123858D02*
X446652Y123596D01*
G01X444575Y119790D02*
X444508Y119987D01*
G01X444776D02*
X444843Y119790D01*
G01X444575Y120840D02*
X444508Y121037D01*
G01X444642Y127795D02*
X444575Y127992D01*
G01X444776Y120971D02*
X444843Y120840D01*
G01X444642Y122808D02*
X444575Y122939D01*
G01X445714Y127598D02*
X445915Y127664D01*
G01X445379Y124055D02*
X445178Y123989D01*
G01X445580Y118084D02*
X443771Y117493D01*
G01X446652Y118412D02*
X445848Y118150D01*
G01X443503Y117756D02*
X446652Y118806D01*
G01X448739Y124646D02*
X451554Y125630D01*
G01X451889Y125367D02*
X449409Y124449D01*
G01X444709Y121627D02*
X445044Y121758D01*
G01X446384Y122677D02*
X446250Y122611D01*
G01X445044Y121430D02*
X444910Y121365D01*
G01X445044Y120380D02*
X444910Y120315D01*
G01X444843Y128058D02*
X444910Y127926D01*
G01Y122939D02*
X445044Y122743D01*
G01X444709Y125367D02*
X444575Y125564D01*
G01X444843D02*
X444977Y125367D01*
G01X446250Y123727D02*
X446116Y123924D01*
G01X446451Y124055D02*
X446585Y123858D01*
G01X444776Y127598D02*
X444642Y127795D01*
G01X444709Y119659D02*
X444575Y119790D01*
G01X444843D02*
X444977Y119659D01*
G01X444776Y120643D02*
X444575Y120840D01*
G01X444843D02*
X444910Y120774D01*
G01X444776Y122677D02*
X444642Y122808D01*
G01X444843Y125236D02*
X444709Y125367D01*
G01X444977D02*
X445111Y125236D01*
G01X444910Y127467D02*
X444776Y127598D01*
G01X444910Y127926D02*
X445111Y127730D01*
G01X446116Y124317D02*
X446451Y124055D01*
G01X445044Y122743D02*
X445245Y122611D01*
G01X444910Y120774D02*
X445044Y120709D01*
G01X444910Y122611D02*
X444776Y122677D01*
G01X446116Y123924D02*
X445982Y123989D01*
G01X445178Y127336D02*
X444910Y127467D01*
G01X445111Y127730D02*
X445245Y127664D01*
G01X449409Y126811D02*
X451889Y125892D01*
G01X446652Y116181D02*
X443503Y117231D01*
G01X443771Y117493D02*
X445580Y116903D01*
G01X445848Y116837D02*
X446652Y116575D01*
G01X445982Y123989D02*
X445781Y124055D01*
G01X451554Y125630D02*
X448739Y126614D01*
G01X445848Y124383D02*
X446116Y124317D01*
G01X445580Y127270D02*
X445178Y127336D01*
G01X443227Y115118D02*
X452085D01*
G01X437400Y117165D02*
X436139D01*
G01X437400Y117953D02*
X436139D01*
G01X437400Y119134D02*
X436139D01*
G01X446652Y119331D02*
X444508D01*
G01X444977Y119659D02*
X446652D01*
G01X444508D02*
X444709D01*
G01X437400Y119921D02*
X436139D01*
G01X446652Y120380D02*
X445044D01*
G01Y120709D02*
X446652D01*
G01X437400Y121102D02*
X436139D01*
G01X446652Y121430D02*
X445044D01*
G01Y121758D02*
X446652D01*
G01X437400Y121890D02*
X436139D01*
G01X447724Y122283D02*
X444508D01*
G01X446250Y122611D02*
X447724D01*
G01X445245D02*
X445915D01*
G01X444508D02*
X444910D01*
G01X437400Y123071D02*
X436139D01*
G01X437400Y123858D02*
X436139D01*
G01X445781Y124055D02*
X445379D01*
G01X451889D02*
X448739D01*
G01X445312Y124383D02*
X445848D01*
G01X449409Y124449D02*
X451889D01*
G01X446652Y124908D02*
X443503D01*
G01X437400Y125039D02*
X436139D01*
G01X445111Y125236D02*
X446652D01*
G01X443503D02*
X444843D01*
G01X437400Y125827D02*
X436139D01*
G01X446652Y126417D02*
X445312D01*
G01Y126745D02*
X446652D01*
G01X451889Y126811D02*
X449409D01*
G01X437400Y127008D02*
X436139D01*
G01X448739Y127205D02*
X451889D01*
G01X445580Y127598D02*
X445714D01*
G01X445245Y127664D02*
X445312D01*
G01X437400Y127795D02*
X436139D01*
G01X445982Y127336D02*
X445580Y127270D01*
G01X444977Y126680D02*
X445312Y126745D01*
G01X445044Y124317D02*
X445312Y124383D01*
G01Y126417D02*
X445044Y126352D01*
G01X435942Y144921D02*
G03X436139Y144724I197J0D01*
G01Y143543D02*
G03X435942Y143346I0J-197D01*
G01Y142953D02*
G03X436139Y142756I197J0D01*
G01Y141575D02*
G03X435942Y141378I0J-197D01*
G01Y140984D02*
G03X436139Y140787I197J0D01*
G01Y139606D02*
G03X435942Y139409I0J-197D01*
G01Y139016D02*
G03X436139Y138819I197J0D01*
G01Y137638D02*
G03X435942Y137441I0J-197D01*
G01Y137047D02*
G03X436139Y136850I197J0D01*
G01Y135669D02*
G03X435942Y135472I0J-197D01*
G01Y135079D02*
G03X436139Y134882I197J0D01*
G01Y133701D02*
G03X435942Y133504I0J-197D01*
G01Y133110D02*
G03X436139Y132913I197J0D01*
G01Y131732D02*
G03X435942Y131535I0J-197D01*
G01Y131142D02*
G03X436139Y130945I197J0D01*
G01Y129764D02*
G03X435942Y129567I0J-197D01*
G01Y129173D02*
G03X436139Y128976I197J0D01*
G01X443227Y136339D02*
G03X442440Y135551I1J-788D01*
G01X452873D02*
G03X452085Y136339I-788J0D01*
G01X444776Y134095D02*
X444977Y134226D01*
G01X445178Y133963D02*
X444977Y133832D01*
G01X444776Y129108D02*
X445044Y129304D01*
G01X444642Y133963D02*
X444776Y134095D01*
G01X444977Y133832D02*
X444843Y133701D01*
G01X444709Y131470D02*
X444843Y131601D01*
G01X446183Y132782D02*
X446317Y132913D01*
G01X445044Y131339D02*
X444910Y131207D01*
G01X446518Y132651D02*
X446384Y132520D01*
G01X444575Y131273D02*
X444709Y131470D01*
G01X444575Y128780D02*
X444776Y129108D01*
G01X444575Y133832D02*
X444642Y133963D01*
G01X444910Y131207D02*
X444843Y131076D01*
G01X446585Y132782D02*
X446518Y132651D01*
G01X444508Y131076D02*
X444575Y131273D01*
G01X444508Y133569D02*
X444575Y133832D01*
G01X444843Y133701D02*
X444776Y133438D01*
G01X444843Y131076D02*
X444776Y130813D01*
G01X446317Y132913D02*
X446384Y133176D01*
G01X446652Y133045D02*
X446585Y132782D01*
G01X435942Y144921D02*
Y145315D01*
G01Y142953D02*
Y143346D01*
G01Y140984D02*
Y141378D01*
G01Y139016D02*
Y139409D01*
G01Y137047D02*
Y137441D01*
G01Y135079D02*
Y135472D01*
G01Y133110D02*
Y133504D01*
G01Y131142D02*
Y131535D01*
G01Y129173D02*
Y129567D01*
G01X443503Y134882D02*
Y135210D01*
G01X444508Y133045D02*
Y133569D01*
G01Y130813D02*
Y131076D01*
G01Y129895D02*
Y130223D01*
G01X444575Y130551D02*
X444508Y130813D01*
G01X444776D02*
X444843Y130551D01*
G01X444977Y134226D02*
X445178Y134291D01*
G01X445982Y132651D02*
X446183Y132782D01*
G01X446384Y132520D02*
X446183Y132388D01*
G01X445178Y129042D02*
X444977Y128911D01*
G01X444776Y133438D02*
Y133176D01*
G01X445982Y129042D02*
Y129370D01*
G01X446384Y133176D02*
Y133438D01*
G01X446652Y131732D02*
Y131404D01*
G01Y130223D02*
Y129895D01*
G01Y133569D02*
Y133045D01*
G01Y135210D02*
Y134882D01*
G01X444575Y132782D02*
X444508Y133045D01*
G01X444776Y133176D02*
X444843Y132913D01*
G01X446384Y133438D02*
X446317Y133701D01*
G01X446585Y133832D02*
X446652Y133569D01*
G01X444843Y131601D02*
X445044Y131667D01*
G01X444642Y132651D02*
X444575Y132782D01*
G01X446451Y129108D02*
X446585Y128845D01*
G01X446518Y133963D02*
X446585Y133832D01*
G01X444709Y130354D02*
X444575Y130551D01*
G01X444843D02*
X444977Y130354D01*
G01X446317Y128780D02*
X446183Y128976D01*
G01X444843Y130223D02*
X444709Y130354D01*
G01X444977D02*
X445111Y130223D01*
G01X446250Y129304D02*
X446451Y129108D01*
G01X444776Y132520D02*
X444642Y132651D01*
G01X444843Y132913D02*
X444977Y132782D01*
G01X446317Y133701D02*
X446183Y133832D01*
G01X446384Y134095D02*
X446518Y133963D01*
G01X444977Y132388D02*
X444776Y132520D01*
G01X444977Y132782D02*
X445178Y132651D01*
G01X446183Y133832D02*
X445982Y133963D01*
G01X446183Y134226D02*
X446384Y134095D01*
G01X446183Y128976D02*
X445982Y129042D01*
G01X445178Y132323D02*
X444977Y132388D01*
G01X445714Y134357D02*
X446183Y134226D01*
G01X445982Y129370D02*
X446250Y129304D01*
G01X445446Y132257D02*
X445178Y132323D01*
G01Y132651D02*
X445446Y132585D01*
G01X445982Y133963D02*
X445714Y134029D01*
G01X437400Y128976D02*
X436139D01*
G01X445312Y129042D02*
X445178D01*
G01X445312Y129370D02*
X445580D01*
G01X437400Y129764D02*
X436139D01*
G01X446652Y129895D02*
X444508D01*
G01X445111Y130223D02*
X446652D01*
G01X444508D02*
X444843D01*
G01X437400Y130945D02*
X436139D01*
G01X446652Y131404D02*
X445379D01*
G01X437400Y131732D02*
X436139D01*
G01X445379D02*
X446652D01*
G01X445714Y132257D02*
X445446D01*
G01Y132585D02*
X445714D01*
G01X437400Y132913D02*
X436139D01*
G01X437400Y133701D02*
X436139D01*
G01X445714Y134029D02*
X445446D01*
G01Y134357D02*
X445714D01*
G01X437400Y134882D02*
X436139D01*
G01X446652D02*
X443503D01*
G01Y135210D02*
X446652D01*
G01X437400Y135669D02*
X436139D01*
G01X452085Y136339D02*
X443227D01*
G01X437400Y136850D02*
X436139D01*
G01X437400Y137638D02*
X436139D01*
G01X437400Y138819D02*
X436139D01*
G01X437400Y139606D02*
X436139D01*
G01X437400Y140787D02*
X436139D01*
G01X437400Y141575D02*
X436139D01*
G01X437400Y142756D02*
X436139D01*
G01X437400Y143543D02*
X436139D01*
G01X437400Y144724D02*
X436139D01*
G01X445379Y131404D02*
X445044Y131339D01*
G01Y131667D02*
X445379Y131732D01*
G01X445044Y129304D02*
X445312Y129370D01*
G01X445714Y132585D02*
X445982Y132651D01*
G01X445446Y134029D02*
X445178Y133963D01*
G01Y134291D02*
X445446Y134357D01*
G01X446183Y132388D02*
X445714Y132257D01*
G01X436139Y145512D02*
G03X435942Y145315I0J-197D01*
G01X436139Y161260D02*
G03X435942Y161063I0J-197D01*
G01Y160669D02*
G03X436139Y160472I197J0D01*
G01Y159291D02*
G03X435942Y159095I0J-197D01*
G01Y158701D02*
G03X436139Y158504I197J0D01*
G01Y157323D02*
G03X435942Y157126I0J-197D01*
G01Y156732D02*
G03X436139Y156535I197J0D01*
G01Y155354D02*
G03X435942Y155158I0J-197D01*
G01Y154764D02*
G03X436139Y154567I197J0D01*
G01Y153386D02*
G03X435942Y153189I0J-197D01*
G01Y152795D02*
G03X436139Y152598I197J0D01*
G01Y151417D02*
G03X435942Y151220I0J-197D01*
G01Y150827D02*
G03X436139Y150630I197J0D01*
G01Y149449D02*
G03X435942Y149252I0J-197D01*
G01Y148858D02*
G03X436139Y148661I197J0D01*
G01Y147480D02*
G03X435942Y147283I0J-197D01*
G01Y146890D02*
G03X436139Y146693I197J0D01*
G01X435942Y160669D02*
Y161063D01*
G01Y158701D02*
Y159095D01*
G01Y156732D02*
Y157126D01*
G01Y154764D02*
Y155158D01*
G01Y152795D02*
Y153189D01*
G01Y150827D02*
Y151220D01*
G01Y148858D02*
Y149252D01*
G01Y146890D02*
Y147283D01*
G01X437400Y145512D02*
X436139D01*
G01X437400Y146693D02*
X436139D01*
G01X437400Y147480D02*
X436139D01*
G01X437400Y148661D02*
X436139D01*
G01X437400Y149449D02*
X436139D01*
G01X437400Y150630D02*
X436139D01*
G01X437400Y151417D02*
X436139D01*
G01X437400Y152598D02*
X436139D01*
G01X437400Y153386D02*
X436139D01*
G01X437400Y154567D02*
X436139D01*
G01X437400Y155354D02*
X436139D01*
G01X437400Y156535D02*
X436139D01*
G01X437400Y157323D02*
X436139D01*
G01X437400Y158504D02*
X436139D01*
G01X437400Y159291D02*
X436139D01*
G01X437400Y160472D02*
X436139D01*
G01X437400Y161260D02*
X436139D01*
G01Y167165D02*
G03X435942Y166969I0J-197D01*
G01Y166575D02*
G03X436139Y166378I197J0D01*
G01Y165197D02*
G03X435942Y165000I0J-197D01*
G01Y164606D02*
G03X436139Y164409I197J0D01*
G01Y163228D02*
G03X435942Y163032I0J-197D01*
G01Y162638D02*
G03X436139Y162441I197J0D01*
G01Y173071D02*
G03X435942Y172874I0J-197D01*
G01Y172480D02*
G03X436139Y172283I197J0D01*
G01Y171102D02*
G03X435942Y170906I0J-197D01*
G01Y170512D02*
G03X436139Y170315I197J0D01*
G01Y169134D02*
G03X435942Y168937I0J-197D01*
G01Y168543D02*
G03X436139Y168346I197J0D01*
G01X435942Y172480D02*
Y172874D01*
G01Y170512D02*
Y170906D01*
G01Y168543D02*
Y168937D01*
G01Y166575D02*
Y166969D01*
G01Y164606D02*
Y165000D01*
G01Y162638D02*
Y163032D01*
G01X437400Y162441D02*
X436139D01*
G01X437400Y163228D02*
X436139D01*
G01X437400Y164409D02*
X436139D01*
G01X437400Y165197D02*
X436139D01*
G01X437400Y166378D02*
X436139D01*
G01X437400Y167165D02*
X436139D01*
G01X437400Y168346D02*
X436139D01*
G01X437400Y169134D02*
X436139D01*
G01X437400Y170315D02*
X436139D01*
G01X437400Y171102D02*
X436139D01*
G01X437400Y172283D02*
X436139D01*
G01X437400Y173071D02*
X436139D01*
G01Y190787D02*
G03X435942Y190591I0J-197D01*
G01Y190197D02*
G03X436139Y190000I197J0D01*
G01Y188819D02*
G03X435942Y188622I0J-197D01*
G01Y188228D02*
G03X436139Y188032I197J1D01*
G01Y186850D02*
G03X435942Y186654I0J-197D01*
G01Y186260D02*
G03X436139Y186063I197J0D01*
G01Y184882D02*
G03X435942Y184685I0J-197D01*
G01Y184291D02*
G03X436139Y184095I197J1D01*
G01Y182913D02*
G03X435942Y182717I0J-197D01*
G01Y182323D02*
G03X436139Y182126I197J0D01*
G01X435942Y190197D02*
Y190591D01*
G01Y188228D02*
Y188622D01*
G01Y186260D02*
Y186654D01*
G01Y184291D02*
Y184685D01*
G01Y182323D02*
Y182717D01*
G01X437400Y182126D02*
X436139D01*
G01X437400Y182913D02*
X436139D01*
G01X437400Y184095D02*
X436139D01*
G01X437400Y184882D02*
X436139D01*
G01X437400Y186063D02*
X436139D01*
G01X437400Y186850D02*
X436139D01*
G01X437400Y188032D02*
X436139D01*
G01X437400Y188819D02*
X436139D01*
G01X437400Y190000D02*
X436139D01*
G01X437400Y190787D02*
X436139D01*
G01X438653Y381710D02*
Y384510D01*
G01X437724Y619690D02*
Y602367D01*
G01X460244Y-113228D02*
G03Y-105354I0J3937D01*
G01X458070Y-62047D02*
Y-105354D01*
G01X467715Y11457D02*
G03X467912Y11654I0J197D01*
G01Y12047D02*
G03X467715Y12244I-197J0D01*
G01Y9488D02*
G03X467912Y9685I0J197D01*
G01Y10079D02*
G03X467715Y10276I-197J0D01*
G01X461022Y4469D02*
G03X459841Y5650I-1181J0D01*
G01X452873Y7244D02*
Y26890D01*
G01X455904Y-984D02*
Y2008D01*
G01X457085Y86161D02*
Y4469D01*
G01Y2008D02*
Y4469D01*
G01X458030Y10236D02*
Y9528D01*
G01Y12205D02*
Y11496D01*
G01X461022Y2008D02*
Y4469D01*
G01X506495Y-984D02*
X455904D01*
G01X461022Y4469D02*
X457085D01*
G01Y5650D02*
X459841D01*
G01X466534Y2008D02*
Y88622D01*
G01X467912Y11654D02*
Y12047D01*
G01Y9685D02*
Y10079D01*
G01X466534Y9488D02*
X467715D01*
G01X457085Y9528D02*
X458030D01*
G01Y10236D02*
X457085D01*
G01X467715Y10276D02*
X466534D01*
G01Y11457D02*
X467715D01*
G01X457085Y11496D02*
X458030D01*
G01Y12205D02*
X457085D01*
G01X467715Y12244D02*
X466534D01*
G01X467715Y29173D02*
G03X467912Y29370I0J197D01*
G01X467715Y27205D02*
G03X467912Y27402I0J197D01*
G01Y27795D02*
G03X467715Y27992I-197J0D01*
G01Y25236D02*
G03X467912Y25433I0J197D01*
G01Y25827D02*
G03X467715Y26024I-197J0D01*
G01Y23268D02*
G03X467912Y23465I0J197D01*
G01Y23858D02*
G03X467715Y24055I-197J0D01*
G01Y21299D02*
G03X467912Y21496I0J197D01*
G01Y21890D02*
G03X467715Y22087I-197J0D01*
G01Y19331D02*
G03X467912Y19528I0J197D01*
G01Y19921D02*
G03X467715Y20118I-197J0D01*
G01Y17362D02*
G03X467912Y17559I0J197D01*
G01Y17953D02*
G03X467715Y18150I-197J0D01*
G01Y15394D02*
G03X467912Y15591I0J197D01*
G01Y15984D02*
G03X467715Y16181I-197J0D01*
G01Y13425D02*
G03X467912Y13622I0J197D01*
G01Y14016D02*
G03X467715Y14213I-197J0D01*
G01X458030Y14173D02*
Y13465D01*
G01Y16142D02*
Y15433D01*
G01Y18110D02*
Y17402D01*
G01Y20079D02*
Y19370D01*
G01Y22047D02*
Y21339D01*
G01Y24016D02*
Y23307D01*
G01Y25984D02*
Y25276D01*
G01Y27953D02*
Y27244D01*
G01Y29921D02*
Y29213D01*
G01X467912Y29370D02*
Y29764D01*
G01Y27402D02*
Y27795D01*
G01Y25433D02*
Y25827D01*
G01Y23465D02*
Y23858D01*
G01Y21496D02*
Y21890D01*
G01Y19528D02*
Y19921D01*
G01Y17559D02*
Y17953D01*
G01Y15591D02*
Y15984D01*
G01Y13622D02*
Y14016D01*
G01X466534Y13425D02*
X467715D01*
G01X457085Y13465D02*
X458030D01*
G01Y14173D02*
X457085D01*
G01X467715Y14213D02*
X466534D01*
G01Y15394D02*
X467715D01*
G01X457085Y15433D02*
X458030D01*
G01Y16142D02*
X457085D01*
G01X467715Y16181D02*
X466534D01*
G01Y17362D02*
X467715D01*
G01X457085Y17402D02*
X458030D01*
G01Y18110D02*
X457085D01*
G01X467715Y18150D02*
X466534D01*
G01Y19331D02*
X467715D01*
G01X457085Y19370D02*
X458030D01*
G01Y20079D02*
X457085D01*
G01X467715Y20118D02*
X466534D01*
G01Y21299D02*
X467715D01*
G01X457085Y21339D02*
X458030D01*
G01Y22047D02*
X457085D01*
G01X467715Y22087D02*
X466534D01*
G01Y23268D02*
X467715D01*
G01X457085Y23307D02*
X458030D01*
G01Y24016D02*
X457085D01*
G01X467715Y24055D02*
X466534D01*
G01Y25236D02*
X467715D01*
G01X457085Y25276D02*
X458030D01*
G01Y25984D02*
X457085D01*
G01X467715Y26024D02*
X466534D01*
G01Y27205D02*
X467715D01*
G01X457085Y27244D02*
X458030D01*
G01Y27953D02*
X457085D01*
G01X467715Y27992D02*
X466534D01*
G01Y29173D02*
X467715D01*
G01X457085Y29213D02*
X458030D01*
G01X467715Y39016D02*
G03X467912Y39213I0J197D01*
G01X467715Y37047D02*
G03X467912Y37244I0J197D01*
G01Y37638D02*
G03X467715Y37835I-197J0D01*
G01Y35079D02*
G03X467912Y35276I0J197D01*
G01Y35669D02*
G03X467715Y35866I-197J0D01*
G01Y33110D02*
G03X467912Y33307I0J197D01*
G01Y33701D02*
G03X467715Y33898I-197J0D01*
G01Y31142D02*
G03X467912Y31339I0J197D01*
G01Y31732D02*
G03X467715Y31929I-197J0D01*
G01X467912Y29764D02*
G03X467715Y29961I-197J0D01*
G01Y44921D02*
G03X467912Y45118I0J197D01*
G01Y45512D02*
G03X467715Y45709I-197J0D01*
G01Y42953D02*
G03X467912Y43150I0J197D01*
G01Y43543D02*
G03X467715Y43740I-197J0D01*
G01Y40984D02*
G03X467912Y41181I0J197D01*
G01Y41575D02*
G03X467715Y41772I-197J0D01*
G01X467912Y39606D02*
G03X467715Y39803I-197J0D01*
G01X458030Y31890D02*
Y31181D01*
G01Y33858D02*
Y33150D01*
G01Y35827D02*
Y35118D01*
G01Y37795D02*
Y37087D01*
G01Y39764D02*
Y39055D01*
G01Y43701D02*
Y42992D01*
G01Y41732D02*
Y41024D01*
G01Y45669D02*
Y44961D01*
G01X467912Y45118D02*
Y45512D01*
G01Y43150D02*
Y43543D01*
G01Y41181D02*
Y41575D01*
G01Y39213D02*
Y39606D01*
G01Y37244D02*
Y37638D01*
G01Y35276D02*
Y35669D01*
G01Y33307D02*
Y33701D01*
G01Y31339D02*
Y31732D01*
G01X466613Y38966D02*
X466534Y38993D01*
G01X458030Y29921D02*
X457085D01*
G01X467715Y29961D02*
X466534D01*
G01Y31142D02*
X467715D01*
G01X457085Y31181D02*
X458030D01*
G01Y31890D02*
X457085D01*
G01X467715Y31929D02*
X466534D01*
G01Y33110D02*
X467715D01*
G01X457085Y33150D02*
X458030D01*
G01Y33858D02*
X457085D01*
G01X467715Y33898D02*
X466534D01*
G01Y35079D02*
X467715D01*
G01X457085Y35118D02*
X458030D01*
G01Y35827D02*
X457085D01*
G01X467715Y35866D02*
X466534D01*
G01Y37047D02*
X467715D01*
G01X457085Y37087D02*
X458030D01*
G01Y37795D02*
X457085D01*
G01X467715Y37835D02*
X466534D01*
G01X467597Y38966D02*
X466613D01*
G01X457085Y39055D02*
X458030D01*
G01Y39764D02*
X457085D01*
G01X467715Y39803D02*
X466534D01*
G01Y40984D02*
X467715D01*
G01X457085Y41024D02*
X458030D01*
G01Y41732D02*
X457085D01*
G01X467715Y41772D02*
X466534D01*
G01Y42953D02*
X467715D01*
G01X457085Y42992D02*
X458030D01*
G01Y43701D02*
X457085D01*
G01X467715Y43740D02*
X466534D01*
G01Y44921D02*
X467715D01*
G01X457085Y44961D02*
X458030D01*
G01Y45669D02*
X457085D01*
G01X467715Y45709D02*
X466534D01*
G01X467718Y39008D02*
X467597Y38966D01*
G01X467715Y62638D02*
G03X467912Y62835I0J197D01*
G01X467715Y60669D02*
G03X467912Y60866I0J197D01*
G01Y61260D02*
G03X467715Y61457I-197J0D01*
G01Y58701D02*
G03X467912Y58898I0J197D01*
G01Y59291D02*
G03X467715Y59488I-197J0D01*
G01Y56732D02*
G03X467912Y56929I0J197D01*
G01Y57323D02*
G03X467715Y57520I-197J0D01*
G01Y54764D02*
G03X467912Y54961I0J197D01*
G01Y55354D02*
G03X467715Y55551I-197J0D01*
G01Y52795D02*
G03X467912Y52992I0J197D01*
G01Y53386D02*
G03X467715Y53583I-197J0D01*
G01Y50827D02*
G03X467912Y51024I0J197D01*
G01Y51417D02*
G03X467715Y51614I-197J0D01*
G01Y48858D02*
G03X467912Y49055I0J197D01*
G01Y49449D02*
G03X467715Y49646I-197J0D01*
G01Y46890D02*
G03X467912Y47087I0J197D01*
G01Y47480D02*
G03X467715Y47677I-197J0D01*
G01X458030Y47638D02*
Y46929D01*
G01Y49606D02*
Y48898D01*
G01Y51575D02*
Y50866D01*
G01Y53543D02*
Y52835D01*
G01Y55512D02*
Y54803D01*
G01Y57480D02*
Y56772D01*
G01Y59449D02*
Y58740D01*
G01Y61417D02*
Y60709D01*
G01Y63386D02*
Y62677D01*
G01X467912Y60866D02*
Y61260D01*
G01Y58898D02*
Y59291D01*
G01Y56929D02*
Y57323D01*
G01Y54961D02*
Y55354D01*
G01Y52992D02*
Y53386D01*
G01Y51024D02*
Y51417D01*
G01Y49055D02*
Y49449D01*
G01Y47087D02*
Y47480D01*
G01X466534Y46890D02*
X467715D01*
G01X457085Y46929D02*
X458030D01*
G01Y47638D02*
X457085D01*
G01X467715Y47677D02*
X466534D01*
G01Y48858D02*
X467715D01*
G01X457085Y48898D02*
X458030D01*
G01Y49606D02*
X457085D01*
G01X467715Y49646D02*
X466534D01*
G01Y50827D02*
X467715D01*
G01X457085Y50866D02*
X458030D01*
G01Y51575D02*
X457085D01*
G01X467715Y51614D02*
X466534D01*
G01Y52795D02*
X467715D01*
G01X457085Y52835D02*
X458030D01*
G01Y53543D02*
X457085D01*
G01X467715Y53583D02*
X466534D01*
G01Y54764D02*
X467715D01*
G01X457085Y54803D02*
X458030D01*
G01Y55512D02*
X457085D01*
G01X467715Y55551D02*
X466534D01*
G01Y56732D02*
X467715D01*
G01X457085Y56772D02*
X458030D01*
G01Y57480D02*
X457085D01*
G01X467715Y57520D02*
X466534D01*
G01Y58701D02*
X467715D01*
G01X457085Y58740D02*
X458030D01*
G01Y59449D02*
X457085D01*
G01X467715Y59488D02*
X466534D01*
G01Y60669D02*
X467715D01*
G01X457085Y60709D02*
X458030D01*
G01Y61417D02*
X457085D01*
G01X467715Y61457D02*
X466534D01*
G01Y62638D02*
X467715D01*
G01X457085Y62677D02*
X458030D01*
G01X467715Y78386D02*
G03X467912Y78583I0J197D01*
G01Y78976D02*
G03X467715Y79173I-197J0D01*
G01Y76417D02*
G03X467912Y76614I0J197D01*
G01Y77008D02*
G03X467715Y77205I-197J0D01*
G01Y74449D02*
G03X467912Y74646I0J197D01*
G01Y75039D02*
G03X467715Y75236I-197J0D01*
G01Y64606D02*
G03X467912Y64803I0J197D01*
G01Y65197D02*
G03X467715Y65394I-197J0D01*
G01X467912Y63228D02*
G03X467715Y63425I-197J0D01*
G01X458857Y67264D02*
G03Y71595I0J2165D01*
G01X458030Y65354D02*
Y64646D01*
G01Y75197D02*
Y74488D01*
G01Y77165D02*
Y76457D01*
G01Y79134D02*
Y78425D01*
G01X467912Y78583D02*
Y78976D01*
G01Y76614D02*
Y77008D01*
G01Y74646D02*
Y75039D01*
G01Y64803D02*
Y65197D01*
G01Y62835D02*
Y63228D01*
G01X458030Y63386D02*
X457085D01*
G01X467715Y63425D02*
X466534D01*
G01Y64606D02*
X467715D01*
G01X457085Y64646D02*
X458030D01*
G01Y65354D02*
X457085D01*
G01X467715Y65394D02*
X466534D01*
G01X457085Y67264D02*
X458857D01*
G01Y71595D02*
X457085D01*
G01X466534Y74449D02*
X467715D01*
G01X457085Y74488D02*
X458030D01*
G01Y75197D02*
X457085D01*
G01X467715Y75236D02*
X466534D01*
G01Y76417D02*
X467715D01*
G01X457085Y76457D02*
X458030D01*
G01Y77165D02*
X457085D01*
G01X467715Y77205D02*
X466534D01*
G01Y78386D02*
X467715D01*
G01X457085Y78425D02*
X458030D01*
G01Y79134D02*
X457085D01*
G01X467715Y79173D02*
X466534D01*
G01X467715Y80354D02*
G03X467912Y80551I0J197D01*
G01Y80945D02*
G03X467715Y81142I-197J0D01*
G01X459841Y84980D02*
G03X461022Y86161I0J1181D01*
G01X455904Y88622D02*
Y91535D01*
G01X457085Y86161D02*
Y88622D01*
G01X458030Y81102D02*
Y80394D01*
G01X461022Y86161D02*
Y88622D01*
G01X467912Y80551D02*
Y80945D01*
G01X466534Y80354D02*
X467715D01*
G01X457085Y80394D02*
X458030D01*
G01Y81102D02*
X457085D01*
G01X467715Y81142D02*
X466534D01*
G01X457085Y84980D02*
X459841D01*
G01X457085Y86161D02*
X461022D01*
G01X506495Y91535D02*
X455904D01*
G01Y107677D02*
Y110669D01*
G01X457085D02*
Y113130D01*
G01X461022Y110669D02*
Y113130D01*
G01X466534Y110669D02*
Y197283D01*
G01X455904Y107677D02*
X506495D01*
G01X467715Y122087D02*
G03X467912Y122283I0J197D01*
G01Y122677D02*
G03X467715Y122874I-197J0D01*
G01Y120118D02*
G03X467912Y120315I0J197D01*
G01Y120709D02*
G03X467715Y120906I-197J0D01*
G01Y118150D02*
G03X467912Y118346I0J197D01*
G01Y118740D02*
G03X467715Y118937I-197J0D01*
G01X461022Y113130D02*
G03X459841Y114311I-1181J0D01*
G01X467715Y127992D02*
G03X467912Y128189I0J197D01*
G01Y128583D02*
G03X467715Y128780I-197J0D01*
G01Y126024D02*
G03X467912Y126220I0J197D01*
G01Y126614D02*
G03X467715Y126811I-197J0D01*
G01Y124055D02*
G03X467912Y124252I0J197D01*
G01Y124646D02*
G03X467715Y124843I-197J0D01*
G01X452873Y115906D02*
Y135551D01*
G01X457085Y194823D02*
Y113130D01*
G01X458030Y120866D02*
Y120158D01*
G01Y118898D02*
Y118189D01*
G01Y122835D02*
Y122126D01*
G01Y124803D02*
Y124095D01*
G01Y126772D02*
Y126063D01*
G01Y128740D02*
Y128032D01*
G01X467912Y128189D02*
Y128583D01*
G01Y126220D02*
Y126614D01*
G01Y124252D02*
Y124646D01*
G01Y122283D02*
Y122677D01*
G01Y120315D02*
Y120709D01*
G01Y118346D02*
Y118740D01*
G01X461022Y113130D02*
X457085D01*
G01Y114311D02*
X459841D01*
G01X466534Y118150D02*
X467715D01*
G01X457085Y118189D02*
X458030D01*
G01Y118898D02*
X457085D01*
G01X467715Y118937D02*
X466534D01*
G01Y120118D02*
X467715D01*
G01X457085Y120158D02*
X458030D01*
G01Y120866D02*
X457085D01*
G01X467715Y120906D02*
X466534D01*
G01Y122087D02*
X467715D01*
G01X457085Y122126D02*
X458030D01*
G01Y122835D02*
X457085D01*
G01X467715Y122874D02*
X466534D01*
G01Y124055D02*
X467715D01*
G01X457085Y124095D02*
X458030D01*
G01Y124803D02*
X457085D01*
G01X467715Y124843D02*
X466534D01*
G01Y126024D02*
X467715D01*
G01X457085Y126063D02*
X458030D01*
G01Y126772D02*
X457085D01*
G01X467715Y126811D02*
X466534D01*
G01Y127992D02*
X467715D01*
G01X457085Y128032D02*
X458030D01*
G01Y128740D02*
X457085D01*
G01X467715Y143740D02*
G03X467912Y143937I0J197D01*
G01Y144331D02*
G03X467715Y144528I-197J0D01*
G01Y141772D02*
G03X467912Y141969I0J197D01*
G01Y142362D02*
G03X467715Y142559I-197J0D01*
G01Y139803D02*
G03X467912Y140000I0J197D01*
G01Y140394D02*
G03X467715Y140591I-197J0D01*
G01Y137835D02*
G03X467912Y138032I0J197D01*
G01Y138425D02*
G03X467715Y138622I-197J0D01*
G01Y135866D02*
G03X467912Y136063I0J197D01*
G01Y136457D02*
G03X467715Y136654I-197J0D01*
G01Y133898D02*
G03X467912Y134095I0J197D01*
G01Y134488D02*
G03X467715Y134685I-197J0D01*
G01Y131929D02*
G03X467912Y132126I0J197D01*
G01Y132520D02*
G03X467715Y132717I-197J0D01*
G01Y129961D02*
G03X467912Y130158I0J197D01*
G01Y130551D02*
G03X467715Y130748I-197J0D01*
G01X458030Y130709D02*
Y130000D01*
G01Y132677D02*
Y131969D01*
G01Y134646D02*
Y133937D01*
G01Y136614D02*
Y135906D01*
G01Y138583D02*
Y137874D01*
G01Y140551D02*
Y139843D01*
G01Y142520D02*
Y141811D01*
G01Y144488D02*
Y143780D01*
G01X467912Y143937D02*
Y144331D01*
G01Y141969D02*
Y142362D01*
G01Y140000D02*
Y140394D01*
G01Y138032D02*
Y138425D01*
G01Y136063D02*
Y136457D01*
G01Y134095D02*
Y134488D01*
G01Y132126D02*
Y132520D01*
G01Y130158D02*
Y130551D01*
G01X467715Y128780D02*
X466534D01*
G01Y129961D02*
X467715D01*
G01X457085Y130000D02*
X458030D01*
G01Y130709D02*
X457085D01*
G01X467715Y130748D02*
X466534D01*
G01Y131929D02*
X467715D01*
G01X457085Y131969D02*
X458030D01*
G01Y132677D02*
X457085D01*
G01X467715Y132717D02*
X466534D01*
G01Y133898D02*
X467715D01*
G01X457085Y133937D02*
X458030D01*
G01Y134646D02*
X457085D01*
G01X467715Y134685D02*
X466534D01*
G01Y135866D02*
X467715D01*
G01X457085Y135906D02*
X458030D01*
G01Y136614D02*
X457085D01*
G01X467715Y136654D02*
X466534D01*
G01Y137835D02*
X467715D01*
G01X457085Y137874D02*
X458030D01*
G01Y138583D02*
X457085D01*
G01X467715Y138622D02*
X466534D01*
G01Y139803D02*
X467715D01*
G01X457085Y139843D02*
X458030D01*
G01Y140551D02*
X457085D01*
G01X467715Y140591D02*
X466534D01*
G01Y141772D02*
X467715D01*
G01X457085Y141811D02*
X458030D01*
G01Y142520D02*
X457085D01*
G01X467715Y142559D02*
X466534D01*
G01Y143740D02*
X467715D01*
G01X457085Y143780D02*
X458030D01*
G01Y144488D02*
X457085D01*
G01X467715Y144528D02*
X466534D01*
G01X467715Y161457D02*
G03X467912Y161654I0J197D01*
G01X467715Y159488D02*
G03X467912Y159685I0J197D01*
G01Y160079D02*
G03X467715Y160276I-197J0D01*
G01Y157520D02*
G03X467912Y157717I0J197D01*
G01Y158110D02*
G03X467715Y158307I-197J0D01*
G01Y155551D02*
G03X467912Y155748I0J197D01*
G01Y156142D02*
G03X467715Y156339I-197J0D01*
G01Y153583D02*
G03X467912Y153780I0J197D01*
G01Y154173D02*
G03X467715Y154370I-197J0D01*
G01Y151614D02*
G03X467912Y151811I0J197D01*
G01Y152205D02*
G03X467715Y152402I-197J0D01*
G01Y149646D02*
G03X467912Y149843I0J197D01*
G01Y150236D02*
G03X467715Y150433I-197J0D01*
G01Y147677D02*
G03X467912Y147874I0J197D01*
G01Y148268D02*
G03X467715Y148465I-197J0D01*
G01Y145709D02*
G03X467912Y145906I0J197D01*
G01Y146299D02*
G03X467715Y146496I-197J0D01*
G01X458030Y146457D02*
Y145748D01*
G01Y148425D02*
Y147717D01*
G01Y150394D02*
Y149685D01*
G01Y152362D02*
Y151654D01*
G01Y154331D02*
Y153622D01*
G01Y156299D02*
Y155591D01*
G01Y158268D02*
Y157559D01*
G01Y160236D02*
Y159528D01*
G01Y162205D02*
Y161496D01*
G01X467912Y161654D02*
Y162047D01*
G01Y159685D02*
Y160079D01*
G01Y157717D02*
Y158110D01*
G01Y155748D02*
Y156142D01*
G01Y153780D02*
Y154173D01*
G01Y151811D02*
Y152205D01*
G01Y149843D02*
Y150236D01*
G01Y147874D02*
Y148268D01*
G01Y145906D02*
Y146299D01*
G01X466534Y145709D02*
X467715D01*
G01X457085Y145748D02*
X458030D01*
G01Y146457D02*
X457085D01*
G01X467715Y146496D02*
X466534D01*
G01Y147677D02*
X467715D01*
G01X457085Y147717D02*
X458030D01*
G01Y148425D02*
X457085D01*
G01X467715Y148465D02*
X466534D01*
G01Y149646D02*
X467715D01*
G01X457085Y149685D02*
X458030D01*
G01Y150394D02*
X457085D01*
G01X467715Y150433D02*
X466534D01*
G01Y151614D02*
X467715D01*
G01X457085Y151654D02*
X458030D01*
G01Y152362D02*
X457085D01*
G01X467715Y152402D02*
X466534D01*
G01Y153583D02*
X467715D01*
G01X457085Y153622D02*
X458030D01*
G01Y154331D02*
X457085D01*
G01X467715Y154370D02*
X466534D01*
G01Y155551D02*
X467715D01*
G01X457085Y155591D02*
X458030D01*
G01Y156299D02*
X457085D01*
G01X467715Y156339D02*
X466534D01*
G01Y157520D02*
X467715D01*
G01X457085Y157559D02*
X458030D01*
G01Y158268D02*
X457085D01*
G01X467715Y158307D02*
X466534D01*
G01Y159488D02*
X467715D01*
G01X457085Y159528D02*
X458030D01*
G01Y160236D02*
X457085D01*
G01X467715Y160276D02*
X466534D01*
G01Y161457D02*
X467715D01*
G01X457085Y161496D02*
X458030D01*
G01X467715Y167362D02*
G03X467912Y167559I0J197D01*
G01X467715Y165394D02*
G03X467912Y165591I0J197D01*
G01Y165984D02*
G03X467715Y166181I-197J0D01*
G01Y163425D02*
G03X467912Y163622I0J197D01*
G01Y164016D02*
G03X467715Y164213I-197J0D01*
G01X467912Y162047D02*
G03X467715Y162244I-197J0D01*
G01Y173268D02*
G03X467912Y173465I0J197D01*
G01Y173858D02*
G03X467715Y174055I-197J0D01*
G01Y171299D02*
G03X467912Y171496I0J197D01*
G01Y171890D02*
G03X467715Y172087I-197J0D01*
G01Y169331D02*
G03X467912Y169528I0J197D01*
G01Y169921D02*
G03X467715Y170118I-197J0D01*
G01X467912Y167953D02*
G03X467715Y168150I-197J0D01*
G01X458857Y175925D02*
G03Y180256I0J2165D01*
G01X458030Y164173D02*
Y163465D01*
G01Y166142D02*
Y165433D01*
G01Y170079D02*
Y169370D01*
G01Y168110D02*
Y167402D01*
G01Y172047D02*
Y171339D01*
G01Y174016D02*
Y173307D01*
G01X467912Y173465D02*
Y173858D01*
G01Y171496D02*
Y171890D01*
G01Y169528D02*
Y169921D01*
G01Y167559D02*
Y167953D01*
G01Y165591D02*
Y165984D01*
G01Y163622D02*
Y164016D01*
G01X458030Y162205D02*
X457085D01*
G01X467715Y162244D02*
X466534D01*
G01Y163425D02*
X467715D01*
G01X457085Y163465D02*
X458030D01*
G01Y164173D02*
X457085D01*
G01X467715Y164213D02*
X466534D01*
G01Y165394D02*
X467715D01*
G01X457085Y165433D02*
X458030D01*
G01Y166142D02*
X457085D01*
G01X467715Y166181D02*
X466534D01*
G01Y167362D02*
X467715D01*
G01X457085Y167402D02*
X458030D01*
G01Y168110D02*
X457085D01*
G01X467715Y168150D02*
X466534D01*
G01Y169331D02*
X467715D01*
G01X457085Y169370D02*
X458030D01*
G01Y170079D02*
X457085D01*
G01X467715Y170118D02*
X466534D01*
G01Y171299D02*
X467715D01*
G01X457085Y171339D02*
X458030D01*
G01Y172047D02*
X457085D01*
G01X467715Y172087D02*
X466534D01*
G01Y173268D02*
X467715D01*
G01X457085Y173307D02*
X458030D01*
G01Y174016D02*
X457085D01*
G01X467715Y174055D02*
X466534D01*
G01X457085Y175925D02*
X458857D01*
G01X467715Y189016D02*
G03X467912Y189213I0J197D01*
G01Y189606D02*
G03X467715Y189803I-197J0D01*
G01Y187047D02*
G03X467912Y187244I0J197D01*
G01Y187638D02*
G03X467715Y187835I-197J0D01*
G01Y185079D02*
G03X467912Y185276I0J197D01*
G01Y185669D02*
G03X467715Y185866I-197J0D01*
G01Y183110D02*
G03X467912Y183307I0J197D01*
G01Y183701D02*
G03X467715Y183898I-197J0D01*
G01X459841Y193642D02*
G03X461022Y194823I0J1181D01*
G01X458030Y183858D02*
Y183150D01*
G01Y185827D02*
Y185118D01*
G01Y187795D02*
Y187087D01*
G01Y189764D02*
Y189055D01*
G01X467912Y189213D02*
Y189606D01*
G01Y187244D02*
Y187638D01*
G01Y185276D02*
Y185669D01*
G01Y183307D02*
Y183701D01*
G01X458857Y180256D02*
X457085D01*
G01X466534Y183110D02*
X467715D01*
G01X457085Y183150D02*
X458030D01*
G01Y183858D02*
X457085D01*
G01X467715Y183898D02*
X466534D01*
G01Y185079D02*
X467715D01*
G01X457085Y185118D02*
X458030D01*
G01Y185827D02*
X457085D01*
G01X467715Y185866D02*
X466534D01*
G01Y187047D02*
X467715D01*
G01X457085Y187087D02*
X458030D01*
G01Y187795D02*
X457085D01*
G01X467715Y187835D02*
X466534D01*
G01Y189016D02*
X467715D01*
G01X457085Y189055D02*
X458030D01*
G01Y189764D02*
X457085D01*
G01X467715Y189803D02*
X466534D01*
G01X457085Y193642D02*
X459841D01*
G01X455904Y197283D02*
Y200197D01*
G01X457085Y194823D02*
Y197283D01*
G01X461022Y194823D02*
Y197283D01*
G01X457085Y194823D02*
X461022D01*
G01X460244Y363425D02*
G03Y371299I0J3937D01*
G01X485441Y-105354D02*
G03Y-113228I0J-3937D01*
G01X478381Y209642D02*
Y217442D01*
G01X490981Y209642D02*
X478381D01*
G01X477281Y208542D02*
Y218542D01*
G01X492081Y208542D02*
X477281D01*
G01X501180Y240354D02*
G03X469684I-15748J0D01*
G03X501180I15748J0D01*
G01D02*
G03X469684I-15748J0D01*
G03X501180I15748J0D01*
G01X484681Y215542D02*
G03Y211542I0J-2000D01*
G01D02*
G03Y215542I0J2000D01*
G01X478381Y217442D02*
X490981D01*
G01X477281Y218542D02*
X492081D01*
G01X492420Y240354D02*
G03X478444I-6988J0D01*
G03X492420I6988J0D01*
G01D02*
G03X478444I-6988J0D01*
G03X492420I6988J0D01*
G01X485431Y247343D02*
G03Y233366I1J-6988D01*
G01X485441Y371299D02*
G03Y363425I0J-3937D01*
G01Y-113228D02*
X683652D01*
G01X490981Y217442D02*
Y209642D01*
G01X492081Y218542D02*
Y208542D01*
G01X485431Y233366D02*
G03Y247343I1J6989D01*
G01X506495Y250197D02*
G03X498621Y258071I-7874J0D01*
G01X506495Y250197D02*
G03X498621Y258071I-7874J0D01*
G01X506495Y250197D02*
G03X498621Y258071I-7874J0D01*
G01X506495Y250197D02*
G03X498621Y258071I-7874J0D01*
G01X506494Y250197D02*
G03X498620Y258071I-7874J0D01*
G01X485441Y371299D02*
X683652D01*
G01X506495Y0D02*
G03X514369Y-7874I7874J0D01*
G01X506495Y0D02*
G03X514369Y-7874I7874J0D01*
G01X506495Y0D02*
G03X514369Y-7874I7874J0D01*
G01X506495Y0D02*
G03X514369Y-7874I7874J0D01*
G01X714566D02*
X514369D01*
G01D02*
X714566D01*
G01D02*
X514369D01*
G01X506495Y0D02*
G03X514369Y-7874I7874J0D01*
G01X714566D02*
X514369D01*
G01X506495Y250197D02*
Y0D01*
G01Y250197D02*
Y0D01*
G01Y250197D02*
Y0D01*
G01Y250197D02*
Y-984D01*
G01X514369Y0D02*
Y116437D01*
G01X506494Y0D02*
Y250197D01*
G01X535137Y0D02*
X514369D01*
G01Y116437D02*
G03X506494I-3937J0D01*
G01Y141634D02*
G03X514369I3937J0D01*
G01D02*
Y258071D01*
G01D02*
X535137D01*
G01X529966Y-751064D02*
X530436Y-751589D01*
X530984Y-751904D01*
X531689Y-752009D01*
X532394Y-751799D01*
X532942Y-751379D01*
X533334Y-750644D01*
X533412Y-749804D01*
X533256Y-748964D01*
X532864Y-748439D01*
X532316Y-748019D01*
X531767Y-747914D01*
X531219Y-748019D01*
X530514Y-748439D01*
X530749Y-745709D01*
X532864D01*
G01X529966Y609566D02*
X530436Y609041D01*
X530984Y608726D01*
X531689Y608621D01*
X532394Y608831D01*
X532942Y609251D01*
X533334Y609986D01*
X533412Y610826D01*
X533256Y611666D01*
X532864Y612191D01*
X532316Y612611D01*
X531767Y612716D01*
X531219Y612611D01*
X530514Y612191D01*
X530749Y614921D01*
X532864D01*
G01X542010Y-69933D02*
Y-54333D01*
G01X546495Y-69933D02*
X537525D01*
G01X535137Y-7874D02*
G03Y0I0J3937D01*
G01X551396Y69008D02*
G03X542813I-4291J0D01*
G03X551396I4291J0D01*
G01Y195351D02*
G03X542813Y195352I-4292J0D01*
G03X551396Y195351I4291J-1D01*
G01X535137Y258071D02*
G03Y265945I0J3937D01*
G01X553460Y328003D02*
Y312403D01*
G01X548975Y328003D02*
X557945D01*
G01X560333Y0D02*
G03Y-7874I1J-3937D01*
G01X581102Y0D02*
X560333D01*
G01Y265945D02*
G03Y258071I1J-3937D01*
G01D02*
X581102D01*
G01Y116437D02*
Y0D01*
G01X588976Y116437D02*
G03X581102I-3937J0D01*
G01Y141634D02*
G03X588976I3937J0D01*
G01X581102Y258071D02*
Y141634D01*
G01X588976Y258070D02*
G03X581102Y265945I-7874J1D01*
G01X588976Y258070D02*
G03X581102Y265945I-7874J1D01*
G01X588976Y258070D02*
G03X581102Y265945I-7874J1D01*
G01X588976Y258070D02*
G03X581102Y265945I-7874J1D01*
G01X588976Y258071D02*
G03X581102Y265945I-7874J0D01*
G01X625787Y17716D02*
G03X594291Y17717I-15748J0D01*
G03X625787Y17716I15748J-1D01*
G01D02*
G03X594291Y17717I-15748J0D01*
G03X625787Y17716I15748J-1D01*
G01X588976Y7874D02*
G03X596850Y0I7874J0D01*
G01X588976Y7874D02*
G03X596850Y0I7874J0D01*
G01X588976Y7874D02*
G03X596850Y0I7874J0D01*
G01X588976Y7874D02*
G03X596850Y0I7874J0D01*
G01X588976Y7874D02*
Y258070D01*
G01Y7874D02*
Y258070D01*
G01X596850Y0D02*
X720472D01*
G01X596850D02*
X720472D01*
G01X588976Y7874D02*
Y258070D01*
G01Y7874D02*
Y259055D01*
G01X596850Y0D02*
X720472D01*
G01X596850D02*
X720472D01*
G01X596850D02*
X720472D01*
G01X588976Y7874D02*
G03X596850Y0I7874J0D01*
G01X588976Y258071D02*
Y7874D01*
G01X660432Y40551D02*
X588976D01*
G01Y57874D02*
X692125D01*
G01X639566Y150393D02*
X588976D01*
G01Y166535D02*
X639566D01*
G01X588976Y259055D02*
X639566D01*
G01X610953Y-740940D02*
Y-758263D01*
G01X617027Y17716D02*
G03X603050Y17717I-6989J0D01*
G03X617027Y17716I6989J-1D01*
G01D02*
G03X603050Y17717I-6989J0D01*
G03X617027Y17716I6989J-1D01*
G01X610039Y24705D02*
G03Y10728I0J-6989D01*
G01D02*
G03Y24705I0J6988D01*
G01X610789Y42529D02*
G03Y46529I0J2000D01*
G01D02*
G03Y42529I0J-2000D01*
G01X617089Y40629D02*
X604489D01*
G01X617089Y48429D02*
Y40629D01*
G01X604489D02*
Y48429D01*
G01X618189Y39529D02*
X603389D01*
G01D02*
Y49529D01*
G01X604489Y48429D02*
X617089D01*
G01X603389Y49529D02*
X618189D01*
G01X610953Y619690D02*
Y602367D01*
G01X618189Y49529D02*
Y39529D01*
G01X631614Y43814D02*
X646829Y28599D01*
G01X638684Y40279D02*
X631614Y43814D01*
G01D02*
X635149Y36744D01*
G01X628936Y147401D02*
Y60787D01*
G01D02*
X660235D01*
G01X627755Y69055D02*
G03X627558Y68858I0J-197D01*
G01Y68464D02*
G03X627755Y68267I197J0D01*
G01Y71023D02*
G03X627558Y70826I0J-197D01*
G01Y70433D02*
G03X627755Y70236I197J0D01*
G01Y72992D02*
G03X627558Y72795I0J-197D01*
G01Y72401D02*
G03X627755Y72204I197J0D01*
G01Y74960D02*
G03X627558Y74763I0J-197D01*
G01Y74370D02*
G03X627755Y74173I197J0D01*
G01X627558Y68858D02*
Y68464D01*
G01Y70826D02*
Y70433D01*
G01Y72795D02*
Y72401D01*
G01Y74763D02*
Y74370D01*
G01X628936Y74960D02*
X627755D01*
G01Y74173D02*
X628936D01*
G01Y72992D02*
X627755D01*
G01Y72204D02*
X628936D01*
G01Y71023D02*
X627755D01*
G01Y70236D02*
X628936D01*
G01Y69055D02*
X627755D01*
G01Y68267D02*
X628936D01*
G01X627755Y90708D02*
G03X627558Y90511I0J-197D01*
G01X627755Y92677D02*
G03X627558Y92480I0J-197D01*
G01Y92086D02*
G03X627755Y91889I197J0D01*
G01Y94645D02*
G03X627558Y94448I0J-197D01*
G01Y94055D02*
G03X627755Y93858I197J0D01*
G01Y84803D02*
G03X627558Y84606I0J-197D01*
G01Y84212D02*
G03X627755Y84015I197J0D01*
G01Y86771D02*
G03X627558Y86574I0J-197D01*
G01Y86181D02*
G03X627755Y85984I197J0D01*
G01Y88740D02*
G03X627558Y88543I0J-197D01*
G01Y88149D02*
G03X627755Y87952I197J0D01*
G01X627558Y90118D02*
G03X627755Y89921I197J0D01*
G01X627558Y84606D02*
Y84212D01*
G01Y86574D02*
Y86181D01*
G01Y88543D02*
Y88149D01*
G01Y90511D02*
Y90118D01*
G01Y92480D02*
Y92086D01*
G01Y94448D02*
Y94055D01*
G01X628936Y94645D02*
X627755D01*
G01Y93858D02*
X628936D01*
G01Y92677D02*
X627755D01*
G01Y91889D02*
X628936D01*
G01Y90708D02*
X627755D01*
G01Y89921D02*
X628936D01*
G01Y88740D02*
X627755D01*
G01Y87952D02*
X628936D01*
G01Y86771D02*
X627755D01*
G01Y85984D02*
X628936D01*
G01Y84803D02*
X627755D01*
G01Y84015D02*
X628936D01*
G01X627755Y96614D02*
G03X627558Y96417I0J-197D01*
G01Y96023D02*
G03X627755Y95826I197J0D01*
G01Y98582D02*
G03X627558Y98385I0J-197D01*
G01Y97992D02*
G03X627755Y97795I197J0D01*
G01Y100551D02*
G03X627558Y100354I0J-197D01*
G01Y99960D02*
G03X627755Y99763I197J0D01*
G01Y102519D02*
G03X627558Y102322I0J-197D01*
G01Y101929D02*
G03X627755Y101732I197J0D01*
G01Y104488D02*
G03X627558Y104291I0J-197D01*
G01Y103897D02*
G03X627755Y103700I197J0D01*
G01Y106456D02*
G03X627558Y106259I0J-197D01*
G01Y105866D02*
G03X627755Y105669I197J0D01*
G01Y108425D02*
G03X627558Y108228I0J-197D01*
G01Y107834D02*
G03X627755Y107637I197J0D01*
G01Y110393D02*
G03X627558Y110196I0J-197D01*
G01Y109803D02*
G03X627755Y109606I197J0D01*
G01Y112362D02*
G03X627558Y112165I0J-197D01*
G01Y111771D02*
G03X627755Y111574I197J0D01*
G01X627558Y96417D02*
Y96023D01*
G01Y98385D02*
Y97992D01*
G01Y100354D02*
Y99960D01*
G01Y102322D02*
Y101929D01*
G01Y104291D02*
Y103897D01*
G01Y106259D02*
Y105866D01*
G01Y108228D02*
Y107834D01*
G01Y110196D02*
Y109803D01*
G01Y112165D02*
Y111771D01*
G01X627755Y111574D02*
X628936D01*
G01Y110393D02*
X627755D01*
G01Y109606D02*
X628936D01*
G01Y108425D02*
X627755D01*
G01Y107637D02*
X628936D01*
G01Y106456D02*
X627755D01*
G01Y105669D02*
X628936D01*
G01Y104488D02*
X627755D01*
G01Y103700D02*
X628936D01*
G01Y102519D02*
X627755D01*
G01Y101732D02*
X628936D01*
G01Y100551D02*
X627755D01*
G01Y99763D02*
X628936D01*
G01Y98582D02*
X627755D01*
G01Y97795D02*
X628936D01*
G01Y96614D02*
X627755D01*
G01Y95826D02*
X628936D01*
G01X627755Y114330D02*
G03X627558Y114133I0J-197D01*
G01Y113740D02*
G03X627755Y113543I197J0D01*
G01Y116299D02*
G03X627558Y116102I0J-197D01*
G01Y115708D02*
G03X627755Y115511I197J0D01*
G01Y118267D02*
G03X627558Y118070I0J-197D01*
G01Y117677D02*
G03X627755Y117480I197J0D01*
G01Y120236D02*
G03X627558Y120039I0J-197D01*
G01Y119645D02*
G03X627755Y119448I197J0D01*
G01Y122204D02*
G03X627558Y122008I0J-197D01*
G01Y121614D02*
G03X627755Y121417I197J0D01*
G01Y124173D02*
G03X627558Y123976I0J-197D01*
G01Y123582D02*
G03X627755Y123385I197J0D01*
G01Y126141D02*
G03X627558Y125945I0J-197D01*
G01Y125551D02*
G03X627755Y125354I197J0D01*
G01Y128110D02*
G03X627558Y127913I0J-197D01*
G01Y127519D02*
G03X627755Y127322I197J0D01*
G01X627558Y114133D02*
Y113740D01*
G01Y116102D02*
Y115708D01*
G01Y118070D02*
Y117677D01*
G01Y120039D02*
Y119645D01*
G01Y122008D02*
Y121614D01*
G01Y123976D02*
Y123582D01*
G01Y125945D02*
Y125551D01*
G01Y127913D02*
Y127519D01*
G01X628936Y128110D02*
X627755D01*
G01Y127322D02*
X628936D01*
G01Y126141D02*
X627755D01*
G01Y125354D02*
X628936D01*
G01Y124173D02*
X627755D01*
G01Y123385D02*
X628936D01*
G01Y122204D02*
X627755D01*
G01Y121417D02*
X628936D01*
G01Y120236D02*
X627755D01*
G01Y119448D02*
X628936D01*
G01Y118267D02*
X627755D01*
G01Y117480D02*
X628936D01*
G01Y116299D02*
X627755D01*
G01Y115511D02*
X628936D01*
G01Y114330D02*
X627755D01*
G01Y113543D02*
X628936D01*
G01Y112362D02*
X627755D01*
G01Y135984D02*
G03X627558Y135787I0J-197D01*
G01Y135393D02*
G03X627755Y135196I197J0D01*
G01Y137952D02*
G03X627558Y137756I0J-197D01*
G01Y137362D02*
G03X627755Y137165I197J0D01*
G01Y139921D02*
G03X627558Y139724I0J-197D01*
G01Y139330D02*
G03X627755Y139133I197J0D01*
G01Y130078D02*
G03X627558Y129882I0J-197D01*
G01Y129488D02*
G03X627755Y129291I197J0D01*
G01Y132047D02*
G03X627558Y131850I0J-197D01*
G01Y131456D02*
G03X627755Y131259I197J0D01*
G01Y134015D02*
G03X627558Y133819I0J-197D01*
G01Y133425D02*
G03X627755Y133228I197J0D01*
G01X627558Y129882D02*
Y129488D01*
G01Y131850D02*
Y131456D01*
G01Y133819D02*
Y133425D01*
G01Y135787D02*
Y135393D01*
G01Y137756D02*
Y137362D01*
G01Y139724D02*
Y139330D01*
G01X628936Y139921D02*
X627755D01*
G01Y139133D02*
X628936D01*
G01Y137952D02*
X627755D01*
G01Y137165D02*
X628936D01*
G01Y135984D02*
X627755D01*
G01Y135196D02*
X628936D01*
G01Y134015D02*
X627755D01*
G01Y133228D02*
X628936D01*
G01Y132047D02*
X627755D01*
G01Y131259D02*
X628936D01*
G01Y130078D02*
X627755D01*
G01Y129291D02*
X628936D01*
G01Y147401D02*
X660235D01*
G01X627755Y177716D02*
G03X627558Y177519I0J-197D01*
G01Y177126D02*
G03X627755Y176929I197J0D01*
G01X628936Y256063D02*
Y169448D01*
G01X627558Y177519D02*
Y177126D01*
G01X628936Y177716D02*
X627755D01*
G01Y176929D02*
X628936D01*
G01Y169448D02*
X660235D01*
G01X627755Y179685D02*
G03X627558Y179488I0J-197D01*
G01Y179094D02*
G03X627755Y178897I197J0D01*
G01Y181653D02*
G03X627558Y181456I0J-197D01*
G01Y181063D02*
G03X627755Y180866I197J0D01*
G01Y183622D02*
G03X627558Y183425I0J-197D01*
G01Y183031D02*
G03X627755Y182834I197J0D01*
G01Y193464D02*
G03X627558Y193267I0J-197D01*
G01Y192874D02*
G03X627755Y192677I197J0D01*
G01X627558Y194842D02*
G03X627755Y194645I197J0D01*
G01X627558Y179488D02*
Y179094D01*
G01Y181456D02*
Y181063D01*
G01Y183425D02*
Y183031D01*
G01Y193267D02*
Y192874D01*
G01X627755Y194645D02*
X628936D01*
G01Y193464D02*
X627755D01*
G01Y192677D02*
X628936D01*
G01Y183622D02*
X627755D01*
G01Y182834D02*
X628936D01*
G01Y181653D02*
X627755D01*
G01Y180866D02*
X628936D01*
G01Y179685D02*
X627755D01*
G01Y178897D02*
X628936D01*
G01X627755Y195433D02*
G03X627558Y195236I0J-197D01*
G01X627755Y197401D02*
G03X627558Y197204I0J-197D01*
G01Y196811D02*
G03X627755Y196614I197J0D01*
G01Y199370D02*
G03X627558Y199173I0J-197D01*
G01Y198779D02*
G03X627755Y198582I197J0D01*
G01Y201338D02*
G03X627558Y201141I0J-197D01*
G01Y200748D02*
G03X627755Y200551I197J0D01*
G01Y203307D02*
G03X627558Y203110I0J-197D01*
G01Y202716D02*
G03X627755Y202519I197J0D01*
G01Y205275D02*
G03X627558Y205078I0J-197D01*
G01Y204685D02*
G03X627755Y204488I197J0D01*
G01Y207244D02*
G03X627558Y207047I0J-197D01*
G01Y206653D02*
G03X627755Y206456I197J0D01*
G01Y209212D02*
G03X627558Y209015I0J-197D01*
G01Y208622D02*
G03X627755Y208425I197J0D01*
G01Y211181D02*
G03X627558Y210984I0J-197D01*
G01Y210590D02*
G03X627755Y210393I197J0D01*
G01X627558Y195236D02*
Y194842D01*
G01Y197204D02*
Y196811D01*
G01Y199173D02*
Y198779D01*
G01Y201141D02*
Y200748D01*
G01Y203110D02*
Y202716D01*
G01Y205078D02*
Y204685D01*
G01Y207047D02*
Y206653D01*
G01Y209015D02*
Y208622D01*
G01Y210984D02*
Y210590D01*
G01X628936Y211181D02*
X627755D01*
G01Y210393D02*
X628936D01*
G01Y209212D02*
X627755D01*
G01Y208425D02*
X628936D01*
G01Y207244D02*
X627755D01*
G01Y206456D02*
X628936D01*
G01Y205275D02*
X627755D01*
G01Y204488D02*
X628936D01*
G01Y203307D02*
X627755D01*
G01Y202519D02*
X628936D01*
G01Y201338D02*
X627755D01*
G01Y200551D02*
X628936D01*
G01Y199370D02*
X627755D01*
G01Y198582D02*
X628936D01*
G01Y197401D02*
X627755D01*
G01Y196614D02*
X628936D01*
G01Y195433D02*
X627755D01*
G01Y219055D02*
G03X627558Y218858I0J-197D01*
G01X627755Y221023D02*
G03X627558Y220826I0J-197D01*
G01Y220433D02*
G03X627755Y220236I197J0D01*
G01Y222992D02*
G03X627558Y222795I0J-197D01*
G01Y222401D02*
G03X627755Y222204I197J0D01*
G01Y224960D02*
G03X627558Y224763I0J-197D01*
G01Y224370D02*
G03X627755Y224173I197J0D01*
G01Y226929D02*
G03X627558Y226732I0J-197D01*
G01Y226338D02*
G03X627755Y226141I197J0D01*
G01Y213149D02*
G03X627558Y212952I0J-197D01*
G01Y212559D02*
G03X627755Y212362I197J0D01*
G01Y215118D02*
G03X627558Y214921I0J-197D01*
G01Y214527D02*
G03X627755Y214330I197J0D01*
G01Y217086D02*
G03X627558Y216889I0J-197D01*
G01Y216496D02*
G03X627755Y216299I197J0D01*
G01X627558Y218464D02*
G03X627755Y218267I197J0D01*
G01X627558Y212952D02*
Y212559D01*
G01Y214921D02*
Y214527D01*
G01Y216889D02*
Y216496D01*
G01Y218858D02*
Y218464D01*
G01Y220826D02*
Y220433D01*
G01Y222795D02*
Y222401D01*
G01Y224763D02*
Y224370D01*
G01Y226732D02*
Y226338D01*
G01X628857Y219104D02*
X628936Y219078D01*
G01Y226929D02*
X627755D01*
G01Y226141D02*
X628936D01*
G01Y224960D02*
X627755D01*
G01Y224173D02*
X628936D01*
G01Y222992D02*
X627755D01*
G01Y222204D02*
X628936D01*
G01Y221023D02*
X627755D01*
G01Y220236D02*
X628936D01*
G01X627873Y219104D02*
X628857D01*
G01X627755Y218267D02*
X628936D01*
G01Y217086D02*
X627755D01*
G01Y216299D02*
X628936D01*
G01Y215118D02*
X627755D01*
G01Y214330D02*
X628936D01*
G01Y213149D02*
X627755D01*
G01Y212362D02*
X628936D01*
G01X627752Y219063D02*
X627873Y219104D01*
G01X627755Y228897D02*
G03X627558Y228700I0J-197D01*
G01Y228307D02*
G03X627755Y228110I197J0D01*
G01Y230866D02*
G03X627558Y230669I0J-197D01*
G01Y230275D02*
G03X627755Y230078I197J0D01*
G01Y232834D02*
G03X627558Y232637I0J-197D01*
G01Y232244D02*
G03X627755Y232047I197J0D01*
G01Y234803D02*
G03X627558Y234606I0J-197D01*
G01Y234212D02*
G03X627755Y234015I197J0D01*
G01Y236771D02*
G03X627558Y236574I0J-197D01*
G01Y236181D02*
G03X627755Y235984I197J0D01*
G01Y238740D02*
G03X627558Y238543I0J-197D01*
G01Y238149D02*
G03X627755Y237952I197J0D01*
G01Y240708D02*
G03X627558Y240511I0J-197D01*
G01Y240118D02*
G03X627755Y239921I197J0D01*
G01Y242677D02*
G03X627558Y242480I0J-197D01*
G01Y242086D02*
G03X627755Y241889I197J0D01*
G01X627558Y244055D02*
G03X627755Y243858I197J0D01*
G01X627558Y228700D02*
Y228307D01*
G01Y230669D02*
Y230275D01*
G01Y232637D02*
Y232244D01*
G01Y234606D02*
Y234212D01*
G01Y236574D02*
Y236181D01*
G01Y238543D02*
Y238149D01*
G01Y240511D02*
Y240118D01*
G01Y242480D02*
Y242086D01*
G01Y244448D02*
Y244055D01*
G01X627755Y243858D02*
X628936D01*
G01Y242677D02*
X627755D01*
G01Y241889D02*
X628936D01*
G01Y240708D02*
X627755D01*
G01Y239921D02*
X628936D01*
G01Y238740D02*
X627755D01*
G01Y237952D02*
X628936D01*
G01Y236771D02*
X627755D01*
G01Y235984D02*
X628936D01*
G01Y234803D02*
X627755D01*
G01Y234015D02*
X628936D01*
G01Y232834D02*
X627755D01*
G01Y232047D02*
X628936D01*
G01Y230866D02*
X627755D01*
G01Y230078D02*
X628936D01*
G01Y228897D02*
X627755D01*
G01Y228110D02*
X628936D01*
G01X627755Y244645D02*
G03X627558Y244448I0J-197D01*
G01X627755Y246614D02*
G03X627558Y246417I0J-197D01*
G01Y246023D02*
G03X627755Y245826I197J0D01*
G01Y248582D02*
G03X627558Y248385I0J-197D01*
G01Y247992D02*
G03X627755Y247795I197J0D01*
G01X628936Y256063D02*
X660235D01*
G01X627558Y246417D02*
Y246023D01*
G01Y248385D02*
Y247992D01*
G01X628936Y248582D02*
X627755D01*
G01Y247795D02*
X628936D01*
G01Y246614D02*
X627755D01*
G01Y245826D02*
X628936D01*
G01Y244645D02*
X627755D01*
G01X646829Y28599D02*
X683029D01*
G01X635149Y36744D02*
X638684Y40279D01*
G01X639566Y60787D02*
Y57874D01*
G01X638385Y63248D02*
Y60787D01*
G01X634448Y63248D02*
Y60787D01*
G01X635629Y64429D02*
G03X634448Y63248I0J-1181D01*
G01X636613Y82145D02*
G03Y77815I0J-2165D01*
G01X638385Y63248D02*
Y144941D01*
G01X637440Y74212D02*
Y74921D01*
G01Y72244D02*
Y72952D01*
G01Y70275D02*
Y70984D01*
G01Y68307D02*
Y69015D01*
G01X636613Y77815D02*
X638385D01*
G01Y74921D02*
X637440D01*
G01Y74212D02*
X638385D01*
G01Y72952D02*
X637440D01*
G01Y72244D02*
X638385D01*
G01Y70984D02*
X637440D01*
G01Y70275D02*
X638385D01*
G01Y69015D02*
X637440D01*
G01Y68307D02*
X638385D01*
G01Y64429D02*
X635629D01*
G01X638385Y63248D02*
X634448D01*
G01X637440Y93897D02*
Y94606D01*
G01Y91929D02*
Y92637D01*
G01Y87992D02*
Y88700D01*
G01Y89960D02*
Y90669D01*
G01Y86023D02*
Y86732D01*
G01Y84055D02*
Y84763D01*
G01X638385Y94606D02*
X637440D01*
G01Y93897D02*
X638385D01*
G01Y92637D02*
X637440D01*
G01Y91929D02*
X638385D01*
G01Y90669D02*
X637440D01*
G01Y89960D02*
X638385D01*
G01Y88700D02*
X637440D01*
G01Y87992D02*
X638385D01*
G01Y86732D02*
X637440D01*
G01Y86023D02*
X638385D01*
G01Y84763D02*
X637440D01*
G01Y84055D02*
X638385D01*
G01Y82145D02*
X636613D01*
G01X637440Y111614D02*
Y112322D01*
G01Y109645D02*
Y110354D01*
G01Y107677D02*
Y108385D01*
G01Y105708D02*
Y106417D01*
G01Y103740D02*
Y104448D01*
G01Y101771D02*
Y102480D01*
G01Y99803D02*
Y100511D01*
G01Y97834D02*
Y98543D01*
G01Y95866D02*
Y96574D01*
G01Y111614D02*
X638385D01*
G01Y110354D02*
X637440D01*
G01Y109645D02*
X638385D01*
G01Y108385D02*
X637440D01*
G01Y107677D02*
X638385D01*
G01Y106417D02*
X637440D01*
G01Y105708D02*
X638385D01*
G01Y104448D02*
X637440D01*
G01Y103740D02*
X638385D01*
G01Y102480D02*
X637440D01*
G01Y101771D02*
X638385D01*
G01Y100511D02*
X637440D01*
G01Y99803D02*
X638385D01*
G01Y98543D02*
X637440D01*
G01Y97834D02*
X638385D01*
G01Y96574D02*
X637440D01*
G01Y95866D02*
X638385D01*
G01X642598Y122519D02*
G03X643385Y121732I787J0D01*
G01X649287Y125289D02*
X649153Y125157D01*
G01X648952Y125420D02*
X649086Y125551D01*
G01X648885Y125289D02*
X648952Y125420D01*
G01X649153Y125157D02*
X649086Y124895D01*
G01X648818Y125026D02*
X648885Y125289D01*
G01X649488Y125420D02*
X649287Y125289D01*
G01X649086Y125551D02*
X649287Y125682D01*
G01X649891Y128700D02*
Y130472D01*
G01X649488Y129029D02*
Y128700D01*
G01X649086Y124895D02*
Y124632D01*
G01X648818Y126338D02*
Y126667D01*
G01Y127848D02*
Y128176D01*
G01Y124501D02*
Y125026D01*
G01Y122861D02*
Y123189D01*
G01X642598Y142165D02*
Y122519D01*
G01X637440Y127362D02*
Y128070D01*
G01Y125393D02*
Y126102D01*
G01Y123425D02*
Y124133D01*
G01Y121456D02*
Y122165D01*
G01Y119488D02*
Y120196D01*
G01Y117519D02*
Y118228D01*
G01Y115551D02*
Y116259D01*
G01Y113582D02*
Y114291D01*
G01X649086Y124632D02*
X649153Y124370D01*
G01X648885Y124239D02*
X648818Y124501D01*
G01X648952Y124108D02*
X648885Y124239D01*
G01X649153Y124370D02*
X649287Y124239D01*
G01X649086Y123976D02*
X648952Y124108D01*
G01X649287Y124239D02*
X649488Y124108D01*
G01X649287Y123845D02*
X649086Y123976D01*
G01X649756Y123714D02*
X649287Y123845D01*
G01X649488Y128700D02*
X649220Y128766D01*
G01X650024Y125813D02*
X650293Y125748D01*
G01Y125420D02*
X650024Y125485D01*
G01X649488Y124108D02*
X649756Y124042D01*
G01X650158Y128700D02*
X649891D01*
G01X648818Y128176D02*
X650963D01*
G01X638385Y128070D02*
X637440D01*
G01X650359Y127848D02*
X648818D01*
G01X637440Y127362D02*
X638385D01*
G01X648818Y126667D02*
X650091D01*
G01Y126338D02*
X648818D01*
G01X638385Y126102D02*
X637440D01*
G01X649756Y125813D02*
X650024D01*
G01Y125485D02*
X649756D01*
G01X637440Y125393D02*
X638385D01*
G01Y124133D02*
X637440D01*
G01X649756Y124042D02*
X650024D01*
G01Y123714D02*
X649756D01*
G01X637440Y123425D02*
X638385D01*
G01X648818Y123189D02*
X651968D01*
G01Y122861D02*
X648818D01*
G01X638385Y122165D02*
X637440D01*
G01X643385Y121732D02*
X652243D01*
G01X637440Y121456D02*
X638385D01*
G01Y120196D02*
X637440D01*
G01Y119488D02*
X638385D01*
G01Y118228D02*
X637440D01*
G01Y117519D02*
X638385D01*
G01Y116259D02*
X637440D01*
G01Y115551D02*
X638385D01*
G01Y114291D02*
X637440D01*
G01Y113582D02*
X638385D01*
G01Y112322D02*
X637440D01*
G01X650091Y126667D02*
X650426Y126732D01*
G01Y126404D02*
X650091Y126338D01*
G01X650426Y128766D02*
X650158Y128700D01*
G01X649756Y125485D02*
X649488Y125420D01*
G01X650024Y124042D02*
X650293Y124108D01*
G01Y123779D02*
X650024Y123714D01*
G01X649287Y125682D02*
X649756Y125813D01*
G01X643385Y142952D02*
G03X642598Y142165I0J-787D01*
G01X634448Y144941D02*
G03X635629Y143759I1181J-1D01*
G01X649421Y130341D02*
X649220Y130144D01*
G01X649086Y130472D02*
X649220Y130604D01*
G01X648952Y135262D02*
X649086Y135393D01*
G01X648952Y130275D02*
X649086Y130472D01*
G01X649354Y135328D02*
X649220Y135131D01*
G01Y130144D02*
X649153Y130013D01*
G01X648885Y135131D02*
X648952Y135262D01*
G01X648885Y130078D02*
X648952Y130275D01*
G01X649153Y130013D02*
X649086Y129750D01*
G01X649220Y135131D02*
X649153Y134869D01*
G01X648818D02*
X648885Y135131D01*
G01X648818Y129685D02*
X648885Y130078D01*
G01X649086Y129750D02*
X649153Y129291D01*
G01X648885Y129226D02*
X648818Y129685D01*
G01X649153Y134606D02*
X649220Y134344D01*
G01X649555Y130407D02*
X649421Y130341D01*
G01X649220Y130604D02*
X649488Y130735D01*
G01X649555Y135459D02*
X649354Y135328D01*
G01X650158Y130407D02*
Y129029D01*
G01X649891Y141168D02*
Y139987D01*
G01X649622Y139921D02*
Y141233D01*
G01X649153Y134869D02*
Y134606D01*
G01X648818Y141496D02*
Y141889D01*
G01Y137362D02*
Y137690D01*
G01Y138412D02*
Y138740D01*
G01Y139265D02*
Y139659D01*
G01Y136312D02*
Y136640D01*
G01Y132834D02*
Y133163D01*
G01Y134475D02*
Y134869D01*
G01Y131325D02*
Y131653D01*
G01X647746Y135459D02*
Y135787D01*
G01X646731Y131456D02*
Y130866D01*
G01Y134015D02*
Y133425D01*
G01X643582Y133622D02*
Y134015D01*
G01Y130866D02*
Y131259D01*
G01Y132178D02*
Y132703D01*
G01X638385Y147401D02*
Y144941D01*
G01X637440Y137204D02*
Y137913D01*
G01Y139173D02*
Y139882D01*
G01Y135236D02*
Y135945D01*
G01Y133267D02*
Y133976D01*
G01Y131299D02*
Y132008D01*
G01Y129330D02*
Y130039D01*
G01X634448Y147401D02*
Y144941D01*
G01X648885Y134212D02*
X648818Y134475D01*
G01X649756Y130472D02*
X649555Y130407D01*
G01X650091Y134015D02*
X650293Y134081D01*
G01X649891Y139987D02*
X651700Y140577D01*
G01X648818Y139659D02*
X649622Y139921D01*
G01X651968Y140315D02*
X648818Y139265D01*
G01X646731Y133425D02*
X643917Y132441D01*
G01X643582Y132703D02*
X646061Y133622D01*
G01X649086Y135393D02*
X649220Y135459D01*
G01X649019Y128963D02*
X648885Y129226D01*
G01X649220Y134344D02*
X649354Y134147D01*
G01X649019Y134015D02*
X648885Y134212D01*
G01X649153Y129291D02*
X649287Y129094D01*
G01X649220Y128766D02*
X649019Y128963D01*
G01X649354Y133753D02*
X649019Y134015D01*
G01X649354Y134147D02*
X649488Y134081D01*
G01X646061Y131259D02*
X643582Y132178D01*
G01X648818Y141889D02*
X651968Y140840D01*
G01X651700Y140577D02*
X649891Y141168D01*
G01X649622Y141233D02*
X648818Y141496D01*
G01X649488Y134081D02*
X649689Y134015D01*
G01X643917Y132441D02*
X646731Y131456D01*
G01X649287Y129094D02*
X649488Y129029D01*
G01X649622Y133687D02*
X649354Y133753D01*
G01X649891Y130800D02*
X650293Y130735D01*
G01X634448Y144941D02*
X638385D01*
G01Y143759D02*
X635629D01*
G01X652243Y142952D02*
X643385D01*
G01X638385Y139882D02*
X637440D01*
G01Y139173D02*
X638385D01*
G01X648818Y138740D02*
X650963D01*
G01X650493Y138412D02*
X648818D01*
G01X638385Y137913D02*
X637440D01*
G01X648818Y137690D02*
X650426D01*
G01Y137362D02*
X648818D01*
G01X637440Y137204D02*
X638385D01*
G01X648818Y136640D02*
X650426D01*
G01Y136312D02*
X648818D01*
G01X638385Y135945D02*
X637440D01*
G01X647746Y135787D02*
X650963D01*
G01X649220Y135459D02*
X647746D01*
G01X650226D02*
X649555D01*
G01X637440Y135236D02*
X638385D01*
G01X649689Y134015D02*
X650091D01*
G01X643582D02*
X646731D01*
G01X638385Y133976D02*
X637440D01*
G01X650158Y133687D02*
X649622D01*
G01X646061Y133622D02*
X643582D01*
G01X637440Y133267D02*
X638385D01*
G01X648818Y133163D02*
X651968D01*
G01X650359Y132834D02*
X648818D01*
G01X638385Y132008D02*
X637440D01*
G01X648818Y131653D02*
X650158D01*
G01Y131325D02*
X648818D01*
G01X637440Y131299D02*
X638385D01*
G01X643582Y131259D02*
X646061D01*
G01X646731Y130866D02*
X643582D01*
G01X649891Y130472D02*
X649756D01*
G01X650226Y130407D02*
X650158D01*
G01X638385Y130039D02*
X637440D01*
G01Y129330D02*
X638385D01*
G01X650158Y129029D02*
X650293D01*
G01X649488Y130735D02*
X649891Y130800D01*
G01X650493Y131391D02*
X650158Y131325D01*
G01X650426Y133753D02*
X650158Y133687D01*
G01Y131653D02*
X650426Y131719D01*
G01X639566Y150393D02*
Y147401D01*
G01X635629Y173090D02*
G03X634448Y171909I0J-1181D01*
G01X639566Y169448D02*
Y166535D01*
G01X638385Y171909D02*
Y253602D01*
G01Y171909D02*
Y169448D01*
G01X637440Y176968D02*
Y177677D01*
G01X634448Y171909D02*
Y169448D01*
G01X638385Y177677D02*
X637440D01*
G01Y176968D02*
X638385D01*
G01Y173090D02*
X635629D01*
G01X638385Y171909D02*
X634448D01*
G01X636613Y190807D02*
G03Y186476I0J-2165D01*
G01X637440Y194685D02*
Y195393D01*
G01Y192716D02*
Y193425D01*
G01Y182874D02*
Y183582D01*
G01Y180905D02*
Y181614D01*
G01Y178937D02*
Y179645D01*
G01Y194685D02*
X638385D01*
G01Y193425D02*
X637440D01*
G01Y192716D02*
X638385D01*
G01Y190807D02*
X636613D01*
G01Y186476D02*
X638385D01*
G01Y183582D02*
X637440D01*
G01Y182874D02*
X638385D01*
G01Y181614D02*
X637440D01*
G01Y180905D02*
X638385D01*
G01Y179645D02*
X637440D01*
G01Y178937D02*
X638385D01*
G01X637440Y210433D02*
Y211141D01*
G01Y208464D02*
Y209173D01*
G01Y206496D02*
Y207204D01*
G01Y204527D02*
Y205236D01*
G01Y202559D02*
Y203267D01*
G01Y200590D02*
Y201299D01*
G01Y198622D02*
Y199330D01*
G01Y196653D02*
Y197362D01*
G01X638385Y211141D02*
X637440D01*
G01Y210433D02*
X638385D01*
G01Y209173D02*
X637440D01*
G01Y208464D02*
X638385D01*
G01Y207204D02*
X637440D01*
G01Y206496D02*
X638385D01*
G01Y205236D02*
X637440D01*
G01Y204527D02*
X638385D01*
G01Y203267D02*
X637440D01*
G01Y202559D02*
X638385D01*
G01Y201299D02*
X637440D01*
G01Y200590D02*
X638385D01*
G01Y199330D02*
X637440D01*
G01Y198622D02*
X638385D01*
G01Y197362D02*
X637440D01*
G01Y196653D02*
X638385D01*
G01Y195393D02*
X637440D01*
G01Y226181D02*
Y226889D01*
G01Y224212D02*
Y224921D01*
G01Y222244D02*
Y222952D01*
G01Y220275D02*
Y220984D01*
G01Y218307D02*
Y219015D01*
G01Y214370D02*
Y215078D01*
G01Y216338D02*
Y217047D01*
G01Y212401D02*
Y213110D01*
G01X638385Y226889D02*
X637440D01*
G01Y226181D02*
X638385D01*
G01Y224921D02*
X637440D01*
G01Y224212D02*
X638385D01*
G01Y222952D02*
X637440D01*
G01Y222244D02*
X638385D01*
G01Y220984D02*
X637440D01*
G01Y220275D02*
X638385D01*
G01Y219015D02*
X637440D01*
G01Y218307D02*
X638385D01*
G01Y217047D02*
X637440D01*
G01Y216338D02*
X638385D01*
G01Y215078D02*
X637440D01*
G01Y214370D02*
X638385D01*
G01Y213110D02*
X637440D01*
G01Y212401D02*
X638385D01*
G01X642598Y231181D02*
G03X643385Y230393I787J-1D01*
G01X649086Y238412D02*
X649153Y237952D01*
G01X648885Y237887D02*
X648818Y238346D01*
G01X649153Y243267D02*
X649220Y243005D01*
G01X648885Y242874D02*
X648818Y243136D01*
G01X649086Y233294D02*
X649153Y233031D01*
G01X648885Y232900D02*
X648818Y233163D01*
G01X649019Y237624D02*
X648885Y237887D01*
G01X648952Y232769D02*
X648885Y232900D01*
G01X649220Y243005D02*
X649354Y242808D01*
G01X649019Y242677D02*
X648885Y242874D01*
G01X649153Y237952D02*
X649287Y237756D01*
G01X649220Y237428D02*
X649019Y237624D01*
G01X649153Y233031D02*
X649287Y232900D01*
G01X649086Y232637D02*
X648952Y232769D01*
G01X649354Y242415D02*
X649019Y242677D01*
G01X649287Y232900D02*
X649488Y232769D01*
G01X649287Y232506D02*
X649086Y232637D01*
G01X649354Y242808D02*
X649488Y242743D01*
G01X646061Y239921D02*
X643582Y240840D01*
G01X643917Y241102D02*
X646731Y240118D01*
G01X649488Y242743D02*
X649689Y242677D01*
G01X648818Y238346D02*
X648885Y238740D01*
G01X650158Y239068D02*
Y237690D01*
G01X649891Y237362D02*
Y239133D01*
G01X649488Y237690D02*
Y237362D01*
G01X649153Y243530D02*
Y243267D01*
G01X649086Y233556D02*
Y233294D01*
G01X648818Y243136D02*
Y243530D01*
G01Y241496D02*
Y241824D01*
G01Y239987D02*
Y240315D01*
G01Y236509D02*
Y236837D01*
G01Y233163D02*
Y233687D01*
G01Y235000D02*
Y235328D01*
G01Y231522D02*
Y231850D01*
G01X647746Y244120D02*
Y244448D01*
G01X646731Y240118D02*
Y239527D01*
G01Y242677D02*
Y242086D01*
G01X643582Y242283D02*
Y242677D01*
G01Y240840D02*
Y241365D01*
G01Y239527D02*
Y239921D01*
G01X642598Y250826D02*
Y231181D01*
G01X637440Y243897D02*
Y244606D01*
G01Y241929D02*
Y242637D01*
G01Y239960D02*
Y240669D01*
G01Y237992D02*
Y238700D01*
G01Y236023D02*
Y236732D01*
G01Y234055D02*
Y234763D01*
G01Y232086D02*
Y232795D01*
G01Y230118D02*
Y230826D01*
G01Y228149D02*
Y228858D01*
G01X649287Y237756D02*
X649488Y237690D01*
G01X649756Y232375D02*
X649287Y232506D01*
G01X649622Y242349D02*
X649354Y242415D01*
G01X649488Y237362D02*
X649220Y237428D01*
G01X650024Y234475D02*
X650293Y234409D01*
G01Y234081D02*
X650024Y234147D01*
G01X649488Y232769D02*
X649756Y232703D01*
G01X649891Y239462D02*
X650293Y239396D01*
G01X648885Y238740D02*
X648952Y238937D01*
G01X649153Y233819D02*
X649086Y233556D01*
G01X648818Y233687D02*
X648885Y233950D01*
G01X649153Y238674D02*
X649086Y238412D01*
G01X649220Y243793D02*
X649153Y243530D01*
G01X648818D02*
X648885Y243793D01*
G01X649220Y244120D02*
X647746D01*
G01X650226D02*
X649555D01*
G01X637440Y243897D02*
X638385D01*
G01X649689Y242677D02*
X650091D01*
G01X643582D02*
X646731D01*
G01X638385Y242637D02*
X637440D01*
G01X650158Y242349D02*
X649622D01*
G01X646061Y242283D02*
X643582D01*
G01X637440Y241929D02*
X638385D01*
G01X648818Y241824D02*
X651968D01*
G01X650359Y241496D02*
X648818D01*
G01X638385Y240669D02*
X637440D01*
G01X648818Y240315D02*
X650158D01*
G01Y239987D02*
X648818D01*
G01X637440Y239960D02*
X638385D01*
G01X643582Y239921D02*
X646061D01*
G01X646731Y239527D02*
X643582D01*
G01X649891Y239133D02*
X649756D01*
G01X650226Y239068D02*
X650158D01*
G01X638385Y238700D02*
X637440D01*
G01Y237992D02*
X638385D01*
G01X650158Y237690D02*
X650293D01*
G01X650158Y237362D02*
X649891D01*
G01X648818Y236837D02*
X650963D01*
G01X638385Y236732D02*
X637440D01*
G01X650359Y236509D02*
X648818D01*
G01X637440Y236023D02*
X638385D01*
G01X648818Y235328D02*
X650091D01*
G01Y235000D02*
X648818D01*
G01X638385Y234763D02*
X637440D01*
G01X649756Y234475D02*
X650024D01*
G01X648885Y233950D02*
X648952Y234081D01*
G01X649220Y238806D02*
X649153Y238674D01*
G01X648885Y243793D02*
X648952Y243924D01*
G01X650024Y234147D02*
X649756D01*
G01X637440Y234055D02*
X638385D01*
G01Y232795D02*
X637440D01*
G01X649756Y232703D02*
X650024D01*
G01Y232375D02*
X649756D01*
G01X637440Y232086D02*
X638385D01*
G01X648818Y231850D02*
X651968D01*
G01Y231522D02*
X648818D01*
G01X638385Y230826D02*
X637440D01*
G01X643385Y230393D02*
X652243D01*
G01X637440Y230118D02*
X638385D01*
G01Y228858D02*
X637440D01*
G01Y228149D02*
X638385D01*
G01X649488Y239396D02*
X649891Y239462D01*
G01X650493Y240052D02*
X650158Y239987D01*
G01X648952Y238937D02*
X649086Y239133D01*
G01X649354Y243989D02*
X649220Y243793D01*
G01X650091Y235328D02*
X650426Y235393D01*
G01Y235065D02*
X650091Y235000D01*
G01X650426Y242415D02*
X650158Y242349D01*
G01Y240315D02*
X650426Y240380D01*
G01Y237428D02*
X650158Y237362D01*
G01X649756Y234147D02*
X649488Y234081D01*
G01X650024Y232703D02*
X650293Y232769D01*
G01Y232441D02*
X650024Y232375D01*
G01X649287Y234344D02*
X649756Y234475D01*
G01X649287Y233950D02*
X649153Y233819D01*
G01X648952Y234081D02*
X649086Y234212D01*
G01X649421Y239002D02*
X649220Y238806D01*
G01X649086Y239133D02*
X649220Y239265D01*
G01X648952Y243924D02*
X649086Y244055D01*
G01X649488Y234081D02*
X649287Y233950D01*
G01X649086Y234212D02*
X649287Y234344D01*
G01X649555Y244120D02*
X649354Y243989D01*
G01X649555Y239068D02*
X649421Y239002D01*
G01X649220Y239265D02*
X649488Y239396D01*
G01X649086Y244055D02*
X649220Y244120D01*
G01X649756Y239133D02*
X649555Y239068D01*
G01X650091Y242677D02*
X650293Y242743D01*
G01X646731Y242086D02*
X643917Y241102D01*
G01X643582Y241365D02*
X646061Y242283D01*
G01X643385Y251614D02*
G03X642598Y250826I0J-787D01*
G01X634448Y253602D02*
G03X635629Y252421I1181J0D01*
G01X648818Y250551D02*
X651968Y249501D01*
G01X651700Y249239D02*
X649891Y249829D01*
G01X649622Y249895D02*
X648818Y250157D01*
G01X649891Y249829D02*
Y248648D01*
G01X649622Y248582D02*
Y249895D01*
G01X648818Y250157D02*
Y250551D01*
G01Y247926D02*
Y248320D01*
G01Y246023D02*
Y246352D01*
G01Y244974D02*
Y245302D01*
G01Y247073D02*
Y247401D01*
G01X639566Y259055D02*
Y256063D01*
G01X638385D02*
Y253602D01*
G01X637440Y247834D02*
Y248543D01*
G01Y245866D02*
Y246574D01*
G01X634448Y256063D02*
Y253602D01*
G01X639566Y257086D02*
X692125D01*
G01X634448Y253602D02*
X638385D01*
G01Y252421D02*
X635629D01*
G01X652243Y251614D02*
X643385D01*
G01X638385Y248543D02*
X637440D01*
G01Y247834D02*
X638385D01*
G01X648818Y247401D02*
X650963D01*
G01X650493Y247073D02*
X648818D01*
G01X638385Y246574D02*
X637440D01*
G01X648818Y246352D02*
X650426D01*
G01Y246023D02*
X648818D01*
G01X637440Y245866D02*
X638385D01*
G01X648818Y245302D02*
X650426D01*
G01Y244974D02*
X648818D01*
G01X638385Y244606D02*
X637440D01*
G01X647746Y244448D02*
X650963D01*
G01X651968Y248976D02*
X648818Y247926D01*
G01X649891Y248648D02*
X651700Y249239D01*
G01X648818Y248320D02*
X649622Y248582D01*
G01X684645Y320118D02*
X637401D01*
G01D02*
Y363425D01*
G01X676180Y345708D02*
G03X644685Y345709I-15748J0D01*
G03X676180Y345708I15747J-1D01*
G01D02*
G03X644685Y345709I-15748J0D01*
G03X676180Y345708I15747J-1D01*
G01X653569Y32935D02*
X654316Y32310D01*
X655156Y31935D01*
X655902D01*
X656649Y32310D01*
X657209Y32935D01*
X657489Y33810D01*
X657302Y34685D01*
X656836Y35435D01*
X655996Y35935D01*
X654876Y36185D01*
X654222Y36685D01*
X653942Y37560D01*
X654129Y38435D01*
X654596Y39060D01*
X655249Y39435D01*
X655902D01*
X656556Y39185D01*
X657116Y38560D01*
G01X661629Y35310D02*
X664616D01*
X664336Y36185D01*
X663869Y36685D01*
X663216Y36935D01*
X662562Y36810D01*
X662002Y36435D01*
X661629Y35560D01*
X661442Y34810D01*
Y34060D01*
X661629Y33310D01*
X662096Y32560D01*
X662656Y32060D01*
X663309Y31935D01*
X663962Y32185D01*
X664616Y32935D01*
G01X669222Y31935D02*
Y36935D01*
G01Y35935D02*
X669689Y36435D01*
X670156Y36810D01*
X670809Y36935D01*
X671276Y36810D01*
X671836Y36435D01*
G01X678029Y36935D02*
Y31935D01*
G01Y38935D02*
X677842Y39060D01*
Y39310D01*
X678029Y39435D01*
X678216Y39310D01*
Y39060D01*
X678029Y38935D01*
G01X684129Y35310D02*
X687116D01*
X686836Y36185D01*
X686369Y36685D01*
X685716Y36935D01*
X685062Y36810D01*
X684502Y36435D01*
X684129Y35560D01*
X683942Y34810D01*
Y34060D01*
X684129Y33310D01*
X684596Y32560D01*
X685156Y32060D01*
X685809Y31935D01*
X686462Y32185D01*
X687116Y32935D01*
G01X691629Y32810D02*
X692096Y32310D01*
X692749Y31935D01*
X693309D01*
X693869Y32185D01*
X694242Y32560D01*
X694429Y33060D01*
X694336Y33810D01*
X693962Y34185D01*
X692282Y34935D01*
X691909Y35810D01*
X692096Y36435D01*
X692469Y36810D01*
X693029Y36935D01*
X693589Y36810D01*
X694149Y36435D01*
G01X706442Y31935D02*
Y36935D01*
G01Y35685D02*
X706816Y36310D01*
X707376Y36810D01*
X708122Y36935D01*
X708776Y36810D01*
X709336Y36310D01*
X709616Y35435D01*
Y31935D01*
G01X713942Y36935D02*
Y33435D01*
X714316Y32560D01*
X714876Y32060D01*
X715529Y31935D01*
X716182Y32060D01*
X716742Y32560D01*
X717116Y33435D01*
G01Y31935D02*
Y36935D01*
G01X720229Y31935D02*
Y36935D01*
G01Y35560D02*
X720509Y36185D01*
X720976Y36685D01*
X721629Y36935D01*
X722282Y36685D01*
X722749Y36185D01*
X723029Y35560D01*
Y31935D01*
G01Y35560D02*
X723309Y36185D01*
X723776Y36685D01*
X724429Y36935D01*
X725082Y36685D01*
X725549Y36185D01*
X725829Y35435D01*
Y31935D01*
G01X728849D02*
Y39435D01*
G01Y35685D02*
X729316Y36435D01*
X729876Y36810D01*
X730436Y36935D01*
X731276Y36685D01*
X731836Y36185D01*
X732209Y35310D01*
Y34310D01*
X732022Y33310D01*
X731649Y32560D01*
X730996Y32060D01*
X730436Y31935D01*
X729876Y32060D01*
X729316Y32435D01*
X728849Y33060D01*
G01X736629Y35310D02*
X739616D01*
X739336Y36185D01*
X738869Y36685D01*
X738216Y36935D01*
X737562Y36810D01*
X737002Y36435D01*
X736629Y35560D01*
X736442Y34810D01*
Y34060D01*
X736629Y33310D01*
X737096Y32560D01*
X737656Y32060D01*
X738309Y31935D01*
X738962Y32185D01*
X739616Y32935D01*
G01X744222Y31935D02*
Y36935D01*
G01Y35935D02*
X744689Y36435D01*
X745156Y36810D01*
X745809Y36935D01*
X746276Y36810D01*
X746836Y36435D01*
G01X762209Y31935D02*
Y36935D01*
G01Y36060D02*
X761836Y36560D01*
X761276Y36810D01*
X760622Y36935D01*
X759969Y36685D01*
X759409Y36185D01*
X759036Y35435D01*
X758849Y34435D01*
X759036Y33435D01*
X759409Y32685D01*
X759969Y32185D01*
X760622Y31935D01*
X761276Y32060D01*
X761836Y32435D01*
X762209Y32935D01*
G01X766442Y31935D02*
Y36935D01*
G01Y35685D02*
X766816Y36310D01*
X767376Y36810D01*
X768122Y36935D01*
X768776Y36810D01*
X769336Y36310D01*
X769616Y35435D01*
Y31935D01*
G01X777209Y39435D02*
Y31935D01*
G01Y33060D02*
X776836Y32435D01*
X776276Y32060D01*
X775622Y31935D01*
X774876Y32185D01*
X774316Y32810D01*
X773942Y33560D01*
X773849Y34435D01*
X773942Y35310D01*
X774316Y36060D01*
X774876Y36685D01*
X775622Y36935D01*
X776276Y36810D01*
X776742Y36560D01*
X777209Y36060D01*
G01X789222Y31935D02*
Y36935D01*
G01Y35935D02*
X789689Y36435D01*
X790156Y36810D01*
X790809Y36935D01*
X791276Y36810D01*
X791836Y36435D01*
G01X796629Y35310D02*
X799616D01*
X799336Y36185D01*
X798869Y36685D01*
X798216Y36935D01*
X797562Y36810D01*
X797002Y36435D01*
X796629Y35560D01*
X796442Y34810D01*
Y34060D01*
X796629Y33310D01*
X797096Y32560D01*
X797656Y32060D01*
X798309Y31935D01*
X798962Y32185D01*
X799616Y32935D01*
G01X804969Y31935D02*
Y38310D01*
X805156Y38935D01*
X805529Y39310D01*
X806089Y39435D01*
X806649Y39185D01*
X806929Y38560D01*
G01X805809Y36435D02*
X803942D01*
G01X811629Y35310D02*
X814616D01*
X814336Y36185D01*
X813869Y36685D01*
X813216Y36935D01*
X812562Y36810D01*
X812002Y36435D01*
X811629Y35560D01*
X811442Y34810D01*
Y34060D01*
X811629Y33310D01*
X812096Y32560D01*
X812656Y32060D01*
X813309Y31935D01*
X813962Y32185D01*
X814616Y32935D01*
G01X819222Y31935D02*
Y36935D01*
G01Y35935D02*
X819689Y36435D01*
X820156Y36810D01*
X820809Y36935D01*
X821276Y36810D01*
X821836Y36435D01*
G01X826629Y35310D02*
X829616D01*
X829336Y36185D01*
X828869Y36685D01*
X828216Y36935D01*
X827562Y36810D01*
X827002Y36435D01*
X826629Y35560D01*
X826442Y34810D01*
Y34060D01*
X826629Y33310D01*
X827096Y32560D01*
X827656Y32060D01*
X828309Y31935D01*
X828962Y32185D01*
X829616Y32935D01*
G01X833942Y31935D02*
Y36935D01*
G01Y35685D02*
X834316Y36310D01*
X834876Y36810D01*
X835622Y36935D01*
X836276Y36810D01*
X836836Y36310D01*
X837116Y35435D01*
Y31935D01*
G01X844522Y36310D02*
X843869Y36810D01*
X843309Y36935D01*
X842562Y36685D01*
X842002Y36185D01*
X841629Y35310D01*
X841536Y34435D01*
X841629Y33560D01*
X842002Y32810D01*
X842562Y32185D01*
X843309Y31935D01*
X843962Y32185D01*
X844522Y32685D01*
G01X849129Y35310D02*
X852116D01*
X851836Y36185D01*
X851369Y36685D01*
X850716Y36935D01*
X850062Y36810D01*
X849502Y36435D01*
X849129Y35560D01*
X848942Y34810D01*
Y34060D01*
X849129Y33310D01*
X849596Y32560D01*
X850156Y32060D01*
X850809Y31935D01*
X851462Y32185D01*
X852116Y32935D01*
G01X865529Y31935D02*
X864969Y32060D01*
X864409Y32560D01*
X864036Y33435D01*
X863849Y34435D01*
X864036Y35435D01*
X864409Y36310D01*
X864969Y36810D01*
X865529Y36935D01*
X866089Y36810D01*
X866649Y36310D01*
X867022Y35435D01*
X867116Y34435D01*
X867022Y33435D01*
X866649Y32560D01*
X866089Y32060D01*
X865529Y31935D01*
G01X871442D02*
Y36935D01*
G01Y35685D02*
X871816Y36310D01*
X872376Y36810D01*
X873122Y36935D01*
X873776Y36810D01*
X874336Y36310D01*
X874616Y35435D01*
Y31935D01*
G01X880529D02*
Y39435D01*
G01X886069Y29685D02*
X886629Y29435D01*
X887376Y29685D01*
X887842Y30185D01*
X888216Y30810D01*
X888776Y32810D01*
X889989Y36935D01*
G01X887002D02*
X888776Y32810D01*
G01X895529Y31685D02*
X895342Y31810D01*
Y32060D01*
X895529Y32185D01*
X895716Y32060D01*
Y31810D01*
X895529Y31685D01*
G01X675326Y22834D02*
G03X660432Y33464I-14893J-5118D01*
G01Y34645D02*
Y40551D01*
G01X660235Y60787D02*
G03X661023Y61574I1J787D01*
G01D02*
Y65708D01*
G01X659331Y67283D02*
G03X659528Y67480I0J197D01*
G01Y67874D02*
G03X659331Y68070I-197J-1D01*
G01Y69252D02*
G03X659528Y69448I0J197D01*
G01Y69842D02*
G03X659331Y70039I-197J0D01*
G01Y71220D02*
G03X659528Y71417I0J197D01*
G01Y71811D02*
G03X659331Y72008I-197J0D01*
G01Y73189D02*
G03X659528Y73385I0J197D01*
G01Y73779D02*
G03X659331Y73976I-197J0D01*
G01Y75157D02*
G03X659528Y75354I0J197D01*
G01Y75748D02*
G03X659331Y75945I-197J0D01*
G01X659528Y67874D02*
Y67480D01*
G01Y69842D02*
Y69448D01*
G01Y71811D02*
Y71417D01*
G01Y73779D02*
Y73385D01*
G01Y75748D02*
Y75354D01*
G01X658070Y144252D02*
Y63937D01*
G01X655708Y144252D02*
Y63937D01*
G01X658070Y75945D02*
X659331D01*
G01X658070Y75157D02*
X659331D01*
G01X658070Y73976D02*
X659331D01*
G01X658070Y73189D02*
X659331D01*
G01X658070Y72008D02*
X659331D01*
G01X658070Y71220D02*
X659331D01*
G01X658070Y70039D02*
X659331D01*
G01X658070Y69252D02*
X659331D01*
G01X658070Y68070D02*
X659331D01*
G01X658070Y67283D02*
X659331D01*
G01X658070Y65708D02*
X661023D01*
G01X658070Y65118D02*
X661023D01*
G01X655708Y63937D02*
X661023D01*
G01X659331Y90905D02*
G03X659528Y91102I0J197D01*
G01Y91496D02*
G03X659331Y91693I-197J0D01*
G01Y92874D02*
G03X659528Y93070I0J197D01*
G01Y93464D02*
G03X659331Y93661I-197J0D01*
G01Y94842D02*
G03X659528Y95039I0J197D01*
G01Y95433D02*
G03X659331Y95630I-197J0D01*
G01Y85000D02*
G03X659528Y85196I0J197D01*
G01Y85590D02*
G03X659331Y85787I-197J0D01*
G01Y86968D02*
G03X659528Y87165I0J197D01*
G01Y87559D02*
G03X659331Y87756I-197J0D01*
G01Y88937D02*
G03X659528Y89133I0J197D01*
G01Y89527D02*
G03X659331Y89724I-197J0D01*
G01X659528Y85590D02*
Y85196D01*
G01Y87559D02*
Y87165D01*
G01Y89527D02*
Y89133D01*
G01Y91496D02*
Y91102D01*
G01Y93464D02*
Y93070D01*
G01Y95433D02*
Y95039D01*
G01X658070Y95630D02*
X659331D01*
G01X658070Y94842D02*
X659331D01*
G01X658070Y93661D02*
X659331D01*
G01X658070Y92874D02*
X659331D01*
G01X658070Y91693D02*
X659331D01*
G01X658070Y90905D02*
X659331D01*
G01X658070Y89724D02*
X659331D01*
G01X658070Y88937D02*
X659331D01*
G01X658070Y87756D02*
X659331D01*
G01X658070Y86968D02*
X659331D01*
G01X658070Y85787D02*
X659331D01*
G01X658070Y85000D02*
X659331D01*
G01Y96811D02*
G03X659528Y97008I0J197D01*
G01Y97401D02*
G03X659331Y97598I-197J0D01*
G01Y98779D02*
G03X659528Y98976I0J197D01*
G01Y99370D02*
G03X659331Y99567I-197J0D01*
G01Y100748D02*
G03X659528Y100945I0J197D01*
G01Y101338D02*
G03X659331Y101535I-197J0D01*
G01Y102716D02*
G03X659528Y102913I0J197D01*
G01Y103307D02*
G03X659331Y103504I-197J0D01*
G01Y104685D02*
G03X659528Y104882I0J197D01*
G01Y105275D02*
G03X659331Y105472I-197J0D01*
G01Y106653D02*
G03X659528Y106850I0J197D01*
G01Y107244D02*
G03X659331Y107441I-197J0D01*
G01Y108622D02*
G03X659528Y108819I0J197D01*
G01Y109212D02*
G03X659331Y109409I-197J0D01*
G01Y110590D02*
G03X659528Y110787I0J197D01*
G01Y111181D02*
G03X659331Y111378I-197J0D01*
G01X659528Y97401D02*
Y97008D01*
G01Y99370D02*
Y98976D01*
G01Y101338D02*
Y100945D01*
G01Y103307D02*
Y102913D01*
G01Y105275D02*
Y104882D01*
G01Y107244D02*
Y106850D01*
G01Y109212D02*
Y108819D01*
G01Y111181D02*
Y110787D01*
G01X658070Y111378D02*
X659331D01*
G01X658070Y110590D02*
X659331D01*
G01X658070Y109409D02*
X659331D01*
G01X658070Y108622D02*
X659331D01*
G01X658070Y107441D02*
X659331D01*
G01X658070Y106653D02*
X659331D01*
G01X658070Y105472D02*
X659331D01*
G01X658070Y104685D02*
X659331D01*
G01X658070Y103504D02*
X659331D01*
G01X658070Y102716D02*
X659331D01*
G01X658070Y101535D02*
X659331D01*
G01X658070Y100748D02*
X659331D01*
G01X658070Y99567D02*
X659331D01*
G01X658070Y98779D02*
X659331D01*
G01X658070Y97598D02*
X659331D01*
G01X658070Y96811D02*
X659331D01*
G01Y112559D02*
G03X659528Y112756I0J197D01*
G01Y113149D02*
G03X659331Y113346I-197J0D01*
G01Y114527D02*
G03X659528Y114724I0J197D01*
G01Y115118D02*
G03X659331Y115315I-197J0D01*
G01Y116496D02*
G03X659528Y116693I0J197D01*
G01Y117086D02*
G03X659331Y117283I-197J0D01*
G01Y118464D02*
G03X659528Y118661I0J197D01*
G01Y119055D02*
G03X659331Y119252I-197J0D01*
G01Y120433D02*
G03X659528Y120630I0J197D01*
G01Y121023D02*
G03X659331Y121220I-197J0D01*
G01Y122401D02*
G03X659528Y122598I0J197D01*
G01Y122992D02*
G03X659331Y123189I-197J0D01*
G01Y124370D02*
G03X659528Y124567I0J197D01*
G01Y124960D02*
G03X659331Y125157I-197J0D01*
G01Y126338D02*
G03X659528Y126535I0J197D01*
G01Y126929D02*
G03X659331Y127126I-197J0D01*
G01Y128307D02*
G03X659528Y128504I0J197D01*
G01X652243Y121732D02*
G03X653031Y122519I1J787D01*
G01X650694Y123976D02*
X650493Y123845D01*
G01X650293Y124108D02*
X650493Y124239D01*
G01X650829Y124108D02*
X650694Y123976D01*
G01X650493Y124239D02*
X650628Y124370D01*
G01X650761Y126601D02*
X650628Y126470D01*
G01X650426Y126732D02*
X650561Y126863D01*
G01X650896Y126798D02*
X650761Y126601D01*
G01X650896Y124239D02*
X650829Y124108D01*
G01X650561Y126863D02*
X650628Y126995D01*
G01X650963D02*
X650896Y126798D01*
G01X650963Y124501D02*
X650896Y124239D01*
G01X650628Y124370D02*
X650694Y124632D01*
G01X650628Y126995D02*
X650694Y127257D01*
G01X659528Y113149D02*
Y112756D01*
G01Y115118D02*
Y114724D01*
G01Y117086D02*
Y116693D01*
G01Y119055D02*
Y118661D01*
G01Y121023D02*
Y120630D01*
G01Y122992D02*
Y122598D01*
G01Y124960D02*
Y124567D01*
G01Y126929D02*
Y126535D01*
G01Y128897D02*
Y128504D01*
G01X653031Y122519D02*
Y142165D01*
G01X651968Y123189D02*
Y122861D01*
G01X650963Y125026D02*
Y124501D01*
G01Y127257D02*
Y126995D01*
G01Y128176D02*
Y127848D01*
G01X650896Y127519D02*
X650963Y127257D01*
G01X650694D02*
X650628Y127519D01*
G01X650493Y123845D02*
X650293Y123779D01*
G01X650694Y124632D02*
Y124895D01*
G01X650896Y125289D02*
X650963Y125026D01*
G01X650694Y124895D02*
X650628Y125157D01*
G01Y126470D02*
X650426Y126404D01*
G01X650829Y125420D02*
X650896Y125289D01*
G01X650761Y127716D02*
X650896Y127519D01*
G01X650628D02*
X650493Y127716D01*
G01X650628Y127848D02*
X650761Y127716D01*
G01X650493D02*
X650359Y127848D01*
G01X650694Y125551D02*
X650829Y125420D01*
G01X650628Y125157D02*
X650493Y125289D01*
G01Y125682D02*
X650694Y125551D01*
G01X650493Y125289D02*
X650293Y125420D01*
G01Y125748D02*
X650493Y125682D01*
G01X658070Y128307D02*
X659331D01*
G01X650963Y127848D02*
X650628D01*
G01X658070Y127126D02*
X659331D01*
G01X658070Y126338D02*
X659331D01*
G01X658070Y125157D02*
X659331D01*
G01X658070Y124370D02*
X659331D01*
G01X658070Y123189D02*
X659331D01*
G01X658070Y122401D02*
X659331D01*
G01X658070Y121220D02*
X659331D01*
G01X658070Y120433D02*
X659331D01*
G01X658070Y119252D02*
X659331D01*
G01X658070Y118464D02*
X659331D01*
G01X658070Y117283D02*
X659331D01*
G01X658070Y116496D02*
X659331D01*
G01X658070Y115315D02*
X659331D01*
G01X658070Y114527D02*
X659331D01*
G01X658070Y113346D02*
X659331D01*
G01X658070Y112559D02*
X659331D01*
G01X659528Y134803D02*
G03X659331Y135000I-197J0D01*
G01Y136181D02*
G03X659528Y136378I0J197D01*
G01Y136771D02*
G03X659331Y136968I-197J0D01*
G01Y138149D02*
G03X659528Y138346I0J197D01*
G01Y138740D02*
G03X659331Y138937I-197J0D01*
G01Y140118D02*
G03X659528Y140315I0J197D01*
G01Y140708D02*
G03X659331Y140905I-197J0D01*
G01X659528Y128897D02*
G03X659331Y129094I-197J0D01*
G01Y130275D02*
G03X659528Y130472I0J197D01*
G01Y130866D02*
G03X659331Y131063I-197J0D01*
G01Y132244D02*
G03X659528Y132441I0J197D01*
G01Y132834D02*
G03X659331Y133031I-197J0D01*
G01Y134212D02*
G03X659528Y134409I0J197D01*
G01X653031Y142165D02*
G03X652243Y142952I-787J0D01*
G01X650694Y128963D02*
X650426Y128766D01*
G01X650761Y131588D02*
X650628Y131456D01*
G01X650426Y131719D02*
X650561Y131850D01*
G01X650761Y134015D02*
X650561Y133819D01*
G01X650896Y136574D02*
X650761Y136443D01*
G01X650561Y136706D02*
X650628Y136771D01*
G01X650896Y137624D02*
X650694Y137428D01*
G01X650561Y137756D02*
X650628Y137821D01*
G01X650493Y129160D02*
X650628Y129357D01*
G01X650896Y131785D02*
X650761Y131588D01*
G01X650896Y134212D02*
X650761Y134015D01*
G01X650896Y129291D02*
X650694Y128963D01*
G01X650561Y131850D02*
X650628Y131982D01*
G01X650493Y134212D02*
X650628Y134475D01*
G01Y136771D02*
X650694Y136903D01*
G01X650628Y137821D02*
X650694Y137952D01*
G01X650963Y131982D02*
X650896Y131785D01*
G01X650963Y136771D02*
X650896Y136574D01*
G01X650963Y137821D02*
X650896Y137624D01*
G01X650628Y131982D02*
X650694Y132244D01*
G01X650963Y134475D02*
X650896Y134212D01*
G01X650963Y129685D02*
X650896Y129291D01*
G01X650628Y129357D02*
X650694Y129750D01*
G01X661023Y142480D02*
Y146614D01*
G01X659528Y130866D02*
Y130472D01*
G01Y132834D02*
Y132441D01*
G01Y134803D02*
Y134409D01*
G01Y136771D02*
Y136378D01*
G01Y138740D02*
Y138346D01*
G01Y140708D02*
Y140315D01*
G01X651968Y133163D02*
Y132834D01*
G01Y140840D02*
Y140315D01*
G01X650963Y132244D02*
Y131982D01*
G01Y134869D02*
Y134475D01*
G01Y135787D02*
Y135459D01*
G01Y137034D02*
Y136771D01*
G01Y138084D02*
Y137821D01*
G01Y138740D02*
Y138412D01*
G01X650896Y130078D02*
X650963Y129685D01*
G01X650896Y135131D02*
X650963Y134869D01*
G01X650628D02*
X650561Y135131D01*
G01X650896Y132506D02*
X650963Y132244D01*
G01X650694D02*
X650628Y132506D01*
G01X650694Y129750D02*
X650628Y130013D01*
G01Y131456D02*
X650493Y131391D01*
G01X650561Y133819D02*
X650426Y133753D01*
G01X650293Y129029D02*
X650493Y129160D01*
G01X650293Y134081D02*
X650493Y134212D01*
G01X650694Y137952D02*
Y138084D01*
G01Y136903D02*
Y137100D01*
G01X650628Y134475D02*
Y134869D01*
G01X650896Y138281D02*
X650963Y138084D01*
G01X650694D02*
X650628Y138281D01*
G01X650896Y137231D02*
X650963Y137034D01*
G01X650829Y130275D02*
X650896Y130078D01*
G01X650694Y137100D02*
X650628Y137231D01*
G01X650829Y135262D02*
X650896Y135131D01*
G01X650761Y136443D02*
X650426Y136312D01*
G01Y136640D02*
X650561Y136706D01*
G01X650426Y137690D02*
X650561Y137756D01*
G01X650628Y130013D02*
X650561Y130144D01*
G01Y135131D02*
X650426Y135328D01*
G01X650761Y132703D02*
X650896Y132506D01*
G01X650628D02*
X650493Y132703D01*
G01X650694Y130472D02*
X650829Y130275D01*
G01X650761Y138412D02*
X650896Y138281D01*
G01X650628D02*
X650493Y138412D01*
G01X650694Y137428D02*
X650896Y137231D01*
G01X650628D02*
X650561Y137296D01*
G01X650694Y135393D02*
X650829Y135262D01*
G01X650628Y132834D02*
X650761Y132703D01*
G01X650493D02*
X650359Y132834D01*
G01X650561Y130604D02*
X650694Y130472D01*
G01X650561Y130144D02*
X650359Y130341D01*
G01X650426Y135328D02*
X650226Y135459D01*
G01X650561Y137296D02*
X650426Y137362D01*
G01X650561Y135459D02*
X650694Y135393D01*
G01X650293Y130735D02*
X650561Y130604D01*
G01X650359Y130341D02*
X650226Y130407D01*
G01X661023Y144252D02*
X655708D01*
G01X661023Y143070D02*
X658070D01*
G01Y142480D02*
X661023D01*
G01X658070Y140905D02*
X659331D01*
G01X658070Y140118D02*
X659331D01*
G01X658070Y138937D02*
X659331D01*
G01X650963Y138412D02*
X650761D01*
G01X658070Y138149D02*
X659331D01*
G01X658070Y136968D02*
X659331D01*
G01X658070Y136181D02*
X659331D01*
G01X650963Y135459D02*
X650561D01*
G01X658070Y135000D02*
X659331D01*
G01X658070Y134212D02*
X659331D01*
G01X658070Y133031D02*
X659331D01*
G01X651968Y132834D02*
X650628D01*
G01X658070Y132244D02*
X659331D01*
G01X658070Y131063D02*
X659331D01*
G01X658070Y130275D02*
X659331D01*
G01X658070Y129094D02*
X659331D01*
G01X661023Y146614D02*
G03X660235Y147401I-787J0D01*
G01X659331Y175945D02*
G03X659528Y176141I0J197D01*
G01Y176535D02*
G03X659331Y176732I-197J0D01*
G01Y177913D02*
G03X659528Y178110I0J197D01*
G01X660235Y169448D02*
G03X661023Y170236I0J788D01*
G01D02*
Y174370D01*
G01X659528Y176535D02*
Y176141D01*
G01Y178504D02*
Y178110D01*
G01X658070Y252913D02*
Y172598D01*
G01X655708Y252913D02*
Y172598D01*
G01X658070Y177913D02*
X659331D01*
G01X658070Y176732D02*
X659331D01*
G01X658070Y175945D02*
X659331D01*
G01X658070Y174370D02*
X661023D01*
G01X658070Y173779D02*
X661023D01*
G01X655708Y172598D02*
X661023D01*
G01X659331Y179882D02*
G03X659528Y180078I0J197D01*
G01Y180472D02*
G03X659331Y180669I-197J0D01*
G01Y181850D02*
G03X659528Y182047I0J197D01*
G01Y182441D02*
G03X659331Y182637I-197J-1D01*
G01Y183819D02*
G03X659528Y184015I0J197D01*
G01Y184409D02*
G03X659331Y184606I-197J0D01*
G01Y193661D02*
G03X659528Y193858I0J197D01*
G01Y194252D02*
G03X659331Y194448I-197J-1D01*
G01X659528Y178504D02*
G03X659331Y178700I-197J-1D01*
G01X659528Y180472D02*
Y180078D01*
G01Y182441D02*
Y182047D01*
G01Y184409D02*
Y184015D01*
G01Y194252D02*
Y193858D01*
G01X658070Y194448D02*
X659331D01*
G01X658070Y193661D02*
X659331D01*
G01X658070Y184606D02*
X659331D01*
G01X658070Y183819D02*
X659331D01*
G01X658070Y182637D02*
X659331D01*
G01X658070Y181850D02*
X659331D01*
G01X658070Y180669D02*
X659331D01*
G01X658070Y179882D02*
X659331D01*
G01X658070Y178700D02*
X659331D01*
G01Y195630D02*
G03X659528Y195826I0J197D01*
G01Y196220D02*
G03X659331Y196417I-197J0D01*
G01Y197598D02*
G03X659528Y197795I0J197D01*
G01Y198189D02*
G03X659331Y198385I-197J-1D01*
G01Y199567D02*
G03X659528Y199763I0J197D01*
G01Y200157D02*
G03X659331Y200354I-197J0D01*
G01Y201535D02*
G03X659528Y201732I0J197D01*
G01Y202126D02*
G03X659331Y202322I-197J-1D01*
G01Y203504D02*
G03X659528Y203700I0J197D01*
G01Y204094D02*
G03X659331Y204291I-197J0D01*
G01Y205472D02*
G03X659528Y205669I0J197D01*
G01Y206063D02*
G03X659331Y206259I-197J-1D01*
G01Y207441D02*
G03X659528Y207637I0J197D01*
G01Y208031D02*
G03X659331Y208228I-197J0D01*
G01Y209409D02*
G03X659528Y209606I0J197D01*
G01Y210000D02*
G03X659331Y210196I-197J-1D01*
G01X659528Y196220D02*
Y195826D01*
G01Y198189D02*
Y197795D01*
G01Y200157D02*
Y199763D01*
G01Y202126D02*
Y201732D01*
G01Y204094D02*
Y203700D01*
G01Y206063D02*
Y205669D01*
G01Y208031D02*
Y207637D01*
G01Y210000D02*
Y209606D01*
G01X658070Y210196D02*
X659331D01*
G01X658070Y209409D02*
X659331D01*
G01X658070Y208228D02*
X659331D01*
G01X658070Y207441D02*
X659331D01*
G01X658070Y206259D02*
X659331D01*
G01X658070Y205472D02*
X659331D01*
G01X658070Y204291D02*
X659331D01*
G01X658070Y203504D02*
X659331D01*
G01X658070Y202322D02*
X659331D01*
G01X658070Y201535D02*
X659331D01*
G01X658070Y200354D02*
X659331D01*
G01X658070Y199567D02*
X659331D01*
G01X658070Y198385D02*
X659331D01*
G01X658070Y197598D02*
X659331D01*
G01X658070Y196417D02*
X659331D01*
G01X658070Y195630D02*
X659331D01*
G01Y221220D02*
G03X659528Y221417I0J197D01*
G01Y221811D02*
G03X659331Y222008I-197J0D01*
G01Y223189D02*
G03X659528Y223385I0J197D01*
G01Y223779D02*
G03X659331Y223976I-197J0D01*
G01Y225157D02*
G03X659528Y225354I0J197D01*
G01Y225748D02*
G03X659331Y225945I-197J0D01*
G01Y227126D02*
G03X659528Y227322I0J197D01*
G01Y227716D02*
G03X659331Y227913I-197J0D01*
G01X659528Y217874D02*
G03X659331Y218070I-197J-1D01*
G01Y219252D02*
G03X659528Y219448I0J197D01*
G01Y219842D02*
G03X659331Y220039I-197J0D01*
G01Y211378D02*
G03X659528Y211574I0J197D01*
G01Y211968D02*
G03X659331Y212165I-197J0D01*
G01Y213346D02*
G03X659528Y213543I0J197D01*
G01Y213937D02*
G03X659331Y214133I-197J-1D01*
G01Y215315D02*
G03X659528Y215511I0J197D01*
G01Y215905D02*
G03X659331Y216102I-197J0D01*
G01Y217283D02*
G03X659528Y217480I0J197D01*
G01Y211968D02*
Y211574D01*
G01Y213937D02*
Y213543D01*
G01Y215905D02*
Y215511D01*
G01Y217874D02*
Y217480D01*
G01Y221811D02*
Y221417D01*
G01Y219842D02*
Y219448D01*
G01Y223779D02*
Y223385D01*
G01Y225748D02*
Y225354D01*
G01Y227716D02*
Y227322D01*
G01X658070Y227126D02*
X659331D01*
G01X658070Y225945D02*
X659331D01*
G01X658070Y225157D02*
X659331D01*
G01X658070Y223976D02*
X659331D01*
G01X658070Y223189D02*
X659331D01*
G01X658070Y222008D02*
X659331D01*
G01X658070Y221220D02*
X659331D01*
G01X658070Y220039D02*
X659331D01*
G01X658070Y219252D02*
X659331D01*
G01X658070Y218070D02*
X659331D01*
G01X658070Y217283D02*
X659331D01*
G01X658070Y216102D02*
X659331D01*
G01X658070Y215315D02*
X659331D01*
G01X658070Y214133D02*
X659331D01*
G01X658070Y213346D02*
X659331D01*
G01X658070Y212165D02*
X659331D01*
G01X658070Y211378D02*
X659331D01*
G01Y229094D02*
G03X659528Y229291I0J197D01*
G01Y229685D02*
G03X659331Y229882I-197J0D01*
G01Y231063D02*
G03X659528Y231259I0J197D01*
G01Y231653D02*
G03X659331Y231850I-197J0D01*
G01Y233031D02*
G03X659528Y233228I0J197D01*
G01Y233622D02*
G03X659331Y233819I-197J0D01*
G01Y235000D02*
G03X659528Y235196I0J197D01*
G01Y235590D02*
G03X659331Y235787I-197J0D01*
G01Y236968D02*
G03X659528Y237165I0J197D01*
G01Y237559D02*
G03X659331Y237756I-197J0D01*
G01Y238937D02*
G03X659528Y239133I0J197D01*
G01Y239527D02*
G03X659331Y239724I-197J0D01*
G01Y240905D02*
G03X659528Y241102I0J197D01*
G01Y241496D02*
G03X659331Y241693I-197J0D01*
G01Y242874D02*
G03X659528Y243070I0J197D01*
G01Y243464D02*
G03X659331Y243661I-197J0D01*
G01X652243Y230393D02*
G03X653031Y231181I0J788D01*
G01X650829Y243924D02*
X650896Y243793D01*
G01X650561D02*
X650426Y243989D01*
G01X650896Y238740D02*
X650963Y238346D01*
G01X650896Y243793D02*
X650963Y243530D01*
G01X650628D02*
X650561Y243793D01*
G01X650896Y241168D02*
X650963Y240905D01*
G01X650694D02*
X650628Y241168D01*
G01X650694Y238412D02*
X650628Y238674D01*
G01X650896Y236181D02*
X650963Y235919D01*
G01X650694D02*
X650628Y236181D01*
G01X650896Y233950D02*
X650963Y233687D01*
G01X650694Y233556D02*
X650628Y233819D01*
G01X650829Y238937D02*
X650896Y238740D01*
G01X650628Y238674D02*
X650561Y238806D01*
G01X650829Y234081D02*
X650896Y233950D01*
G01X650761Y241365D02*
X650896Y241168D01*
G01X650628D02*
X650493Y241365D01*
G01X650694Y239133D02*
X650829Y238937D01*
G01X650761Y236378D02*
X650896Y236181D01*
G01X650628D02*
X650493Y236378D01*
G01X650694Y244055D02*
X650829Y243924D01*
G01X650628Y241496D02*
X650761Y241365D01*
G01X650493D02*
X650359Y241496D01*
G01X650561Y239265D02*
X650694Y239133D01*
G01X650561Y238806D02*
X650359Y239002D01*
G01X650628Y236509D02*
X650761Y236378D01*
G01X650493D02*
X650359Y236509D01*
G01X650694Y234212D02*
X650829Y234081D01*
G01X650628Y233819D02*
X650493Y233950D01*
G01X650426Y243989D02*
X650226Y244120D01*
G01X659528Y229685D02*
Y229291D01*
G01Y231653D02*
Y231259D01*
G01Y233622D02*
Y233228D01*
G01Y235590D02*
Y235196D01*
G01Y237559D02*
Y237165D01*
G01Y239527D02*
Y239133D01*
G01Y241496D02*
Y241102D01*
G01Y243464D02*
Y243070D01*
G01X653031Y231181D02*
Y250826D01*
G01X651968Y231850D02*
Y231522D01*
G01Y241824D02*
Y241496D01*
G01X650963Y233687D02*
Y233163D01*
G01Y235919D02*
Y235656D01*
G01Y236837D02*
Y236509D01*
G01Y240905D02*
Y240643D01*
G01Y243530D02*
Y243136D01*
G01Y244448D02*
Y244120D01*
G01X650493Y234344D02*
X650694Y234212D01*
G01X650493Y233950D02*
X650293Y234081D01*
G01X650561Y244120D02*
X650694Y244055D01*
G01X650293Y239396D02*
X650561Y239265D01*
G01X650359Y239002D02*
X650226Y239068D01*
G01X650963Y233163D02*
X650896Y232900D01*
G01X650628Y233031D02*
X650694Y233294D01*
G01X650628Y235656D02*
X650694Y235919D01*
G01X650963Y238346D02*
X650896Y237952D01*
G01X650628Y238018D02*
X650694Y238412D01*
G01Y233294D02*
Y233556D01*
G01X650628Y243136D02*
Y243530D01*
G01X650293Y234409D02*
X650493Y234344D01*
G01X650963Y235656D02*
X650896Y235459D01*
G01X650963Y240643D02*
X650896Y240446D01*
G01X650628Y240643D02*
X650694Y240905D01*
G01X650963Y243136D02*
X650896Y242874D01*
G01X650963Y244120D02*
X650561D01*
G01X658070Y243661D02*
X659331D01*
G01X658070Y242874D02*
X659331D01*
G01X658070Y241693D02*
X659331D01*
G01X651968Y241496D02*
X650628D01*
G01X658070Y240905D02*
X659331D01*
G01X658070Y239724D02*
X659331D01*
G01X658070Y238937D02*
X659331D01*
G01X658070Y237756D02*
X659331D01*
G01X658070Y236968D02*
X659331D01*
G01X650963Y236509D02*
X650628D01*
G01X658070Y235787D02*
X659331D01*
G01X658070Y235000D02*
X659331D01*
G01X650896Y235459D02*
X650761Y235262D01*
G01X650493Y237821D02*
X650628Y238018D01*
G01X650896Y237952D02*
X650694Y237624D01*
G01X650896Y232900D02*
X650829Y232769D01*
G01X650561Y235525D02*
X650628Y235656D01*
G01X650561Y240511D02*
X650628Y240643D01*
G01X650493Y242874D02*
X650628Y243136D01*
G01X658070Y233819D02*
X659331D01*
G01X658070Y233031D02*
X659331D01*
G01X658070Y231850D02*
X659331D01*
G01X658070Y231063D02*
X659331D01*
G01X658070Y229882D02*
X659331D01*
G01X658070Y229094D02*
X659331D01*
G01X658070Y227913D02*
X659331D01*
G01X650896Y240446D02*
X650761Y240249D01*
G01X650896Y242874D02*
X650761Y242677D01*
G01X650829Y232769D02*
X650694Y232637D01*
G01X650493Y232900D02*
X650628Y233031D01*
G01X650761Y235262D02*
X650628Y235131D01*
G01X650426Y235393D02*
X650561Y235525D01*
G01X650761Y240249D02*
X650628Y240118D01*
G01X650426Y240380D02*
X650561Y240511D01*
G01X650761Y242677D02*
X650561Y242480D01*
G01X650694Y232637D02*
X650493Y232506D01*
G01X650293Y232769D02*
X650493Y232900D01*
G01X650293Y237690D02*
X650493Y237821D01*
G01X650293Y242743D02*
X650493Y242874D01*
G01X650694Y237624D02*
X650426Y237428D01*
G01X650628Y240118D02*
X650493Y240052D01*
G01X650561Y242480D02*
X650426Y242415D01*
G01X650493Y232506D02*
X650293Y232441D01*
G01X650628Y235131D02*
X650426Y235065D01*
G01X659331Y244842D02*
G03X659528Y245039I0J197D01*
G01Y245433D02*
G03X659331Y245630I-197J0D01*
G01Y246811D02*
G03X659528Y247008I0J197D01*
G01Y247401D02*
G03X659331Y247598I-197J0D01*
G01Y248779D02*
G03X659528Y248976I0J197D01*
G01Y249370D02*
G03X659331Y249567I-197J0D01*
G01X653031Y250826D02*
G03X652243Y251614I-787J1D01*
G01X661023Y255275D02*
G03X660235Y256063I-787J1D01*
G01X650694Y245761D02*
X650628Y245892D01*
G01X650896Y246942D02*
X650963Y246745D01*
G01X650694D02*
X650628Y246942D01*
G01X650896Y245892D02*
X650963Y245695D01*
G01X650761Y247073D02*
X650896Y246942D01*
G01X650628D02*
X650493Y247073D01*
G01X650694Y246089D02*
X650896Y245892D01*
G01X650628D02*
X650561Y245958D01*
G01X661220Y265945D02*
Y257086D01*
G01X661023Y251141D02*
Y255275D01*
G01X659528Y245433D02*
Y245039D01*
G01Y247401D02*
Y247008D01*
G01Y249370D02*
Y248976D01*
G01X651968Y249501D02*
Y248976D01*
G01X650963Y245695D02*
Y245433D01*
G01Y246745D02*
Y246483D01*
G01Y247401D02*
Y247073D01*
G01X650561Y245958D02*
X650426Y246023D01*
G01X650694Y246614D02*
Y246745D01*
G01Y245564D02*
Y245761D01*
G01X661023Y252913D02*
X655708D01*
G01X661023Y251732D02*
X658070D01*
G01X650963Y245433D02*
X650896Y245236D01*
G01X650963Y246483D02*
X650896Y246286D01*
G01X658070Y251141D02*
X661023D01*
G01X658070Y249567D02*
X659331D01*
G01X658070Y248779D02*
X659331D01*
G01X658070Y247598D02*
X659331D01*
G01X650963Y247073D02*
X650761D01*
G01X658070Y246811D02*
X659331D01*
G01X658070Y245630D02*
X659331D01*
G01X658070Y244842D02*
X659331D01*
G01X650628Y245433D02*
X650694Y245564D01*
G01X650628Y246483D02*
X650694Y246614D01*
G01X650896Y245236D02*
X650761Y245105D01*
G01X650561Y245367D02*
X650628Y245433D01*
G01X650896Y246286D02*
X650694Y246089D01*
G01X650561Y246417D02*
X650628Y246483D01*
G01X650426Y245302D02*
X650561Y245367D01*
G01X650426Y246352D02*
X650561Y246417D01*
G01X650761Y245105D02*
X650426Y244974D01*
G01X667420Y345708D02*
G03X653445Y345709I-6988J0D01*
G03X667420Y345708I6987J-1D01*
G01D02*
G03X653445Y345709I-6988J0D01*
G03X667420Y345708I6987J-1D01*
G01D02*
G03X653445Y345709I-6988J0D01*
G03X667420Y345708I6987J-1D01*
G01X660433Y352697D02*
G03Y338720I0J-6988D01*
G01D02*
G03Y352697I0J6989D01*
G01X667322Y-105354D02*
Y-7874D01*
G01X712597Y-58110D02*
G03X681101Y-58111I-15748J0D01*
G03X712597Y-58110I15748J1D01*
G01D02*
G03X681101Y-58111I-15748J0D01*
G03X712597Y-58110I15748J1D01*
G01X675196Y25708D02*
G03X676377Y24527I1181J0D01*
G01X683661Y34429D02*
G03Y29311I0J-2559D01*
G01X680708Y36574D02*
Y27126D01*
G01X675196Y41653D02*
Y25708D01*
G01X690157Y27126D02*
X680708D01*
G01X676377Y24527D02*
X692311D01*
G01X676569Y22834D02*
X685231D01*
G01X676377Y42834D02*
G03X675196Y41653I0J-1181D01*
G01X683661Y33248D02*
G03Y30492I0J-1378D01*
G01Y33641D02*
G03Y30098I0J-1772D01*
G01X680837Y46929D02*
Y45354D01*
G01X679920Y35737D02*
Y39674D01*
G01X675983D02*
Y35737D01*
G01X680837Y45354D02*
X685578D01*
G01X676377Y42834D02*
X692285D01*
G01X675983Y39674D02*
X679920D01*
G01X690157Y36574D02*
X680708D01*
G01X675983Y35737D02*
X679920D01*
G01X680837Y51929D02*
Y50354D01*
G01Y56929D02*
Y55354D01*
G01Y61929D02*
Y60354D01*
G01Y61929D02*
X685578D01*
G01X680837Y60354D02*
X685578D01*
G01X680837Y56929D02*
X685578D01*
G01X680837Y55354D02*
X685578D01*
G01X680837Y51929D02*
X685578D01*
G01X680837Y50354D02*
X685578D01*
G01X680837Y46929D02*
X685578D01*
G01X680837Y66929D02*
Y65354D01*
G01Y71929D02*
Y70354D01*
G01Y76929D02*
Y75354D01*
G01Y76929D02*
X685578D01*
G01X680837Y75354D02*
X685578D01*
G01X680837Y71929D02*
X685578D01*
G01X680837Y70354D02*
X685578D01*
G01X680837Y66929D02*
X685578D01*
G01X680837Y65354D02*
X685578D01*
G01X680837Y81929D02*
Y80354D01*
G01Y86929D02*
Y85354D01*
G01Y91929D02*
Y90354D01*
G01Y96929D02*
Y95354D01*
G01D02*
X685578D01*
G01X680837Y91929D02*
X685578D01*
G01X680837Y90354D02*
X685578D01*
G01X680837Y86929D02*
X685578D01*
G01X680837Y85354D02*
X685578D01*
G01X680837Y81929D02*
X685578D01*
G01X680837Y80354D02*
X685578D01*
G01X680837Y101929D02*
Y100354D01*
G01Y106929D02*
Y105354D01*
G01Y111929D02*
Y110354D01*
G01Y111929D02*
X685578D01*
G01X680837Y110354D02*
X685578D01*
G01X680837Y106929D02*
X685578D01*
G01X680837Y105354D02*
X685578D01*
G01X680837Y101929D02*
X685578D01*
G01X680837Y100354D02*
X685578D01*
G01X680837Y96929D02*
X685578D01*
G01X682041Y115916D02*
X682001Y115876D01*
G01X682100Y115836D02*
X682159Y115916D01*
G01D02*
X682178Y115976D01*
G01X682060D02*
X682041Y115916D01*
G01X682021Y115775D02*
X682100Y115836D01*
G01X682910Y121102D02*
Y120236D01*
G01Y124252D02*
Y123385D01*
G01Y127401D02*
Y126535D01*
G01X682572Y115755D02*
Y116700D01*
G01X682454D02*
Y115916D01*
G01X682336Y116057D02*
Y115896D01*
G01X682178Y115976D02*
Y116057D01*
G01X682060Y116037D02*
Y115976D01*
G01X681568Y115856D02*
Y116158D01*
G01Y116278D02*
Y116700D01*
G01X681450D02*
Y115755D01*
G01X680837Y116929D02*
Y115354D01*
G01X680750Y126535D02*
Y127401D01*
G01Y123385D02*
Y124252D01*
G01Y120236D02*
Y121102D01*
G01X682178Y116057D02*
X682159Y116117D01*
G01X682041Y116097D02*
X682060Y116037D01*
G01X682001Y115876D02*
X681942Y115856D01*
G01X682159Y116117D02*
X682100Y116198D01*
G01X682454Y115916D02*
X682336Y116057D01*
G01Y115896D02*
X682454Y115755D01*
G01X682001Y116137D02*
X682041Y116097D01*
G01X682100Y116198D02*
X682021Y116258D01*
G01X681942Y116158D02*
X682001Y116137D01*
G01X682021Y116258D02*
X681922Y116278D01*
G01X680750Y127401D02*
X685431D01*
G01Y126535D02*
X680751D01*
G01X680750Y124252D02*
X685431D01*
G01Y123385D02*
X680751D01*
G01X680750Y121102D02*
X685431D01*
G01Y120236D02*
X680751D01*
G01X680837Y116929D02*
X685578D01*
G01X682572Y116700D02*
X682454D01*
G01X681568D02*
X681450D01*
G01X681922Y116278D02*
X681568D01*
G01Y116158D02*
X681942D01*
G01Y115856D02*
X681568D01*
G01X682454Y115755D02*
X682572D01*
G01X681450D02*
X681922D01*
G01X680837Y115354D02*
X685578D01*
G01X681922Y115755D02*
X682021Y115775D01*
G01X682910Y130551D02*
Y129685D01*
G01Y133700D02*
Y132834D01*
G01Y136850D02*
Y135984D01*
G01X681673Y136157D02*
Y136669D01*
G01X681609D02*
Y136244D01*
G01X681545Y136320D02*
Y136233D01*
G01X681459Y136157D02*
Y136222D01*
G01Y136603D02*
Y136669D01*
G01X681417Y136363D02*
Y136429D01*
G01X681140D02*
Y136603D01*
G01Y136222D02*
Y136363D01*
G01X681076Y136669D02*
Y136157D01*
G01X680837Y141929D02*
Y140354D01*
G01X680750Y135984D02*
Y136850D01*
G01Y132834D02*
Y133700D01*
G01Y129685D02*
Y130551D01*
G01X681609Y136244D02*
X681545Y136320D01*
G01Y136233D02*
X681609Y136157D01*
G01X680837Y141929D02*
X685578D01*
G01X680837Y140354D02*
X685578D01*
G01X680750Y136850D02*
X685431D01*
G01X681459Y136669D02*
X681076D01*
G01X681673D02*
X681609D01*
G01X681140Y136603D02*
X681459D01*
G01X681417Y136429D02*
X681140D01*
G01Y136363D02*
X681417D01*
G01X681459Y136222D02*
X681140D01*
G01X681076Y136157D02*
X681459D01*
G01X681609D02*
X681673D01*
G01X685431Y135984D02*
X680751D01*
G01X680750Y133700D02*
X685431D01*
G01Y132834D02*
X680751D01*
G01X680750Y130551D02*
X685431D01*
G01Y129685D02*
X680751D01*
G01X680837Y146929D02*
Y145354D01*
G01Y151929D02*
Y150354D01*
G01Y156929D02*
Y155354D01*
G01Y161929D02*
Y160354D01*
G01D02*
X685578D01*
G01X680837Y156929D02*
X685578D01*
G01X680837Y155354D02*
X685578D01*
G01X680837Y151929D02*
X685578D01*
G01X680837Y150354D02*
X685578D01*
G01X680837Y146929D02*
X685578D01*
G01X680837Y145354D02*
X685578D01*
G01X675196Y175630D02*
G03X676377Y174448I1181J-1D01*
G01X681371Y170827D02*
X681351Y170907D01*
G01X681469Y170928D02*
X681489Y170867D01*
G01X681312Y171450D02*
X681371Y171551D01*
G01X681824Y170867D02*
X681843Y170907D01*
G01X682020Y171309D02*
X681981Y171229D01*
G01X681961Y170907D02*
X681942Y170847D01*
G01X681489Y171028D02*
X681469Y170968D01*
G01X681430Y171430D02*
X681410Y171370D01*
G01X681351Y170988D02*
X681371Y171068D01*
G01X681292Y171370D02*
X681312Y171450D01*
G01X682414Y170686D02*
Y171631D01*
G01X682296D02*
Y170847D01*
G01X682178Y170988D02*
Y170827D01*
G01X682020Y171410D02*
Y171309D01*
G01X681902Y171330D02*
Y171390D01*
G01X681469Y170968D02*
Y170928D01*
G01X681351Y170907D02*
Y170988D01*
G01X680837Y166929D02*
Y165354D01*
G01Y171929D02*
Y170354D01*
G01X679920Y175236D02*
Y179173D01*
G01X675983D02*
Y175236D01*
G01X675196Y175630D02*
Y191574D01*
G01X681981Y171490D02*
X682020Y171410D01*
G01X681902Y171390D02*
X681863Y171450D01*
G01X681784Y170827D02*
X681824Y170867D01*
G01X681981Y171229D02*
X681902Y171148D01*
G01X681942Y170847D02*
X681883Y170767D01*
G01X681863Y171269D02*
X681902Y171330D01*
G01X682296Y170847D02*
X682178Y170988D01*
G01Y170827D02*
X682296Y170686D01*
G01X681902Y171571D02*
X681981Y171490D01*
G01X681450Y170746D02*
X681371Y170827D01*
G01X681883Y170767D02*
X681804Y170706D01*
G01X681371Y171068D02*
X681450Y171148D01*
G01X681489Y171490D02*
X681430Y171430D01*
G01X681902Y171148D02*
X681824Y171108D01*
G01X681450Y171148D02*
X681528Y171189D01*
G01X681371Y171551D02*
X681469Y171611D01*
G01X681804Y171229D02*
X681863Y171269D01*
G01X681548Y171068D02*
X681489Y171028D01*
G01X681863Y171450D02*
X681804Y171490D01*
G01X681489Y170867D02*
X681548Y170827D01*
G01X681725Y170807D02*
X681784Y170827D01*
G01X681607Y171088D02*
X681548Y171068D01*
G01X681824Y171611D02*
X681902Y171571D01*
G01X681528Y170706D02*
X681450Y170746D01*
G01X681548Y170827D02*
X681607Y170807D01*
G01X681804Y171490D02*
X681725Y171510D01*
G01X681607Y170686D02*
X681528Y170706D01*
G01X681725Y171631D02*
X681824Y171611D01*
G01X675983Y175236D02*
X679920D01*
G01X692311Y174448D02*
X676377D01*
G01X680837Y171929D02*
X685578D01*
G01X681568Y171631D02*
X681725D01*
G01X682414D02*
X682296D01*
G01X681725Y171510D02*
X681568D01*
G01X681410Y171370D02*
X681292D01*
G01X681607Y171209D02*
X681725D01*
G01Y171088D02*
X681607D01*
G01X681843Y170907D02*
X681961D01*
G01X681607Y170807D02*
X681725D01*
G01X682296Y170686D02*
X682414D01*
G01X681706D02*
X681607D01*
G01X680837Y170354D02*
X685578D01*
G01X680837Y166929D02*
X685578D01*
G01X680837Y165354D02*
X685578D01*
G01X680837Y161929D02*
X685578D01*
G01X681469Y171611D02*
X681568Y171631D01*
G01X681824Y171108D02*
X681725Y171088D01*
G01X681804Y170706D02*
X681706Y170686D01*
G01X681568Y171510D02*
X681489Y171490D01*
G01X681528Y171189D02*
X681607Y171209D01*
G01X681725D02*
X681804Y171229D01*
G01X687204Y185413D02*
G03X682086I-2559J0D01*
G03X687204I2559J0D01*
G01X687598D02*
G03X681692I-2953J0D01*
G03X687598I2953J0D01*
G01X687864D02*
G03X681426I-3219J0D01*
G03X687864I3219J0D01*
G01X676377Y192756D02*
G03X675196Y191574I0J-1181D01*
G01X680708Y180689D02*
Y190137D01*
G01X676377Y192756D02*
X692285D01*
G01X680708Y190137D02*
X690157D01*
G01X681426Y185413D02*
X682086D01*
G01X680708Y180689D02*
X690157D01*
G01X679920Y179173D02*
X675983D01*
G01X683652Y-113228D02*
G03Y-105354I0J3937D01*
G01X703837Y-58110D02*
G03X689861Y-58111I-6988J0D01*
G03X703837Y-58110I6988J1D01*
G01D02*
G03X689861Y-58111I-6988J0D01*
G03X703837Y-58110I6988J1D01*
G01D02*
G03X689861Y-58111I-6988J0D01*
G03X703837Y-58110I6988J1D01*
G01X696849Y-65098D02*
G03Y-51122I0J6988D01*
G01D02*
G03Y-65098I0J-6988D01*
G01X683652Y-7874D02*
G03Y0I0J3937D01*
G01X685231Y22834D02*
Y0D01*
G01X692125Y25334D02*
G03X694094Y23366I1969J1D01*
G01X692125Y25334D02*
G03X694094Y23366I1969J1D01*
G01X685629Y29311D02*
G03Y34429I0J2559D01*
G01X692125Y25334D02*
G03X694094Y23366I1969J1D01*
G01X692125Y25334D02*
G03X694094Y23366I1969J1D01*
G01X698976Y18031D02*
Y19212D01*
G01X698424Y23366D02*
Y13700D01*
G01Y24527D02*
Y23366D01*
G01X698385Y18031D02*
Y19212D01*
G01X695669Y39059D02*
Y27677D01*
G01X693306Y40078D02*
Y27283D01*
G01X692519Y24527D02*
Y42834D01*
G01Y24216D02*
Y24527D01*
G01Y13700D02*
Y24216D01*
G01X692125Y25334D02*
Y42067D01*
G01Y25334D02*
Y42067D01*
G01X690550Y42834D02*
Y24527D01*
G01X690157Y27126D02*
Y36574D01*
G01X685629Y29311D02*
Y30492D01*
G01X683661Y29311D02*
Y30492D01*
G01X693306Y27283D02*
X696062Y24527D01*
G01X685629Y29311D02*
X683661D01*
G01X695669Y28858D02*
X722440D01*
G01X695669Y28464D02*
X692519D01*
G01X695669Y27677D02*
X720394D01*
G01X692311Y24527D02*
X722440D01*
G01X694094Y23366D02*
X720472D01*
G01X694094D02*
X720472D01*
G01X722440Y22559D02*
X692519D01*
G01Y20433D02*
X722440D01*
G01X692519Y19842D02*
X722440D01*
G01X692519Y19252D02*
X722440D01*
G01X698385Y19212D02*
X716180D01*
G01X698385Y18031D02*
X716180D01*
G01X692519Y17992D02*
X722440D01*
G01X702361Y17401D02*
X692519D01*
G01X702361Y16811D02*
X692519D01*
G01X702361Y13700D02*
X692519D01*
G01X692125Y25334D02*
Y363425D01*
G01Y25334D02*
Y42067D01*
G01X694094Y23366D02*
X720472D01*
G01X694094D02*
X720472D01*
G01X692125Y25335D02*
Y42067D01*
G01X692124Y25335D02*
G03X694094Y23366I1969J0D01*
G01X720472D02*
X694094D01*
G01X691082Y44790D02*
X691108Y44821D01*
G01X691052Y44770D02*
X691082Y44790D01*
G01X691019Y44763D02*
X691052Y44770D01*
G01X690686Y45328D02*
X690660Y45296D01*
G01X690717Y45347D02*
X690686Y45328D01*
G01X690749Y45354D02*
X690717Y45347D01*
G01X685245Y44790D02*
X685219Y44821D01*
G01X685276Y44770D02*
X685245Y44790D01*
G01X685309Y44763D02*
X685276Y44770D01*
G01X685641Y45328D02*
X685667Y45296D01*
G01X685611Y45347D02*
X685641Y45328D01*
G01X685578Y45354D02*
X685611Y45347D01*
G01X684857D02*
X684824Y45354D01*
G01X684887Y45328D02*
X684857Y45347D01*
G01X684913Y45296D02*
X684887Y45328D01*
G01X686030Y44770D02*
X686063Y44763D01*
G01X685999Y44790D02*
X686030Y44770D01*
G01X685973Y44821D02*
X685999Y44790D01*
G01X690298Y44770D02*
X690265Y44763D01*
G01X690328Y44790D02*
X690298Y44770D01*
G01X690354Y44821D02*
X690328Y44790D01*
G01X691470Y45347D02*
X691504Y45354D01*
G01X691440Y45328D02*
X691470Y45347D01*
G01X691414Y45296D02*
X691440Y45328D01*
G01X698857Y46082D02*
G03X698480Y46161I-197J0D01*
G01X699212Y44035D02*
G03X701180Y46004I0J1968D01*
G01X699212Y44035D02*
G03X701180Y46004I0J1968D01*
G01X693498Y45157D02*
G03X693302Y45354I-197J0D01*
G01X694094Y44035D02*
G03X692125Y42067I0J-1969D01*
G01X693667Y43950D02*
G03X693306Y42815I1608J-1136D01*
G01X694094Y44035D02*
G03X692125Y42067I0J-1969D01*
G01X695275Y44783D02*
G03X693667Y43950I0J-1968D01*
G01X685629Y30492D02*
G03Y33248I0J1378D01*
G01Y30098D02*
G03Y33641I0J1771D01*
G01X699212Y44035D02*
G03X701180Y46004I0J1968D01*
G01X699212Y44035D02*
G03X701180Y46004I0J1968D01*
G01X694094Y44035D02*
G03X692125Y42067I0J-1969D01*
G01X694094Y44035D02*
G03X692125Y42067I0J-1969D01*
G01X695669Y39059D02*
X703149Y42547D01*
G01X696062Y42834D02*
X693306Y40078D01*
G01X691108Y44821D02*
X691414Y45296D01*
G01X690660D02*
X690354Y44821D01*
G01X699054Y44035D02*
Y173287D01*
G01Y42834D02*
Y44035D01*
G01X698857Y45554D02*
Y46082D01*
G01X698249Y47342D02*
Y46161D01*
G01X697397D02*
Y47342D01*
G01X696850Y44035D02*
Y173287D01*
G01Y44035D02*
Y42834D01*
G01X696715Y47342D02*
Y46161D01*
G01X693498Y44173D02*
Y45157D01*
G01X692711Y46929D02*
Y45354D01*
G01X691957Y46929D02*
Y45354D01*
G01X691203D02*
Y46929D01*
G01X685629Y34429D02*
Y33248D01*
G01X685100Y45354D02*
Y46929D01*
G01X684346D02*
Y45354D01*
G01X683661Y33248D02*
Y34429D01*
G01X683593Y46929D02*
Y45354D01*
G01X695758Y46319D02*
X695837Y46161D01*
G01X695155D02*
X695076Y46319D01*
G01X685667Y45296D02*
X685973Y44821D01*
G01X685219D02*
X684913Y45296D01*
G01X695155Y46161D02*
X698480D01*
G01X699054Y45554D02*
X698857D01*
G01X690749Y45354D02*
X693302D01*
G01X684913Y45296D02*
X685667D01*
G01X691414D02*
X690660D01*
G01X690354Y44821D02*
X691108D01*
G01X685973D02*
X685219D01*
G01X691019Y44763D02*
X685309D01*
G01X693498Y44173D02*
X696850D01*
G01X699212Y44035D02*
X694094D01*
G01X699212D02*
X694094D01*
G01X692285Y42834D02*
X721259D01*
G01X683661Y34429D02*
X685629D01*
G01Y33641D02*
X683661D01*
G01Y33248D02*
X685629D01*
G01X722440Y32795D02*
X695669D01*
G01X722440Y31614D02*
X695669D01*
G01X685629Y30492D02*
X683661D01*
G01Y30098D02*
X685629D01*
G01X699212Y44035D02*
X694094D01*
G01X699212D02*
X694094D01*
G01X699212D02*
G03X701181Y46004I0J1969D01*
G01X694094Y44035D02*
X699212D01*
G01X694094D02*
G03X692125Y42067I0J-1969D01*
G01X684887Y46955D02*
X684913Y46987D01*
G01X684857Y46935D02*
X684887Y46955D01*
G01X684824Y46929D02*
X684857Y46935D01*
G01X685999Y47493D02*
X685973Y47462D01*
G01X686030Y47513D02*
X685999Y47493D01*
G01X686063Y47519D02*
X686030Y47513D01*
G01X691082Y49790D02*
X691108Y49821D01*
G01X691052Y49770D02*
X691082Y49790D01*
G01X691019Y49763D02*
X691052Y49770D01*
G01X690686Y50328D02*
X690660Y50296D01*
G01X690717Y50347D02*
X690686Y50328D01*
G01X690749Y50354D02*
X690717Y50347D01*
G01X684887Y51955D02*
X684913Y51987D01*
G01X684857Y51935D02*
X684887Y51955D01*
G01X684824Y51929D02*
X684857Y51935D01*
G01X685999Y52493D02*
X685973Y52462D01*
G01X686030Y52513D02*
X685999Y52493D01*
G01X686063Y52519D02*
X686030Y52513D01*
G01X691082Y54790D02*
X691108Y54821D01*
G01X691052Y54770D02*
X691082Y54790D01*
G01X691019Y54763D02*
X691052Y54770D01*
G01X690686Y55328D02*
X690660Y55296D01*
G01X690717Y55347D02*
X690686Y55328D01*
G01X690749Y55354D02*
X690717Y55347D01*
G01X684887Y56955D02*
X684913Y56987D01*
G01X684857Y56935D02*
X684887Y56955D01*
G01X684824Y56929D02*
X684857Y56935D01*
G01X685999Y57493D02*
X685973Y57462D01*
G01X686030Y57513D02*
X685999Y57493D01*
G01X686063Y57519D02*
X686030Y57513D01*
G01X691082Y59790D02*
X691108Y59821D01*
G01X691052Y59770D02*
X691082Y59790D01*
G01X691019Y59763D02*
X691052Y59770D01*
G01X690686Y60328D02*
X690660Y60296D01*
G01X690717Y60347D02*
X690686Y60328D01*
G01X690749Y60354D02*
X690717Y60347D01*
G01X684887Y61955D02*
X684913Y61987D01*
G01X684857Y61935D02*
X684887Y61955D01*
G01X684824Y61929D02*
X684857Y61935D01*
G01X685999Y62493D02*
X685973Y62462D01*
G01X686030Y62513D02*
X685999Y62493D01*
G01X686063Y62519D02*
X686030Y62513D01*
G01X691440Y46955D02*
X691414Y46987D01*
G01X691470Y46935D02*
X691440Y46955D01*
G01X691504Y46929D02*
X691470Y46935D01*
G01X690328Y47493D02*
X690354Y47462D01*
G01X690298Y47513D02*
X690328Y47493D01*
G01X690265Y47519D02*
X690298Y47513D01*
G01X685245Y49790D02*
X685219Y49821D01*
G01X685276Y49770D02*
X685245Y49790D01*
G01X685309Y49763D02*
X685276Y49770D01*
G01X685641Y50328D02*
X685667Y50296D01*
G01X685611Y50347D02*
X685641Y50328D01*
G01X685578Y50354D02*
X685611Y50347D01*
G01X691440Y51955D02*
X691414Y51987D01*
G01X691470Y51935D02*
X691440Y51955D01*
G01X691504Y51929D02*
X691470Y51935D01*
G01X690328Y52493D02*
X690354Y52462D01*
G01X690298Y52513D02*
X690328Y52493D01*
G01X690265Y52519D02*
X690298Y52513D01*
G01X685245Y54790D02*
X685219Y54821D01*
G01X685276Y54770D02*
X685245Y54790D01*
G01X685309Y54763D02*
X685276Y54770D01*
G01X685641Y55328D02*
X685667Y55296D01*
G01X685611Y55347D02*
X685641Y55328D01*
G01X685578Y55354D02*
X685611Y55347D01*
G01X691440Y56955D02*
X691414Y56987D01*
G01X691470Y56935D02*
X691440Y56955D01*
G01X691504Y56929D02*
X691470Y56935D01*
G01X690328Y57493D02*
X690354Y57462D01*
G01X690298Y57513D02*
X690328Y57493D01*
G01X690265Y57519D02*
X690298Y57513D01*
G01X685245Y59790D02*
X685219Y59821D01*
G01X685276Y59770D02*
X685245Y59790D01*
G01X685309Y59763D02*
X685276Y59770D01*
G01X685641Y60328D02*
X685667Y60296D01*
G01X685611Y60347D02*
X685641Y60328D01*
G01X685578Y60354D02*
X685611Y60347D01*
G01X691440Y61955D02*
X691414Y61987D01*
G01X691470Y61935D02*
X691440Y61955D01*
G01X691504Y61929D02*
X691470Y61935D01*
G01X690328Y62493D02*
X690354Y62462D01*
G01X690298Y62513D02*
X690328Y62493D01*
G01X690265Y62519D02*
X690298Y62513D01*
G01X684857Y50347D02*
X684824Y50354D01*
G01X684887Y50328D02*
X684857Y50347D01*
G01X684913Y50296D02*
X684887Y50328D01*
G01X686030Y49770D02*
X686063Y49763D01*
G01X685999Y49790D02*
X686030Y49770D01*
G01X685973Y49821D02*
X685999Y49790D01*
G01X690717Y46935D02*
X690749Y46929D01*
G01X690686Y46955D02*
X690717Y46935D01*
G01X690660Y46987D02*
X690686Y46955D01*
G01X691052Y47513D02*
X691019Y47519D01*
G01X691082Y47493D02*
X691052Y47513D01*
G01X691108Y47462D02*
X691082Y47493D01*
G01X684857Y55347D02*
X684824Y55354D01*
G01X684887Y55328D02*
X684857Y55347D01*
G01X684913Y55296D02*
X684887Y55328D01*
G01X686030Y54770D02*
X686063Y54763D01*
G01X685999Y54790D02*
X686030Y54770D01*
G01X685973Y54821D02*
X685999Y54790D01*
G01X690717Y51935D02*
X690749Y51929D01*
G01X690686Y51955D02*
X690717Y51935D01*
G01X690660Y51987D02*
X690686Y51955D01*
G01X691052Y52513D02*
X691019Y52519D01*
G01X691082Y52493D02*
X691052Y52513D01*
G01X691108Y52462D02*
X691082Y52493D01*
G01X684857Y60347D02*
X684824Y60354D01*
G01X684887Y60328D02*
X684857Y60347D01*
G01X684913Y60296D02*
X684887Y60328D01*
G01X686030Y59770D02*
X686063Y59763D01*
G01X685999Y59790D02*
X686030Y59770D01*
G01X685973Y59821D02*
X685999Y59790D01*
G01X690717Y56935D02*
X690749Y56929D01*
G01X690686Y56955D02*
X690717Y56935D01*
G01X690660Y56987D02*
X690686Y56955D01*
G01X691052Y57513D02*
X691019Y57519D01*
G01X691082Y57493D02*
X691052Y57513D01*
G01X691108Y57462D02*
X691082Y57493D01*
G01X690717Y61935D02*
X690749Y61929D01*
G01X690686Y61955D02*
X690717Y61935D01*
G01X690660Y61987D02*
X690686Y61955D01*
G01X691052Y62513D02*
X691019Y62519D01*
G01X691082Y62493D02*
X691052Y62513D01*
G01X691108Y62462D02*
X691082Y62493D01*
G01X685276Y62513D02*
X685309Y62519D01*
G01X685245Y62493D02*
X685276Y62513D01*
G01X685219Y62462D02*
X685245Y62493D01*
G01X685611Y61935D02*
X685578Y61929D01*
G01X685641Y61955D02*
X685611Y61935D01*
G01X685667Y61987D02*
X685641Y61955D01*
G01X685276Y57513D02*
X685309Y57519D01*
G01X685245Y57493D02*
X685276Y57513D01*
G01X685219Y57462D02*
X685245Y57493D01*
G01X685611Y56935D02*
X685578Y56929D01*
G01X685641Y56955D02*
X685611Y56935D01*
G01X685667Y56987D02*
X685641Y56955D01*
G01X690298Y59770D02*
X690265Y59763D01*
G01X690328Y59790D02*
X690298Y59770D01*
G01X690354Y59821D02*
X690328Y59790D01*
G01X691470Y60347D02*
X691504Y60354D01*
G01X691440Y60328D02*
X691470Y60347D01*
G01X691414Y60296D02*
X691440Y60328D01*
G01X685276Y52513D02*
X685309Y52519D01*
G01X685245Y52493D02*
X685276Y52513D01*
G01X685219Y52462D02*
X685245Y52493D01*
G01X685611Y51935D02*
X685578Y51929D01*
G01X685641Y51955D02*
X685611Y51935D01*
G01X685667Y51987D02*
X685641Y51955D01*
G01X690298Y54770D02*
X690265Y54763D01*
G01X690328Y54790D02*
X690298Y54770D01*
G01X690354Y54821D02*
X690328Y54790D01*
G01X691470Y55347D02*
X691504Y55354D01*
G01X691440Y55328D02*
X691470Y55347D01*
G01X691414Y55296D02*
X691440Y55328D01*
G01X685276Y47513D02*
X685309Y47519D01*
G01X685245Y47493D02*
X685276Y47513D01*
G01X685219Y47462D02*
X685245Y47493D01*
G01X685611Y46935D02*
X685578Y46929D01*
G01X685641Y46955D02*
X685611Y46935D01*
G01X685667Y46987D02*
X685641Y46955D01*
G01X690298Y49770D02*
X690265Y49763D01*
G01X690328Y49790D02*
X690298Y49770D01*
G01X690354Y49821D02*
X690328Y49790D01*
G01X691470Y50347D02*
X691504Y50354D01*
G01X691440Y50328D02*
X691470Y50347D01*
G01X691414Y50296D02*
X691440Y50328D01*
G01X698480Y59941D02*
G03X698857Y60020I180J79D01*
G01Y58681D02*
G03X698480Y58759I-197J-1D01*
G01X698857Y61830D02*
G03X698480Y61909I-197J0D01*
G01Y56791D02*
G03X698857Y56870I180J79D01*
G01X693302Y56929D02*
G03X693498Y57126I-1J197D01*
G01Y60157D02*
G03X693302Y60354I-197J0D01*
G01Y61929D02*
G03X693498Y62126I-1J197D01*
G01X698480Y50492D02*
G03X698857Y50571I180J79D01*
G01Y49232D02*
G03X698480Y49311I-197J0D01*
G01Y53641D02*
G03X698857Y53720I180J79D01*
G01Y52382D02*
G03X698480Y52460I-197J-1D01*
G01X698857Y55531D02*
G03X698480Y55610I-197J0D01*
G01Y47342D02*
G03X698857Y47421I180J79D01*
G01X693302Y46929D02*
G03X693498Y47126I-1J197D01*
G01Y50157D02*
G03X693302Y50354I-197J0D01*
G01Y51929D02*
G03X693498Y52126I-1J197D01*
G01Y55157D02*
G03X693302Y55354I-197J0D01*
G01X691108Y49821D02*
X691414Y50296D01*
G01X690660D02*
X690354Y49821D01*
G01X691108Y54821D02*
X691414Y55296D01*
G01X685973Y47462D02*
X685667Y46987D01*
G01X690660Y55296D02*
X690354Y54821D01*
G01X684913Y46987D02*
X685219Y47462D01*
G01X695837Y47342D02*
X695758Y47185D01*
G01X695076D02*
X695155Y47342D01*
G01X695837Y50492D02*
X695758Y50334D01*
G01X695076D02*
X695155Y50492D01*
G01X695837Y53641D02*
X695758Y53484D01*
G01X695076D02*
X695155Y53641D01*
G01X695837Y56791D02*
X695758Y56633D01*
G01X695076D02*
X695155Y56791D01*
G01X691108Y59821D02*
X691414Y60296D01*
G01X685973Y52462D02*
X685667Y51987D01*
G01X690660Y60296D02*
X690354Y59821D01*
G01X684913Y51987D02*
X685219Y52462D01*
G01X685973Y57462D02*
X685667Y56987D01*
G01X684913D02*
X685219Y57462D01*
G01X685973Y62462D02*
X685667Y61987D01*
G01X684913D02*
X685219Y62462D01*
G01X695837Y59941D02*
X695758Y59783D01*
G01X695076D02*
X695155Y59941D01*
G01X698857Y61302D02*
Y61830D01*
G01Y60020D02*
Y60539D01*
G01Y58153D02*
Y58681D01*
G01Y56870D02*
Y57389D01*
G01Y53720D02*
Y54239D01*
G01Y51854D02*
Y52382D01*
G01Y50571D02*
Y51090D01*
G01Y48704D02*
Y49232D01*
G01Y47421D02*
Y47940D01*
G01Y55531D02*
Y55003D01*
G01X698249Y50492D02*
Y49311D01*
G01Y53641D02*
Y52460D01*
G01Y56791D02*
Y55610D01*
G01Y59941D02*
Y58759D01*
G01Y63090D02*
Y61909D01*
G01X697397D02*
Y63090D01*
G01Y58759D02*
Y59941D01*
G01Y55610D02*
Y56791D01*
G01Y52460D02*
Y53641D01*
G01Y49311D02*
Y50492D01*
G01X696869Y61102D02*
Y63189D01*
G01Y58267D02*
Y60472D01*
G01Y54370D02*
Y56574D01*
G01Y53031D02*
Y53307D01*
G01Y52441D02*
Y52834D01*
G01Y51141D02*
Y51968D01*
G01X696715Y50492D02*
Y49311D01*
G01Y53641D02*
Y52460D01*
G01Y56791D02*
Y55610D01*
G01Y59941D02*
Y58759D01*
G01Y63090D02*
Y61909D01*
G01X695093Y47185D02*
Y46319D01*
G01Y50334D02*
Y49468D01*
G01Y53484D02*
Y52618D01*
G01Y56633D02*
Y55767D01*
G01Y59783D02*
Y58917D01*
G01Y62933D02*
Y62067D01*
G01X694411D02*
Y62933D01*
G01Y58917D02*
Y59783D01*
G01Y55767D02*
Y56633D01*
G01Y52618D02*
Y53484D01*
G01Y49468D02*
Y50334D01*
G01Y46319D02*
Y47185D01*
G01X693559D02*
Y46319D01*
G01Y50334D02*
Y49468D01*
G01Y53484D02*
Y52618D01*
G01Y56633D02*
Y55767D01*
G01Y59783D02*
Y58917D01*
G01Y62933D02*
Y62067D01*
G01X693498Y62126D02*
Y63110D01*
G01Y57126D02*
Y58110D01*
G01Y52126D02*
Y53110D01*
G01Y49173D02*
Y50157D01*
G01Y47126D02*
Y48110D01*
G01Y55157D02*
Y54173D01*
G01Y60157D02*
Y59173D01*
G01X692711Y60354D02*
Y61929D01*
G01Y55354D02*
Y56929D01*
G01Y51929D02*
Y50354D01*
G01X691957Y51929D02*
Y50354D01*
G01Y56929D02*
Y55354D01*
G01Y61929D02*
Y60354D01*
G01X691203Y50354D02*
Y51929D01*
G01Y56929D02*
Y55354D01*
G01Y61929D02*
Y60354D01*
G01X690803Y55767D02*
Y56633D01*
G01Y46319D02*
Y47185D01*
G01Y50334D02*
Y49468D01*
G01Y53484D02*
Y52618D01*
G01Y59783D02*
Y58917D01*
G01Y62933D02*
Y62067D01*
G01X685100Y60354D02*
Y61929D01*
G01Y55354D02*
Y56929D01*
G01Y50354D02*
Y51929D01*
G01X684346D02*
Y50354D01*
G01Y56929D02*
Y55354D01*
G01Y61929D02*
Y60354D01*
G01X683593Y51929D02*
Y50354D01*
G01Y56929D02*
Y55354D01*
G01Y61929D02*
Y60354D01*
G01X695758Y62067D02*
X695837Y61909D01*
G01X695155D02*
X695076Y62067D01*
G01X695758Y58917D02*
X695837Y58759D01*
G01X695155D02*
X695076Y58917D01*
G01X695758Y55767D02*
X695837Y55610D01*
G01X695155D02*
X695076Y55767D01*
G01X695758Y52618D02*
X695837Y52460D01*
G01X695155D02*
X695076Y52618D01*
G01X695758Y49468D02*
X695837Y49311D01*
G01X695155D02*
X695076Y49468D01*
G01X691414Y61987D02*
X691108Y62462D01*
G01X690354D02*
X690660Y61987D01*
G01X691414Y56987D02*
X691108Y57462D01*
G01X690354D02*
X690660Y56987D01*
G01X691414Y51987D02*
X691108Y52462D01*
G01X685667Y60296D02*
X685973Y59821D01*
G01X690354Y52462D02*
X690660Y51987D01*
G01X685219Y59821D02*
X684913Y60296D01*
G01X691414Y46987D02*
X691108Y47462D01*
G01X685667Y55296D02*
X685973Y54821D01*
G01X690354Y47462D02*
X690660Y46987D01*
G01X685219Y54821D02*
X684913Y55296D01*
G01X685667Y50296D02*
X685973Y49821D01*
G01X685219D02*
X684913Y50296D01*
G01X685309Y62519D02*
X691019D01*
G01X690354Y62462D02*
X691108D01*
G01X685973D02*
X685219D01*
G01X695758Y62067D02*
X690803D01*
G01X685667Y61987D02*
X684913D01*
G01X691414D02*
X690660D01*
G01X690749Y61929D02*
X693302D01*
G01X695155Y61909D02*
X698480D01*
G01X699054Y61302D02*
X698857D01*
G01Y60539D02*
X699054D01*
G01X690749Y60354D02*
X693302D01*
G01X684913Y60296D02*
X685667D01*
G01X691414D02*
X690660D01*
G01X695155Y59941D02*
X698480D01*
G01X690354Y59821D02*
X691108D01*
G01X685973D02*
X685219D01*
G01X690803Y59783D02*
X695758D01*
G01X691019Y59763D02*
X685309D01*
G01X696850Y59173D02*
X693498D01*
G01X695758Y58917D02*
X690803D01*
G01X695155Y58759D02*
X698480D01*
G01X699054Y58153D02*
X698857D01*
G01X693498Y58110D02*
X696850D01*
G01X685309Y57519D02*
X691019D01*
G01X690354Y57462D02*
X691108D01*
G01X685973D02*
X685219D01*
G01X699054Y57389D02*
X698857D01*
G01X685667Y56987D02*
X684913D01*
G01X691414D02*
X690660D01*
G01X690749Y56929D02*
X693302D01*
G01X695155Y56791D02*
X698480D01*
G01X690803Y56633D02*
X695758D01*
G01Y55767D02*
X690803D01*
G01X695155Y55610D02*
X698480D01*
G01X690749Y55354D02*
X693302D01*
G01X684913Y55296D02*
X685667D01*
G01X691414D02*
X690660D01*
G01X698857Y55003D02*
X699054D01*
G01X690354Y54821D02*
X691108D01*
G01X685973D02*
X685219D01*
G01X691019Y54763D02*
X685309D01*
G01X698857Y54239D02*
X699054D01*
G01X696850Y54173D02*
X693498D01*
G01X695155Y53641D02*
X698480D01*
G01X690803Y53484D02*
X695758D01*
G01X693498Y53110D02*
X696850D01*
G01X695758Y52618D02*
X690803D01*
G01X685309Y52519D02*
X691019D01*
G01X685973Y52462D02*
X685219D01*
G01X691108D02*
X690354D01*
G01X695155Y52460D02*
X698480D01*
G01X684913Y51987D02*
X685667D01*
G01X691414D02*
X690660D01*
G01X690749Y51929D02*
X693302D01*
G01X699054Y51854D02*
X698857D01*
G01Y51090D02*
X699054D01*
G01X695155Y50492D02*
X698480D01*
G01X690749Y50354D02*
X693302D01*
G01X690803Y50334D02*
X695758D01*
G01X684913Y50296D02*
X685667D01*
G01X691414D02*
X690660D01*
G01X690354Y49821D02*
X691108D01*
G01X685973D02*
X685219D01*
G01X691019Y49763D02*
X685309D01*
G01X695758Y49468D02*
X690803D01*
G01X695155Y49311D02*
X698480D01*
G01X693498Y49173D02*
X696850D01*
G01X699054Y48704D02*
X698857D01*
G01X693498Y48110D02*
X696850D01*
G01X699054Y47940D02*
X698857D01*
G01X685309Y47519D02*
X691019D01*
G01X685973Y47462D02*
X685219D01*
G01X691108D02*
X690354D01*
G01X695155Y47342D02*
X698480D01*
G01X690803Y47185D02*
X695758D01*
G01X684913Y46987D02*
X685667D01*
G01X691414D02*
X690660D01*
G01X690749Y46929D02*
X693302D01*
G01X695758Y46319D02*
X690803D01*
G01X691082Y64790D02*
X691108Y64821D01*
G01X691052Y64770D02*
X691082Y64790D01*
G01X691019Y64763D02*
X691052Y64770D01*
G01X690686Y65328D02*
X690660Y65296D01*
G01X690717Y65347D02*
X690686Y65328D01*
G01X690749Y65354D02*
X690717Y65347D01*
G01X684887Y66955D02*
X684913Y66987D01*
G01X684857Y66935D02*
X684887Y66955D01*
G01X684824Y66929D02*
X684857Y66935D01*
G01X685999Y67493D02*
X685973Y67462D01*
G01X686030Y67513D02*
X685999Y67493D01*
G01X686063Y67519D02*
X686030Y67513D01*
G01X691082Y69790D02*
X691108Y69821D01*
G01X691052Y69770D02*
X691082Y69790D01*
G01X691019Y69763D02*
X691052Y69770D01*
G01X690686Y70328D02*
X690660Y70296D01*
G01X690717Y70347D02*
X690686Y70328D01*
G01X690749Y70354D02*
X690717Y70347D01*
G01X684887Y71955D02*
X684913Y71987D01*
G01X684857Y71935D02*
X684887Y71955D01*
G01X684824Y71929D02*
X684857Y71935D01*
G01X685999Y72493D02*
X685973Y72462D01*
G01X686030Y72513D02*
X685999Y72493D01*
G01X686063Y72519D02*
X686030Y72513D01*
G01X691082Y74790D02*
X691108Y74821D01*
G01X691052Y74770D02*
X691082Y74790D01*
G01X691019Y74763D02*
X691052Y74770D01*
G01X690686Y75328D02*
X690660Y75296D01*
G01X690717Y75347D02*
X690686Y75328D01*
G01X690749Y75354D02*
X690717Y75347D01*
G01X684887Y76955D02*
X684913Y76987D01*
G01X684857Y76935D02*
X684887Y76955D01*
G01X684824Y76929D02*
X684857Y76935D01*
G01X685999Y77493D02*
X685973Y77462D01*
G01X686030Y77513D02*
X685999Y77493D01*
G01X686063Y77519D02*
X686030Y77513D01*
G01X685245Y64790D02*
X685219Y64821D01*
G01X685276Y64770D02*
X685245Y64790D01*
G01X685309Y64763D02*
X685276Y64770D01*
G01X685641Y65328D02*
X685667Y65296D01*
G01X685611Y65347D02*
X685641Y65328D01*
G01X685578Y65354D02*
X685611Y65347D01*
G01X691440Y66955D02*
X691414Y66987D01*
G01X691470Y66935D02*
X691440Y66955D01*
G01X691504Y66929D02*
X691470Y66935D01*
G01X690328Y67493D02*
X690354Y67462D01*
G01X690298Y67513D02*
X690328Y67493D01*
G01X690265Y67519D02*
X690298Y67513D01*
G01X685245Y69790D02*
X685219Y69821D01*
G01X685276Y69770D02*
X685245Y69790D01*
G01X685309Y69763D02*
X685276Y69770D01*
G01X685641Y70328D02*
X685667Y70296D01*
G01X685611Y70347D02*
X685641Y70328D01*
G01X685578Y70354D02*
X685611Y70347D01*
G01X691440Y71955D02*
X691414Y71987D01*
G01X691470Y71935D02*
X691440Y71955D01*
G01X691504Y71929D02*
X691470Y71935D01*
G01X690328Y72493D02*
X690354Y72462D01*
G01X690298Y72513D02*
X690328Y72493D01*
G01X690265Y72519D02*
X690298Y72513D01*
G01X685245Y74790D02*
X685219Y74821D01*
G01X685276Y74770D02*
X685245Y74790D01*
G01X685309Y74763D02*
X685276Y74770D01*
G01X685641Y75328D02*
X685667Y75296D01*
G01X685611Y75347D02*
X685641Y75328D01*
G01X685578Y75354D02*
X685611Y75347D01*
G01X691440Y76955D02*
X691414Y76987D01*
G01X691470Y76935D02*
X691440Y76955D01*
G01X691504Y76929D02*
X691470Y76935D01*
G01X690328Y77493D02*
X690354Y77462D01*
G01X690298Y77513D02*
X690328Y77493D01*
G01X690265Y77519D02*
X690298Y77513D01*
G01X684857Y65347D02*
X684824Y65354D01*
G01X684887Y65328D02*
X684857Y65347D01*
G01X684913Y65296D02*
X684887Y65328D01*
G01X686030Y64770D02*
X686063Y64763D01*
G01X685999Y64790D02*
X686030Y64770D01*
G01X685973Y64821D02*
X685999Y64790D01*
G01X684857Y70347D02*
X684824Y70354D01*
G01X684887Y70328D02*
X684857Y70347D01*
G01X684913Y70296D02*
X684887Y70328D01*
G01X686030Y69770D02*
X686063Y69763D01*
G01X685999Y69790D02*
X686030Y69770D01*
G01X685973Y69821D02*
X685999Y69790D01*
G01X690717Y66935D02*
X690749Y66929D01*
G01X690686Y66955D02*
X690717Y66935D01*
G01X690660Y66987D02*
X690686Y66955D01*
G01X691052Y67513D02*
X691019Y67519D01*
G01X691082Y67493D02*
X691052Y67513D01*
G01X691108Y67462D02*
X691082Y67493D01*
G01X684857Y75347D02*
X684824Y75354D01*
G01X684887Y75328D02*
X684857Y75347D01*
G01X684913Y75296D02*
X684887Y75328D01*
G01X686030Y74770D02*
X686063Y74763D01*
G01X685999Y74790D02*
X686030Y74770D01*
G01X685973Y74821D02*
X685999Y74790D01*
G01X690717Y71935D02*
X690749Y71929D01*
G01X690686Y71955D02*
X690717Y71935D01*
G01X690660Y71987D02*
X690686Y71955D01*
G01X691052Y72513D02*
X691019Y72519D01*
G01X691082Y72493D02*
X691052Y72513D01*
G01X691108Y72462D02*
X691082Y72493D01*
G01X690717Y76935D02*
X690749Y76929D01*
G01X690686Y76955D02*
X690717Y76935D01*
G01X690660Y76987D02*
X690686Y76955D01*
G01X691052Y77513D02*
X691019Y77519D01*
G01X691082Y77493D02*
X691052Y77513D01*
G01X691108Y77462D02*
X691082Y77493D01*
G01X685276Y77513D02*
X685309Y77519D01*
G01X685245Y77493D02*
X685276Y77513D01*
G01X685219Y77462D02*
X685245Y77493D01*
G01X685611Y76935D02*
X685578Y76929D01*
G01X685641Y76955D02*
X685611Y76935D01*
G01X685667Y76987D02*
X685641Y76955D01*
G01X685276Y72513D02*
X685309Y72519D01*
G01X685245Y72493D02*
X685276Y72513D01*
G01X685219Y72462D02*
X685245Y72493D01*
G01X685611Y71935D02*
X685578Y71929D01*
G01X685641Y71955D02*
X685611Y71935D01*
G01X685667Y71987D02*
X685641Y71955D01*
G01X690298Y74770D02*
X690265Y74763D01*
G01X690328Y74790D02*
X690298Y74770D01*
G01X690354Y74821D02*
X690328Y74790D01*
G01X691470Y75347D02*
X691504Y75354D01*
G01X691440Y75328D02*
X691470Y75347D01*
G01X691414Y75296D02*
X691440Y75328D01*
G01X685276Y67513D02*
X685309Y67519D01*
G01X685245Y67493D02*
X685276Y67513D01*
G01X685219Y67462D02*
X685245Y67493D01*
G01X685611Y66935D02*
X685578Y66929D01*
G01X685641Y66955D02*
X685611Y66935D01*
G01X685667Y66987D02*
X685641Y66955D01*
G01X690298Y69770D02*
X690265Y69763D01*
G01X690328Y69790D02*
X690298Y69770D01*
G01X690354Y69821D02*
X690328Y69790D01*
G01X691470Y70347D02*
X691504Y70354D01*
G01X691440Y70328D02*
X691470Y70347D01*
G01X691414Y70296D02*
X691440Y70328D01*
G01X690298Y64770D02*
X690265Y64763D01*
G01X690328Y64790D02*
X690298Y64770D01*
G01X690354Y64821D02*
X690328Y64790D01*
G01X691470Y65347D02*
X691504Y65354D01*
G01X691440Y65328D02*
X691470Y65347D01*
G01X691414Y65296D02*
X691440Y65328D01*
G01X698480Y78838D02*
G03X698857Y78917I180J79D01*
G01X698480Y69389D02*
G03X698857Y69469I180J79D01*
G01Y68130D02*
G03X698480Y68208I-197J-1D01*
G01X698857Y77578D02*
G03X698480Y77657I-197J0D01*
G01Y72539D02*
G03X698857Y72618I180J79D01*
G01Y71279D02*
G03X698480Y71358I-197J0D01*
G01X698857Y74429D02*
G03X698480Y74508I-197J0D01*
G01Y75689D02*
G03X698857Y75767I180J79D01*
G01X693498Y75157D02*
G03X693302Y75354I-197J0D01*
G01Y76929D02*
G03X693498Y77126I-1J197D01*
G01Y70157D02*
G03X693302Y70354I-197J0D01*
G01Y71929D02*
G03X693498Y72126I-1J197D01*
G01X698480Y63090D02*
G03X698857Y63169I180J79D01*
G01Y64980D02*
G03X698480Y65059I-197J0D01*
G01Y66240D02*
G03X698857Y66319I180J79D01*
G01X693498Y65157D02*
G03X693302Y65354I-197J0D01*
G01Y66929D02*
G03X693498Y67126I-1J197D01*
G01X691108Y64821D02*
X691414Y65296D01*
G01X690660D02*
X690354Y64821D01*
G01X691108Y69821D02*
X691414Y70296D01*
G01X690660D02*
X690354Y69821D01*
G01X691108Y74821D02*
X691414Y75296D01*
G01X685973Y67462D02*
X685667Y66987D01*
G01X690660Y75296D02*
X690354Y74821D01*
G01X684913Y66987D02*
X685219Y67462D01*
G01X685973Y72462D02*
X685667Y71987D01*
G01X684913D02*
X685219Y72462D01*
G01X685973Y77462D02*
X685667Y76987D01*
G01X684913D02*
X685219Y77462D01*
G01X695837Y63090D02*
X695758Y62933D01*
G01X695076D02*
X695155Y63090D01*
G01X695837Y66240D02*
X695758Y66082D01*
G01X695076D02*
X695155Y66240D01*
G01X695837Y69389D02*
X695758Y69232D01*
G01X695076D02*
X695155Y69389D01*
G01X695837Y72539D02*
X695758Y72382D01*
G01X695076D02*
X695155Y72539D01*
G01X695837Y75689D02*
X695758Y75531D01*
G01X695076D02*
X695155Y75689D01*
G01X695837Y78838D02*
X695758Y78681D01*
G01X695076D02*
X695155Y78838D01*
G01X698857Y78917D02*
Y79436D01*
G01Y77050D02*
Y77578D01*
G01Y75767D02*
Y76287D01*
G01Y72618D02*
Y73137D01*
G01Y73901D02*
Y74429D01*
G01Y70751D02*
Y71279D01*
G01Y69469D02*
Y69987D01*
G01Y67602D02*
Y68130D01*
G01Y66319D02*
Y66838D01*
G01Y63169D02*
Y63688D01*
G01Y64980D02*
Y64452D01*
G01X698249Y66240D02*
Y65059D01*
G01Y69389D02*
Y68208D01*
G01Y72539D02*
Y71358D01*
G01Y75689D02*
Y74508D01*
G01Y78838D02*
Y77657D01*
G01X697397D02*
Y78838D01*
G01Y74508D02*
Y75689D01*
G01Y71358D02*
Y72539D01*
G01Y68208D02*
Y69389D01*
G01Y65059D02*
Y66240D01*
G01X696869Y74677D02*
Y76764D01*
G01X696715Y66240D02*
Y65059D01*
G01Y69389D02*
Y68208D01*
G01Y72539D02*
Y71358D01*
G01Y75689D02*
Y74508D01*
G01Y78838D02*
Y77657D01*
G01X695093Y66082D02*
Y65216D01*
G01Y69232D02*
Y68366D01*
G01Y72382D02*
Y71515D01*
G01Y75531D02*
Y74665D01*
G01Y78681D02*
Y77815D01*
G01X694411D02*
Y78681D01*
G01Y74665D02*
Y75531D01*
G01Y71515D02*
Y72382D01*
G01Y68366D02*
Y69232D01*
G01Y65216D02*
Y66082D01*
G01X693559D02*
Y65216D01*
G01Y69232D02*
Y68366D01*
G01Y72382D02*
Y71515D01*
G01Y75531D02*
Y74665D01*
G01Y78681D02*
Y77815D01*
G01X693498Y79173D02*
Y80157D01*
G01Y77126D02*
Y78110D01*
G01Y74173D02*
Y75157D01*
G01Y72126D02*
Y73110D01*
G01Y67126D02*
Y68110D01*
G01Y64173D02*
Y65157D01*
G01Y70157D02*
Y69173D01*
G01X692711Y70354D02*
Y71929D01*
G01Y66929D02*
Y65354D01*
G01Y76929D02*
Y75354D01*
G01X691957Y66929D02*
Y65354D01*
G01Y71929D02*
Y70354D01*
G01Y76929D02*
Y75354D01*
G01X691203D02*
Y76929D01*
G01Y65354D02*
Y66929D01*
G01Y71929D02*
Y70354D01*
G01X690803Y74665D02*
Y75531D01*
G01Y65216D02*
Y66082D01*
G01Y69232D02*
Y68366D01*
G01Y72382D02*
Y71515D01*
G01Y78681D02*
Y77815D01*
G01X685100Y75354D02*
Y76929D01*
G01Y70354D02*
Y71929D01*
G01Y65354D02*
Y66929D01*
G01X684346D02*
Y65354D01*
G01Y71929D02*
Y70354D01*
G01Y76929D02*
Y75354D01*
G01X683593Y66929D02*
Y65354D01*
G01Y71929D02*
Y70354D01*
G01Y76929D02*
Y75354D01*
G01X695758Y77815D02*
X695837Y77657D01*
G01X695155D02*
X695076Y77815D01*
G01X695758Y74665D02*
X695837Y74508D01*
G01X695155D02*
X695076Y74665D01*
G01X695758Y71515D02*
X695837Y71358D01*
G01X695155D02*
X695076Y71515D01*
G01X695758Y68366D02*
X695837Y68208D01*
G01X695155D02*
X695076Y68366D01*
G01X695758Y65216D02*
X695837Y65059D01*
G01X695155D02*
X695076Y65216D01*
G01X691414Y76987D02*
X691108Y77462D01*
G01X690354D02*
X690660Y76987D01*
G01X691414Y71987D02*
X691108Y72462D01*
G01X690354D02*
X690660Y71987D01*
G01X691414Y66987D02*
X691108Y67462D01*
G01X685667Y75296D02*
X685973Y74821D01*
G01X690354Y67462D02*
X690660Y66987D01*
G01X685219Y74821D02*
X684913Y75296D01*
G01X685667Y70296D02*
X685973Y69821D01*
G01X685219D02*
X684913Y70296D01*
G01X685667Y65296D02*
X685973Y64821D01*
G01X685219D02*
X684913Y65296D01*
G01X696850Y79173D02*
X693498D01*
G01X695155Y78838D02*
X698480D01*
G01X690803Y78681D02*
X695758D01*
G01X693498Y78110D02*
X696850D01*
G01X695758Y77815D02*
X690803D01*
G01X695155Y77657D02*
X698480D01*
G01X685309Y77519D02*
X691019D01*
G01X690354Y77462D02*
X691108D01*
G01X685973D02*
X685219D01*
G01X699054Y77050D02*
X698857D01*
G01X685667Y76987D02*
X684913D01*
G01X691414D02*
X690660D01*
G01X690749Y76929D02*
X693302D01*
G01X699054Y76287D02*
X698857D01*
G01X695155Y75689D02*
X698480D01*
G01X690803Y75531D02*
X695758D01*
G01X690749Y75354D02*
X693302D01*
G01X684913Y75296D02*
X685667D01*
G01X691414D02*
X690660D01*
G01X690354Y74821D02*
X691108D01*
G01X685973D02*
X685219D01*
G01X691019Y74763D02*
X685309D01*
G01X695758Y74665D02*
X690803D01*
G01X695155Y74508D02*
X698480D01*
G01X696850Y74173D02*
X693498D01*
G01X699054Y73901D02*
X698857D01*
G01Y73137D02*
X699054D01*
G01X693498Y73110D02*
X696850D01*
G01X695155Y72539D02*
X698480D01*
G01X685309Y72519D02*
X691019D01*
G01X690354Y72462D02*
X691108D01*
G01X685973D02*
X685219D01*
G01X690803Y72382D02*
X695758D01*
G01X685667Y71987D02*
X684913D01*
G01X691414D02*
X690660D01*
G01X690749Y71929D02*
X693302D01*
G01X695758Y71515D02*
X690803D01*
G01X695155Y71358D02*
X698480D01*
G01X699054Y70751D02*
X698857D01*
G01X690749Y70354D02*
X693302D01*
G01X684913Y70296D02*
X685667D01*
G01X691414D02*
X690660D01*
G01X698857Y69987D02*
X699054D01*
G01X690354Y69821D02*
X691108D01*
G01X685973D02*
X685219D01*
G01X691019Y69763D02*
X685309D01*
G01X695155Y69389D02*
X698480D01*
G01X690803Y69232D02*
X695758D01*
G01X696850Y69173D02*
X693498D01*
G01X695758Y68366D02*
X690803D01*
G01X695155Y68208D02*
X698480D01*
G01X693498Y68110D02*
X696850D01*
G01X699054Y67602D02*
X698857D01*
G01X685309Y67519D02*
X691019D01*
G01X690354Y67462D02*
X691108D01*
G01X685973D02*
X685219D01*
G01X685667Y66987D02*
X684913D01*
G01X691414D02*
X690660D01*
G01X690749Y66929D02*
X693302D01*
G01X699054Y66838D02*
X698857D01*
G01X695155Y66240D02*
X698480D01*
G01X690803Y66082D02*
X695758D01*
G01X690749Y65354D02*
X693302D01*
G01X684913Y65296D02*
X685667D01*
G01X691414D02*
X690660D01*
G01X695758Y65216D02*
X690803D01*
G01X695155Y65059D02*
X698480D01*
G01X690354Y64821D02*
X691108D01*
G01X685973D02*
X685219D01*
G01X691019Y64763D02*
X685309D01*
G01X698857Y64452D02*
X699054D01*
G01X696850Y64173D02*
X693498D01*
G01X698857Y63688D02*
X699054D01*
G01X693498Y63110D02*
X696850D01*
G01X695155Y63090D02*
X698480D01*
G01X690803Y62933D02*
X695758D01*
G01X691082Y79790D02*
X691108Y79821D01*
G01X691052Y79770D02*
X691082Y79790D01*
G01X691019Y79763D02*
X691052Y79770D01*
G01X690686Y80328D02*
X690660Y80296D01*
G01X690717Y80347D02*
X690686Y80328D01*
G01X690749Y80354D02*
X690717Y80347D01*
G01X684887Y81955D02*
X684913Y81987D01*
G01X684857Y81935D02*
X684887Y81955D01*
G01X684824Y81929D02*
X684857Y81935D01*
G01X685999Y82493D02*
X685973Y82462D01*
G01X686030Y82513D02*
X685999Y82493D01*
G01X686063Y82519D02*
X686030Y82513D01*
G01X691082Y84790D02*
X691108Y84821D01*
G01X691052Y84770D02*
X691082Y84790D01*
G01X691019Y84763D02*
X691052Y84770D01*
G01X690686Y85328D02*
X690660Y85296D01*
G01X690717Y85347D02*
X690686Y85328D01*
G01X690749Y85354D02*
X690717Y85347D01*
G01X684887Y86955D02*
X684913Y86987D01*
G01X684857Y86935D02*
X684887Y86955D01*
G01X684824Y86929D02*
X684857Y86935D01*
G01X685999Y87493D02*
X685973Y87462D01*
G01X686030Y87513D02*
X685999Y87493D01*
G01X686063Y87519D02*
X686030Y87513D01*
G01X691082Y89790D02*
X691108Y89821D01*
G01X691052Y89770D02*
X691082Y89790D01*
G01X691019Y89763D02*
X691052Y89770D01*
G01X690686Y90328D02*
X690660Y90296D01*
G01X690717Y90347D02*
X690686Y90328D01*
G01X690749Y90354D02*
X690717Y90347D01*
G01X684887Y91955D02*
X684913Y91987D01*
G01X684857Y91935D02*
X684887Y91955D01*
G01X684824Y91929D02*
X684857Y91935D01*
G01X685999Y92493D02*
X685973Y92462D01*
G01X686030Y92513D02*
X685999Y92493D01*
G01X686063Y92519D02*
X686030Y92513D01*
G01X691082Y94790D02*
X691108Y94821D01*
G01X691052Y94770D02*
X691082Y94790D01*
G01X691019Y94763D02*
X691052Y94770D01*
G01X690686Y95328D02*
X690660Y95296D01*
G01X690717Y95347D02*
X690686Y95328D01*
G01X690749Y95354D02*
X690717Y95347D01*
G01X685245Y79790D02*
X685219Y79821D01*
G01X685276Y79770D02*
X685245Y79790D01*
G01X685309Y79763D02*
X685276Y79770D01*
G01X685641Y80328D02*
X685667Y80296D01*
G01X685611Y80347D02*
X685641Y80328D01*
G01X685578Y80354D02*
X685611Y80347D01*
G01X691440Y81955D02*
X691414Y81987D01*
G01X691470Y81935D02*
X691440Y81955D01*
G01X691504Y81929D02*
X691470Y81935D01*
G01X690328Y82493D02*
X690354Y82462D01*
G01X690298Y82513D02*
X690328Y82493D01*
G01X690265Y82519D02*
X690298Y82513D01*
G01X685245Y84790D02*
X685219Y84821D01*
G01X685276Y84770D02*
X685245Y84790D01*
G01X685309Y84763D02*
X685276Y84770D01*
G01X685641Y85328D02*
X685667Y85296D01*
G01X685611Y85347D02*
X685641Y85328D01*
G01X685578Y85354D02*
X685611Y85347D01*
G01X691440Y86955D02*
X691414Y86987D01*
G01X691470Y86935D02*
X691440Y86955D01*
G01X691504Y86929D02*
X691470Y86935D01*
G01X690328Y87493D02*
X690354Y87462D01*
G01X690298Y87513D02*
X690328Y87493D01*
G01X690265Y87519D02*
X690298Y87513D01*
G01X685245Y89790D02*
X685219Y89821D01*
G01X685276Y89770D02*
X685245Y89790D01*
G01X685309Y89763D02*
X685276Y89770D01*
G01X685641Y90328D02*
X685667Y90296D01*
G01X685611Y90347D02*
X685641Y90328D01*
G01X685578Y90354D02*
X685611Y90347D01*
G01X691440Y91955D02*
X691414Y91987D01*
G01X691470Y91935D02*
X691440Y91955D01*
G01X691504Y91929D02*
X691470Y91935D01*
G01X690328Y92493D02*
X690354Y92462D01*
G01X690298Y92513D02*
X690328Y92493D01*
G01X690265Y92519D02*
X690298Y92513D01*
G01X685245Y94790D02*
X685219Y94821D01*
G01X685276Y94770D02*
X685245Y94790D01*
G01X685309Y94763D02*
X685276Y94770D01*
G01X685641Y95328D02*
X685667Y95296D01*
G01X685611Y95347D02*
X685641Y95328D01*
G01X685578Y95354D02*
X685611Y95347D01*
G01X684857Y80347D02*
X684824Y80354D01*
G01X684887Y80328D02*
X684857Y80347D01*
G01X684913Y80296D02*
X684887Y80328D01*
G01X686030Y79770D02*
X686063Y79763D01*
G01X685999Y79790D02*
X686030Y79770D01*
G01X685973Y79821D02*
X685999Y79790D01*
G01X684857Y85347D02*
X684824Y85354D01*
G01X684887Y85328D02*
X684857Y85347D01*
G01X684913Y85296D02*
X684887Y85328D01*
G01X686030Y84770D02*
X686063Y84763D01*
G01X685999Y84790D02*
X686030Y84770D01*
G01X685973Y84821D02*
X685999Y84790D01*
G01X690717Y81935D02*
X690749Y81929D01*
G01X690686Y81955D02*
X690717Y81935D01*
G01X690660Y81987D02*
X690686Y81955D01*
G01X691052Y82513D02*
X691019Y82519D01*
G01X691082Y82493D02*
X691052Y82513D01*
G01X691108Y82462D02*
X691082Y82493D01*
G01X684857Y90347D02*
X684824Y90354D01*
G01X684887Y90328D02*
X684857Y90347D01*
G01X684913Y90296D02*
X684887Y90328D01*
G01X686030Y89770D02*
X686063Y89763D01*
G01X685999Y89790D02*
X686030Y89770D01*
G01X685973Y89821D02*
X685999Y89790D01*
G01X690717Y86935D02*
X690749Y86929D01*
G01X690686Y86955D02*
X690717Y86935D01*
G01X690660Y86987D02*
X690686Y86955D01*
G01X691052Y87513D02*
X691019Y87519D01*
G01X691082Y87493D02*
X691052Y87513D01*
G01X691108Y87462D02*
X691082Y87493D01*
G01X684857Y95347D02*
X684824Y95354D01*
G01X684887Y95328D02*
X684857Y95347D01*
G01X684913Y95296D02*
X684887Y95328D01*
G01X686030Y94770D02*
X686063Y94763D01*
G01X685999Y94790D02*
X686030Y94770D01*
G01X685973Y94821D02*
X685999Y94790D01*
G01X690717Y91935D02*
X690749Y91929D01*
G01X690686Y91955D02*
X690717Y91935D01*
G01X690660Y91987D02*
X690686Y91955D01*
G01X691052Y92513D02*
X691019Y92519D01*
G01X691082Y92493D02*
X691052Y92513D01*
G01X691108Y92462D02*
X691082Y92493D01*
G01X685276Y92513D02*
X685309Y92519D01*
G01X685245Y92493D02*
X685276Y92513D01*
G01X685219Y92462D02*
X685245Y92493D01*
G01X685611Y91935D02*
X685578Y91929D01*
G01X685641Y91955D02*
X685611Y91935D01*
G01X685667Y91987D02*
X685641Y91955D01*
G01X690298Y94770D02*
X690265Y94763D01*
G01X690328Y94790D02*
X690298Y94770D01*
G01X690354Y94821D02*
X690328Y94790D01*
G01X691470Y95347D02*
X691504Y95354D01*
G01X691440Y95328D02*
X691470Y95347D01*
G01X691414Y95296D02*
X691440Y95328D01*
G01X685276Y87513D02*
X685309Y87519D01*
G01X685245Y87493D02*
X685276Y87513D01*
G01X685219Y87462D02*
X685245Y87493D01*
G01X685611Y86935D02*
X685578Y86929D01*
G01X685641Y86955D02*
X685611Y86935D01*
G01X685667Y86987D02*
X685641Y86955D01*
G01X690298Y89770D02*
X690265Y89763D01*
G01X690328Y89790D02*
X690298Y89770D01*
G01X690354Y89821D02*
X690328Y89790D01*
G01X691470Y90347D02*
X691504Y90354D01*
G01X691440Y90328D02*
X691470Y90347D01*
G01X691414Y90296D02*
X691440Y90328D01*
G01X685276Y82513D02*
X685309Y82519D01*
G01X685245Y82493D02*
X685276Y82513D01*
G01X685219Y82462D02*
X685245Y82493D01*
G01X685611Y81935D02*
X685578Y81929D01*
G01X685641Y81955D02*
X685611Y81935D01*
G01X685667Y81987D02*
X685641Y81955D01*
G01X690298Y84770D02*
X690265Y84763D01*
G01X690328Y84790D02*
X690298Y84770D01*
G01X690354Y84821D02*
X690328Y84790D01*
G01X691470Y85347D02*
X691504Y85354D01*
G01X691440Y85328D02*
X691470Y85347D01*
G01X691414Y85296D02*
X691440Y85328D01*
G01X690298Y79770D02*
X690265Y79763D01*
G01X690328Y79790D02*
X690298Y79770D01*
G01X690354Y79821D02*
X690328Y79790D01*
G01X691470Y80347D02*
X691504Y80354D01*
G01X691440Y80328D02*
X691470Y80347D01*
G01X691414Y80296D02*
X691440Y80328D01*
G01X698480Y91437D02*
G03X698857Y91516I180J79D01*
G01Y90177D02*
G03X698480Y90256I-197J0D01*
G01X698857Y93326D02*
G03X698480Y93405I-197J0D01*
G01Y94586D02*
G03X698857Y94665I180J79D01*
G01X693498Y90157D02*
G03X693302Y90354I-197J0D01*
G01Y91929D02*
G03X693498Y92126I-1J197D01*
G01Y95157D02*
G03X693302Y95354I-197J0D01*
G01X698480Y88287D02*
G03X698857Y88366I180J79D01*
G01Y87027D02*
G03X698480Y87106I-197J0D01*
G01Y81988D02*
G03X698857Y82067I180J79D01*
G01Y80728D02*
G03X698480Y80807I-197J0D01*
G01X698857Y83878D02*
G03X698480Y83956I-197J-1D01*
G01Y85137D02*
G03X698857Y85216I180J79D01*
G01X693498Y80157D02*
G03X693302Y80354I-197J0D01*
G01Y81929D02*
G03X693498Y82126I-1J197D01*
G01Y85157D02*
G03X693302Y85354I-197J0D01*
G01Y86929D02*
G03X693498Y87126I-1J197D01*
G01X691108Y79821D02*
X691414Y80296D01*
G01X690660D02*
X690354Y79821D01*
G01X691108Y84821D02*
X691414Y85296D01*
G01X690660D02*
X690354Y84821D01*
G01X695837Y81988D02*
X695758Y81830D01*
G01X695076D02*
X695155Y81988D01*
G01X695837Y85137D02*
X695758Y84980D01*
G01X695076D02*
X695155Y85137D01*
G01X695837Y88287D02*
X695758Y88130D01*
G01X695076D02*
X695155Y88287D01*
G01X695837Y91437D02*
X695758Y91279D01*
G01X695076D02*
X695155Y91437D01*
G01X695837Y94586D02*
X695758Y94429D01*
G01X695076D02*
X695155Y94586D01*
G01X691108Y89821D02*
X691414Y90296D01*
G01X685973Y82462D02*
X685667Y81987D01*
G01X690660Y90296D02*
X690354Y89821D01*
G01X684913Y81987D02*
X685219Y82462D01*
G01X691108Y94821D02*
X691414Y95296D01*
G01X685973Y87462D02*
X685667Y86987D01*
G01X690660Y95296D02*
X690354Y94821D01*
G01X684913Y86987D02*
X685219Y87462D01*
G01X685973Y92462D02*
X685667Y91987D01*
G01X684913D02*
X685219Y92462D01*
G01X698857Y94665D02*
Y95184D01*
G01Y91516D02*
Y92035D01*
G01Y92798D02*
Y93326D01*
G01Y89649D02*
Y90177D01*
G01Y88366D02*
Y88885D01*
G01Y86499D02*
Y87027D01*
G01Y85216D02*
Y85735D01*
G01Y82067D02*
Y82586D01*
G01Y83350D02*
Y83878D01*
G01Y80200D02*
Y80728D01*
G01X698249Y81988D02*
Y80807D01*
G01Y85137D02*
Y83956D01*
G01Y88287D02*
Y87106D01*
G01Y91437D02*
Y90256D01*
G01Y94586D02*
Y93405D01*
G01X697397D02*
Y94586D01*
G01Y90256D02*
Y91437D01*
G01Y87106D02*
Y88287D01*
G01Y83956D02*
Y85137D01*
G01Y80807D02*
Y81988D01*
G01X696715D02*
Y80807D01*
G01Y85137D02*
Y83956D01*
G01Y88287D02*
Y87106D01*
G01Y91437D02*
Y90256D01*
G01Y94586D02*
Y93405D01*
G01X695093Y81830D02*
Y80964D01*
G01Y84980D02*
Y84114D01*
G01Y88130D02*
Y87263D01*
G01Y91279D02*
Y90413D01*
G01Y94429D02*
Y93563D01*
G01X694411D02*
Y94429D01*
G01Y90413D02*
Y91279D01*
G01Y87263D02*
Y88130D01*
G01Y84114D02*
Y84980D01*
G01Y80964D02*
Y81830D01*
G01X693559D02*
Y80964D01*
G01Y84980D02*
Y84114D01*
G01Y88130D02*
Y87263D01*
G01Y91279D02*
Y90413D01*
G01Y94429D02*
Y93563D01*
G01X693498Y92126D02*
Y93110D01*
G01Y84173D02*
Y85157D01*
G01Y82126D02*
Y83110D01*
G01Y88110D02*
Y87126D01*
G01Y90157D02*
Y89173D01*
G01Y95157D02*
Y94173D01*
G01X692711Y95354D02*
Y96929D01*
G01Y90354D02*
Y91929D01*
G01Y85354D02*
Y86929D01*
G01Y81929D02*
Y80354D01*
G01X691957Y81929D02*
Y80354D01*
G01Y86929D02*
Y85354D01*
G01Y91929D02*
Y90354D01*
G01Y96929D02*
Y95354D01*
G01X691203Y85354D02*
Y86929D01*
G01Y80354D02*
Y81929D01*
G01Y91929D02*
Y90354D01*
G01Y96929D02*
Y95354D01*
G01X690803Y93563D02*
Y94429D01*
G01Y84114D02*
Y84980D01*
G01Y81830D02*
Y80964D01*
G01Y88130D02*
Y87263D01*
G01Y91279D02*
Y90413D01*
G01X685100Y95354D02*
Y96929D01*
G01Y90354D02*
Y91929D01*
G01Y85354D02*
Y86929D01*
G01Y80354D02*
Y81929D01*
G01X684346D02*
Y80354D01*
G01Y86929D02*
Y85354D01*
G01Y91929D02*
Y90354D01*
G01Y96929D02*
Y95354D01*
G01X683593Y81929D02*
Y80354D01*
G01Y86929D02*
Y85354D01*
G01Y91929D02*
Y90354D01*
G01Y96929D02*
Y95354D01*
G01X695758Y93563D02*
X695837Y93405D01*
G01X695155D02*
X695076Y93563D01*
G01X695758Y90413D02*
X695837Y90256D01*
G01X695155D02*
X695076Y90413D01*
G01X695758Y87263D02*
X695837Y87106D01*
G01X695155D02*
X695076Y87263D01*
G01X695758Y84114D02*
X695837Y83956D01*
G01X695155D02*
X695076Y84114D01*
G01X695758Y80964D02*
X695837Y80807D01*
G01X695155D02*
X695076Y80964D01*
G01X691414Y91987D02*
X691108Y92462D01*
G01X690354D02*
X690660Y91987D01*
G01X691414Y86987D02*
X691108Y87462D01*
G01X685667Y95296D02*
X685973Y94821D01*
G01X690354Y87462D02*
X690660Y86987D01*
G01X685219Y94821D02*
X684913Y95296D01*
G01X691414Y81987D02*
X691108Y82462D01*
G01X685667Y90296D02*
X685973Y89821D01*
G01X690354Y82462D02*
X690660Y81987D01*
G01X685219Y89821D02*
X684913Y90296D01*
G01X685667Y85296D02*
X685973Y84821D01*
G01X685219D02*
X684913Y85296D01*
G01X685667Y80296D02*
X685973Y79821D01*
G01X685219D02*
X684913Y80296D01*
G01X690749Y95354D02*
X693302D01*
G01X684913Y95296D02*
X685667D01*
G01X691414D02*
X690660D01*
G01X699054Y95184D02*
X698857D01*
G01X690354Y94821D02*
X691108D01*
G01X685973D02*
X685219D01*
G01X691019Y94763D02*
X685309D01*
G01X695155Y94586D02*
X698480D01*
G01X690803Y94429D02*
X695758D01*
G01X696850Y94173D02*
X693498D01*
G01X695758Y93563D02*
X690803D01*
G01X695155Y93405D02*
X698480D01*
G01X693498Y93110D02*
X696850D01*
G01X699054Y92798D02*
X698857D01*
G01X685309Y92519D02*
X691019D01*
G01X690354Y92462D02*
X691108D01*
G01X685973D02*
X685219D01*
G01X698857Y92035D02*
X699054D01*
G01X685667Y91987D02*
X684913D01*
G01X691414D02*
X690660D01*
G01X690749Y91929D02*
X693302D01*
G01X695155Y91437D02*
X698480D01*
G01X690803Y91279D02*
X695758D01*
G01Y90413D02*
X690803D01*
G01X690749Y90354D02*
X693302D01*
G01X684913Y90296D02*
X685667D01*
G01X691414D02*
X690660D01*
G01X695155Y90256D02*
X698480D01*
G01X690354Y89821D02*
X691108D01*
G01X685973D02*
X685219D01*
G01X691019Y89763D02*
X685309D01*
G01X699054Y89649D02*
X698857D01*
G01X696850Y89173D02*
X693498D01*
G01X698857Y88885D02*
X699054D01*
G01X695155Y88287D02*
X698480D01*
G01X690803Y88130D02*
X695758D01*
G01X693498Y88110D02*
X696850D01*
G01X685309Y87519D02*
X691019D01*
G01X685973Y87462D02*
X685219D01*
G01X691108D02*
X690354D01*
G01X695758Y87263D02*
X690803D01*
G01X695155Y87106D02*
X698480D01*
G01X684913Y86987D02*
X685667D01*
G01X691414D02*
X690660D01*
G01X690749Y86929D02*
X693302D01*
G01X699054Y86499D02*
X698857D01*
G01X699054Y85735D02*
X698857D01*
G01X690749Y85354D02*
X693302D01*
G01X684913Y85296D02*
X685667D01*
G01X691414D02*
X690660D01*
G01X695155Y85137D02*
X698480D01*
G01X690803Y84980D02*
X695758D01*
G01X690354Y84821D02*
X691108D01*
G01X685973D02*
X685219D01*
G01X691019Y84763D02*
X685309D01*
G01X696850Y84173D02*
X693498D01*
G01X695758Y84114D02*
X690803D01*
G01X695155Y83956D02*
X698480D01*
G01X699054Y83350D02*
X698857D01*
G01X693498Y83110D02*
X696850D01*
G01X698857Y82586D02*
X699054D01*
G01X685309Y82519D02*
X691019D01*
G01X690354Y82462D02*
X691108D01*
G01X685973D02*
X685219D01*
G01X695155Y81988D02*
X698480D01*
G01X685667Y81987D02*
X684913D01*
G01X691414D02*
X690660D01*
G01X690749Y81929D02*
X693302D01*
G01X690803Y81830D02*
X695758D01*
G01Y80964D02*
X690803D01*
G01X695155Y80807D02*
X698480D01*
G01X690749Y80354D02*
X693302D01*
G01X684913Y80296D02*
X685667D01*
G01X691414D02*
X690660D01*
G01X699054Y80200D02*
X698857D01*
G01X690354Y79821D02*
X691108D01*
G01X685973D02*
X685219D01*
G01X691019Y79763D02*
X685309D01*
G01X698857Y79436D02*
X699054D01*
G01X684887Y96955D02*
X684913Y96987D01*
G01X684857Y96935D02*
X684887Y96955D01*
G01X684824Y96929D02*
X684857Y96935D01*
G01X685999Y97493D02*
X685973Y97462D01*
G01X686030Y97513D02*
X685999Y97493D01*
G01X686063Y97519D02*
X686030Y97513D01*
G01X691082Y99790D02*
X691108Y99821D01*
G01X691052Y99770D02*
X691082Y99790D01*
G01X691019Y99763D02*
X691052Y99770D01*
G01X690686Y100328D02*
X690660Y100296D01*
G01X690717Y100347D02*
X690686Y100328D01*
G01X690749Y100354D02*
X690717Y100347D01*
G01X684887Y101955D02*
X684913Y101987D01*
G01X684857Y101935D02*
X684887Y101955D01*
G01X684824Y101929D02*
X684857Y101935D01*
G01X685999Y102493D02*
X685973Y102462D01*
G01X686030Y102513D02*
X685999Y102493D01*
G01X686063Y102519D02*
X686030Y102513D01*
G01X691082Y104790D02*
X691108Y104821D01*
G01X691052Y104770D02*
X691082Y104790D01*
G01X691019Y104763D02*
X691052Y104770D01*
G01X690686Y105328D02*
X690660Y105296D01*
G01X690717Y105347D02*
X690686Y105328D01*
G01X690749Y105354D02*
X690717Y105347D01*
G01X684887Y106955D02*
X684913Y106987D01*
G01X684857Y106935D02*
X684887Y106955D01*
G01X684824Y106929D02*
X684857Y106935D01*
G01X685999Y107493D02*
X685973Y107462D01*
G01X686030Y107513D02*
X685999Y107493D01*
G01X686063Y107519D02*
X686030Y107513D01*
G01X691082Y109790D02*
X691108Y109821D01*
G01X691052Y109770D02*
X691082Y109790D01*
G01X691019Y109763D02*
X691052Y109770D01*
G01X690686Y110328D02*
X690660Y110296D01*
G01X690717Y110347D02*
X690686Y110328D01*
G01X690749Y110354D02*
X690717Y110347D01*
G01X684887Y111955D02*
X684913Y111987D01*
G01X684857Y111935D02*
X684887Y111955D01*
G01X684824Y111929D02*
X684857Y111935D01*
G01X691440Y96955D02*
X691414Y96987D01*
G01X691470Y96935D02*
X691440Y96955D01*
G01X691504Y96929D02*
X691470Y96935D01*
G01X690328Y97493D02*
X690354Y97462D01*
G01X690298Y97513D02*
X690328Y97493D01*
G01X690265Y97519D02*
X690298Y97513D01*
G01X685245Y99790D02*
X685219Y99821D01*
G01X685276Y99770D02*
X685245Y99790D01*
G01X685309Y99763D02*
X685276Y99770D01*
G01X685641Y100328D02*
X685667Y100296D01*
G01X685611Y100347D02*
X685641Y100328D01*
G01X685578Y100354D02*
X685611Y100347D01*
G01X691440Y101955D02*
X691414Y101987D01*
G01X691470Y101935D02*
X691440Y101955D01*
G01X691504Y101929D02*
X691470Y101935D01*
G01X690328Y102493D02*
X690354Y102462D01*
G01X690298Y102513D02*
X690328Y102493D01*
G01X690265Y102519D02*
X690298Y102513D01*
G01X685245Y104790D02*
X685219Y104821D01*
G01X685276Y104770D02*
X685245Y104790D01*
G01X685309Y104763D02*
X685276Y104770D01*
G01X685641Y105328D02*
X685667Y105296D01*
G01X685611Y105347D02*
X685641Y105328D01*
G01X685578Y105354D02*
X685611Y105347D01*
G01X691440Y106955D02*
X691414Y106987D01*
G01X691470Y106935D02*
X691440Y106955D01*
G01X691504Y106929D02*
X691470Y106935D01*
G01X690328Y107493D02*
X690354Y107462D01*
G01X690298Y107513D02*
X690328Y107493D01*
G01X690265Y107519D02*
X690298Y107513D01*
G01X685245Y109790D02*
X685219Y109821D01*
G01X685276Y109770D02*
X685245Y109790D01*
G01X685309Y109763D02*
X685276Y109770D01*
G01X685641Y110328D02*
X685667Y110296D01*
G01X685611Y110347D02*
X685641Y110328D01*
G01X685578Y110354D02*
X685611Y110347D01*
G01X691440Y111955D02*
X691414Y111987D01*
G01X691470Y111935D02*
X691440Y111955D01*
G01X691504Y111929D02*
X691470Y111935D01*
G01X684857Y100347D02*
X684824Y100354D01*
G01X684887Y100328D02*
X684857Y100347D01*
G01X684913Y100296D02*
X684887Y100328D01*
G01X686030Y99770D02*
X686063Y99763D01*
G01X685999Y99790D02*
X686030Y99770D01*
G01X685973Y99821D02*
X685999Y99790D01*
G01X690717Y96935D02*
X690749Y96929D01*
G01X690686Y96955D02*
X690717Y96935D01*
G01X690660Y96987D02*
X690686Y96955D01*
G01X691052Y97513D02*
X691019Y97519D01*
G01X691082Y97493D02*
X691052Y97513D01*
G01X691108Y97462D02*
X691082Y97493D01*
G01X684857Y105347D02*
X684824Y105354D01*
G01X684887Y105328D02*
X684857Y105347D01*
G01X684913Y105296D02*
X684887Y105328D01*
G01X686030Y104770D02*
X686063Y104763D01*
G01X685999Y104790D02*
X686030Y104770D01*
G01X685973Y104821D02*
X685999Y104790D01*
G01X690717Y101935D02*
X690749Y101929D01*
G01X690686Y101955D02*
X690717Y101935D01*
G01X690660Y101987D02*
X690686Y101955D01*
G01X691052Y102513D02*
X691019Y102519D01*
G01X691082Y102493D02*
X691052Y102513D01*
G01X691108Y102462D02*
X691082Y102493D01*
G01X684857Y110347D02*
X684824Y110354D01*
G01X684887Y110328D02*
X684857Y110347D01*
G01X684913Y110296D02*
X684887Y110328D01*
G01X686030Y109770D02*
X686063Y109763D01*
G01X685999Y109790D02*
X686030Y109770D01*
G01X685973Y109821D02*
X685999Y109790D01*
G01X690717Y106935D02*
X690749Y106929D01*
G01X690686Y106955D02*
X690717Y106935D01*
G01X690660Y106987D02*
X690686Y106955D01*
G01X691052Y107513D02*
X691019Y107519D01*
G01X691082Y107493D02*
X691052Y107513D01*
G01X691108Y107462D02*
X691082Y107493D01*
G01X690717Y111935D02*
X690749Y111929D01*
G01X690686Y111955D02*
X690717Y111935D01*
G01X690660Y111987D02*
X690686Y111955D01*
G01X685611Y111935D02*
X685578Y111929D01*
G01X685641Y111955D02*
X685611Y111935D01*
G01X685667Y111987D02*
X685641Y111955D01*
G01X685276Y107513D02*
X685309Y107519D01*
G01X685245Y107493D02*
X685276Y107513D01*
G01X685219Y107462D02*
X685245Y107493D01*
G01X685611Y106935D02*
X685578Y106929D01*
G01X685641Y106955D02*
X685611Y106935D01*
G01X685667Y106987D02*
X685641Y106955D01*
G01X690298Y109770D02*
X690265Y109763D01*
G01X690328Y109790D02*
X690298Y109770D01*
G01X690354Y109821D02*
X690328Y109790D01*
G01X691470Y110347D02*
X691504Y110354D01*
G01X691440Y110328D02*
X691470Y110347D01*
G01X691414Y110296D02*
X691440Y110328D01*
G01X685276Y102513D02*
X685309Y102519D01*
G01X685245Y102493D02*
X685276Y102513D01*
G01X685219Y102462D02*
X685245Y102493D01*
G01X685611Y101935D02*
X685578Y101929D01*
G01X685641Y101955D02*
X685611Y101935D01*
G01X685667Y101987D02*
X685641Y101955D01*
G01X690298Y104770D02*
X690265Y104763D01*
G01X690328Y104790D02*
X690298Y104770D01*
G01X690354Y104821D02*
X690328Y104790D01*
G01X691470Y105347D02*
X691504Y105354D01*
G01X691440Y105328D02*
X691470Y105347D01*
G01X691414Y105296D02*
X691440Y105328D01*
G01X685276Y97513D02*
X685309Y97519D01*
G01X685245Y97493D02*
X685276Y97513D01*
G01X685219Y97462D02*
X685245Y97493D01*
G01X685611Y96935D02*
X685578Y96929D01*
G01X685641Y96955D02*
X685611Y96935D01*
G01X685667Y96987D02*
X685641Y96955D01*
G01X690298Y99770D02*
X690265Y99763D01*
G01X690328Y99790D02*
X690298Y99770D01*
G01X690354Y99821D02*
X690328Y99790D01*
G01X691470Y100347D02*
X691504Y100354D01*
G01X691440Y100328D02*
X691470Y100347D01*
G01X691414Y100296D02*
X691440Y100328D01*
G01X698857Y112224D02*
G03X698480Y112303I-197J0D01*
G01Y107185D02*
G03X698857Y107264I180J79D01*
G01Y105925D02*
G03X698480Y106004I-197J0D01*
G01Y100885D02*
G03X698857Y100965I180J79D01*
G01X698480Y110334D02*
G03X698857Y110413I180J79D01*
G01Y109074D02*
G03X698480Y109153I-197J0D01*
G01X698857Y102775D02*
G03X698480Y102854I-197J0D01*
G01Y104035D02*
G03X698857Y104114I180J79D01*
G01X698480Y97736D02*
G03X698857Y97815I180J79D01*
G01Y96476D02*
G03X698480Y96555I-197J0D01*
G01X698857Y99626D02*
G03X698480Y99704I-197J-1D01*
G01X693498Y110157D02*
G03X693302Y110354I-197J0D01*
G01Y111929D02*
G03X693498Y112126I-1J197D01*
G01Y100157D02*
G03X693302Y100354I-197J0D01*
G01Y101929D02*
G03X693498Y102126I-1J197D01*
G01Y105157D02*
G03X693302Y105354I-197J0D01*
G01Y106929D02*
G03X693498Y107126I-1J197D01*
G01X693302Y96929D02*
G03X693498Y97126I-1J197D01*
G01X691108Y99821D02*
X691414Y100296D01*
G01X690660D02*
X690354Y99821D01*
G01X691108Y104821D02*
X691414Y105296D01*
G01X685973Y97462D02*
X685667Y96987D01*
G01X690660Y105296D02*
X690354Y104821D01*
G01X684913Y96987D02*
X685219Y97462D01*
G01X691108Y109821D02*
X691414Y110296D01*
G01X685973Y102462D02*
X685667Y101987D01*
G01X690660Y110296D02*
X690354Y109821D01*
G01X684913Y101987D02*
X685219Y102462D01*
G01X685973Y107462D02*
X685667Y106987D01*
G01X684913D02*
X685219Y107462D01*
G01X685973Y112462D02*
X685667Y111987D01*
G01X695837Y97736D02*
X695758Y97578D01*
G01X695076D02*
X695155Y97736D01*
G01X695837Y100885D02*
X695758Y100728D01*
G01X695076D02*
X695155Y100885D01*
G01X695837Y104035D02*
X695758Y103878D01*
G01X695076D02*
X695155Y104035D01*
G01X695837Y107185D02*
X695758Y107027D01*
G01X695076D02*
X695155Y107185D01*
G01X695837Y110334D02*
X695758Y110177D01*
G01X695076D02*
X695155Y110334D01*
G01X684913Y111987D02*
X685219Y112462D01*
G01X698857Y110413D02*
Y110932D01*
G01Y111696D02*
Y112224D01*
G01Y108546D02*
Y109074D01*
G01Y107264D02*
Y107783D01*
G01Y105397D02*
Y105925D01*
G01Y104114D02*
Y104633D01*
G01Y100965D02*
Y101483D01*
G01Y102247D02*
Y102775D01*
G01Y99098D02*
Y99626D01*
G01Y97815D02*
Y98334D01*
G01Y95948D02*
Y96476D01*
G01X698249Y97736D02*
Y96555D01*
G01Y100885D02*
Y99704D01*
G01Y104035D02*
Y102854D01*
G01Y107185D02*
Y106004D01*
G01Y110334D02*
Y109153D01*
G01X697397D02*
Y110334D01*
G01Y106004D02*
Y107185D01*
G01Y102854D02*
Y104035D01*
G01Y99704D02*
Y100885D01*
G01Y96555D02*
Y97736D01*
G01X696715D02*
Y96555D01*
G01Y100885D02*
Y99704D01*
G01Y104035D02*
Y102854D01*
G01Y107185D02*
Y106004D01*
G01Y110334D02*
Y109153D01*
G01X695093Y97578D02*
Y96712D01*
G01Y100728D02*
Y99862D01*
G01Y103878D02*
Y103011D01*
G01Y107027D02*
Y106161D01*
G01Y110177D02*
Y109311D01*
G01X694411D02*
Y110177D01*
G01Y106161D02*
Y107027D01*
G01Y103011D02*
Y103878D01*
G01Y99862D02*
Y100728D01*
G01Y96712D02*
Y97578D01*
G01X693559D02*
Y96712D01*
G01Y100728D02*
Y99862D01*
G01Y103878D02*
Y103011D01*
G01Y107027D02*
Y106161D01*
G01Y110177D02*
Y109311D01*
G01X693498Y112126D02*
Y113110D01*
G01Y109173D02*
Y110157D01*
G01Y104173D02*
Y105157D01*
G01Y102126D02*
Y103110D01*
G01Y97126D02*
Y98110D01*
G01Y100157D02*
Y99173D01*
G01Y108110D02*
Y107126D01*
G01X692711Y105354D02*
Y106929D01*
G01Y100354D02*
Y101929D01*
G01Y111929D02*
Y110354D01*
G01X691957Y101929D02*
Y100354D01*
G01Y106929D02*
Y105354D01*
G01Y111929D02*
Y110354D01*
G01X691203D02*
Y111929D01*
G01Y105354D02*
Y106929D01*
G01Y101929D02*
Y100354D01*
G01X690803Y103011D02*
Y103878D01*
G01Y97578D02*
Y96712D01*
G01Y100728D02*
Y99862D01*
G01Y107027D02*
Y106161D01*
G01Y110177D02*
Y109311D01*
G01X685100Y110354D02*
Y111929D01*
G01Y105354D02*
Y106929D01*
G01Y100354D02*
Y101929D01*
G01X684346D02*
Y100354D01*
G01Y106929D02*
Y105354D01*
G01Y111929D02*
Y110354D01*
G01X683593Y101929D02*
Y100354D01*
G01Y106929D02*
Y105354D01*
G01Y111929D02*
Y110354D01*
G01X695758Y109311D02*
X695837Y109153D01*
G01X695155D02*
X695076Y109311D01*
G01X695758Y106161D02*
X695837Y106004D01*
G01X695155D02*
X695076Y106161D01*
G01X695758Y103011D02*
X695837Y102854D01*
G01X695155D02*
X695076Y103011D01*
G01X695758Y99862D02*
X695837Y99704D01*
G01X695155D02*
X695076Y99862D01*
G01X695758Y96712D02*
X695837Y96555D01*
G01X695155D02*
X695076Y96712D01*
G01X691414Y111987D02*
X691108Y112462D01*
G01X690354D02*
X690660Y111987D01*
G01X691414Y106987D02*
X691108Y107462D01*
G01X690354D02*
X690660Y106987D01*
G01X691414Y101987D02*
X691108Y102462D01*
G01X685667Y110296D02*
X685973Y109821D01*
G01X690354Y102462D02*
X690660Y101987D01*
G01X685219Y109821D02*
X684913Y110296D01*
G01X691414Y96987D02*
X691108Y97462D01*
G01X685667Y105296D02*
X685973Y104821D01*
G01X690354Y97462D02*
X690660Y96987D01*
G01X685219Y104821D02*
X684913Y105296D01*
G01X685667Y100296D02*
X685973Y99821D01*
G01X685219D02*
X684913Y100296D01*
G01X685667Y111987D02*
X684913D01*
G01X691414D02*
X690660D01*
G01X690749Y111929D02*
X693302D01*
G01X699054Y111696D02*
X698857D01*
G01Y110932D02*
X699054D01*
G01X690749Y110354D02*
X693302D01*
G01X695155Y110334D02*
X698480D01*
G01X684913Y110296D02*
X685667D01*
G01X691414D02*
X690660D01*
G01X690803Y110177D02*
X695758D01*
G01X690354Y109821D02*
X691108D01*
G01X685973D02*
X685219D01*
G01X691019Y109763D02*
X685309D01*
G01X695758Y109311D02*
X690803D01*
G01X696850Y109173D02*
X693498D01*
G01X695155Y109153D02*
X698480D01*
G01X699054Y108546D02*
X698857D01*
G01X693498Y108110D02*
X696850D01*
G01X698857Y107783D02*
X699054D01*
G01X685309Y107519D02*
X691019D01*
G01X685973Y107462D02*
X685219D01*
G01X691108D02*
X690354D01*
G01X695155Y107185D02*
X698480D01*
G01X690803Y107027D02*
X695758D01*
G01X684913Y106987D02*
X685667D01*
G01X691414D02*
X690660D01*
G01X690749Y106929D02*
X693302D01*
G01X695758Y106161D02*
X690803D01*
G01X695155Y106004D02*
X698480D01*
G01X699054Y105397D02*
X698857D01*
G01X690749Y105354D02*
X693302D01*
G01X684913Y105296D02*
X685667D01*
G01X691414D02*
X690660D01*
G01X690354Y104821D02*
X691108D01*
G01X685973D02*
X685219D01*
G01X691019Y104763D02*
X685309D01*
G01X699054Y104633D02*
X698857D01*
G01X696850Y104173D02*
X693498D01*
G01X695155Y104035D02*
X698480D01*
G01X690803Y103878D02*
X695758D01*
G01X693498Y103110D02*
X696850D01*
G01X695758Y103011D02*
X690803D01*
G01X695155Y102854D02*
X698480D01*
G01X685309Y102519D02*
X691019D01*
G01X690354Y102462D02*
X691108D01*
G01X685973D02*
X685219D01*
G01X699054Y102247D02*
X698857D01*
G01X685667Y101987D02*
X684913D01*
G01X691414D02*
X690660D01*
G01X690749Y101929D02*
X693302D01*
G01X698857Y101483D02*
X699054D01*
G01X695155Y100885D02*
X698480D01*
G01X690803Y100728D02*
X695758D01*
G01X690749Y100354D02*
X693302D01*
G01X684913Y100296D02*
X685667D01*
G01X691414D02*
X690660D01*
G01X695758Y99862D02*
X690803D01*
G01X690354Y99821D02*
X691108D01*
G01X685973D02*
X685219D01*
G01X691019Y99763D02*
X685309D01*
G01X695155Y99704D02*
X698480D01*
G01X696850Y99173D02*
X693498D01*
G01X699054Y99098D02*
X698857D01*
G01Y98334D02*
X699054D01*
G01X693498Y98110D02*
X696850D01*
G01X695155Y97736D02*
X698480D01*
G01X690803Y97578D02*
X695758D01*
G01X685309Y97519D02*
X691019D01*
G01X690354Y97462D02*
X691108D01*
G01X685973D02*
X685219D01*
G01X685667Y96987D02*
X684913D01*
G01X691414D02*
X690660D01*
G01X690749Y96929D02*
X693302D01*
G01X695758Y96712D02*
X690803D01*
G01X695155Y96555D02*
X698480D01*
G01X699054Y95948D02*
X698857D01*
G01X685999Y112493D02*
X685973Y112462D01*
G01X686030Y112513D02*
X685999Y112493D01*
G01X686063Y112519D02*
X686030Y112513D01*
G01X691082Y114790D02*
X691108Y114821D01*
G01X691052Y114770D02*
X691082Y114790D01*
G01X691019Y114763D02*
X691052Y114770D01*
G01X690686Y115328D02*
X690660Y115296D01*
G01X690717Y115347D02*
X690686Y115328D01*
G01X690749Y115354D02*
X690717Y115347D01*
G01X684887Y116955D02*
X684913Y116987D01*
G01X684857Y116935D02*
X684887Y116955D01*
G01X684824Y116929D02*
X684857Y116935D01*
G01X685999Y117493D02*
X685973Y117462D01*
G01X686030Y117513D02*
X685999Y117493D01*
G01X686063Y117519D02*
X686030Y117513D01*
G01X693593Y119908D02*
X693619Y119939D01*
G01X693563Y119888D02*
X693593Y119908D01*
G01X693530Y119882D02*
X693563Y119888D01*
G01X693094Y120052D02*
X693069Y120021D01*
G01X693125Y120072D02*
X693094Y120052D01*
G01X693158Y120078D02*
X693125Y120072D01*
G01X684892Y121128D02*
X684918Y121160D01*
G01X684861Y121109D02*
X684892Y121128D01*
G01X684828Y121102D02*
X684861Y121109D01*
G01X685701Y121430D02*
X685675Y121399D01*
G01X685731Y121450D02*
X685701Y121430D01*
G01X685764Y121456D02*
X685731Y121450D01*
G01X684892Y124278D02*
X684918Y124309D01*
G01X684861Y124258D02*
X684892Y124278D01*
G01X684828Y124252D02*
X684861Y124258D01*
G01X685701Y124580D02*
X685675Y124548D01*
G01X685731Y124599D02*
X685701Y124580D01*
G01X685764Y124606D02*
X685731Y124599D01*
G01X684892Y127428D02*
X684918Y127459D01*
G01X684861Y127408D02*
X684892Y127428D01*
G01X684828Y127401D02*
X684861Y127408D01*
G01X685701Y127729D02*
X685675Y127698D01*
G01X685731Y127749D02*
X685701Y127729D01*
G01X685764Y127756D02*
X685731Y127749D01*
G01X690328Y112493D02*
X690354Y112462D01*
G01X690298Y112513D02*
X690328Y112493D01*
G01X690265Y112519D02*
X690298Y112513D01*
G01X685245Y114790D02*
X685219Y114821D01*
G01X685276Y114770D02*
X685245Y114790D01*
G01X685309Y114763D02*
X685276Y114770D01*
G01X685641Y115328D02*
X685667Y115296D01*
G01X685611Y115347D02*
X685641Y115328D01*
G01X685578Y115354D02*
X685611Y115347D01*
G01X691440Y116955D02*
X691414Y116987D01*
G01X691470Y116935D02*
X691440Y116955D01*
G01X691504Y116929D02*
X691470Y116935D01*
G01X690328Y117493D02*
X690354Y117462D01*
G01X690298Y117513D02*
X690328Y117493D01*
G01X690265Y117519D02*
X690298Y117513D01*
G01X685098Y119908D02*
X685072Y119939D01*
G01X685128Y119888D02*
X685098Y119908D01*
G01X685161Y119882D02*
X685128Y119888D01*
G01X685495Y120209D02*
X685521Y120178D01*
G01X685464Y120229D02*
X685495Y120209D01*
G01X685431Y120236D02*
X685464Y120229D01*
G01X693698Y121286D02*
X693672Y121317D01*
G01X693728Y121266D02*
X693698Y121286D01*
G01X693761Y121259D02*
X693728Y121266D01*
G01X685098Y123058D02*
X685072Y123089D01*
G01X685128Y123038D02*
X685098Y123058D01*
G01X685161Y123031D02*
X685128Y123038D01*
G01X692990Y121430D02*
X693016Y121399D01*
G01X692959Y121450D02*
X692990Y121430D01*
G01X692926Y121456D02*
X692959Y121450D01*
G01X685495Y123359D02*
X685521Y123328D01*
G01X685464Y123379D02*
X685495Y123359D01*
G01X685431Y123385D02*
X685464Y123379D01*
G01X685098Y126207D02*
X685072Y126239D01*
G01X685128Y126187D02*
X685098Y126207D01*
G01X685161Y126181D02*
X685128Y126187D01*
G01X685495Y126509D02*
X685521Y126478D01*
G01X685464Y126528D02*
X685495Y126509D01*
G01X685431Y126535D02*
X685464Y126528D01*
G01X684857Y115347D02*
X684824Y115354D01*
G01X684887Y115328D02*
X684857Y115347D01*
G01X684913Y115296D02*
X684887Y115328D01*
G01X686030Y114770D02*
X686063Y114763D01*
G01X685999Y114790D02*
X686030Y114770D01*
G01X685973Y114821D02*
X685999Y114790D01*
G01X691052Y112513D02*
X691019Y112519D01*
G01X691082Y112493D02*
X691052Y112513D01*
G01X691108Y112462D02*
X691082Y112493D01*
G01X684861Y120229D02*
X684828Y120236D01*
G01X684892Y120209D02*
X684861Y120229D01*
G01X684918Y120178D02*
X684892Y120209D01*
G01X685731Y119888D02*
X685764Y119882D01*
G01X685701Y119908D02*
X685731Y119888D01*
G01X685675Y119939D02*
X685701Y119908D01*
G01X684861Y123379D02*
X684828Y123385D01*
G01X684892Y123359D02*
X684861Y123379D01*
G01X684918Y123328D02*
X684892Y123359D01*
G01X690717Y116935D02*
X690749Y116929D01*
G01X690686Y116955D02*
X690717Y116935D01*
G01X690660Y116987D02*
X690686Y116955D01*
G01X685731Y123038D02*
X685764Y123031D01*
G01X685701Y123058D02*
X685731Y123038D01*
G01X685675Y123089D02*
X685701Y123058D01*
G01X691052Y117513D02*
X691019Y117519D01*
G01X691082Y117493D02*
X691052Y117513D01*
G01X691108Y117462D02*
X691082Y117493D01*
G01X684861Y126528D02*
X684828Y126535D01*
G01X684892Y126509D02*
X684861Y126528D01*
G01X684918Y126478D02*
X684892Y126509D01*
G01X685731Y126187D02*
X685764Y126181D01*
G01X685701Y126207D02*
X685731Y126187D01*
G01X685675Y126239D02*
X685701Y126207D01*
G01X693125Y121266D02*
X693158Y121259D01*
G01X693094Y121286D02*
X693125Y121266D01*
G01X693069Y121317D02*
X693094Y121286D01*
G01X693563Y121450D02*
X693530Y121456D01*
G01X693593Y121430D02*
X693563Y121450D01*
G01X693619Y121399D02*
X693593Y121430D01*
G01X685128Y127749D02*
X685161Y127756D01*
G01X685098Y127729D02*
X685128Y127749D01*
G01X685072Y127698D02*
X685098Y127729D01*
G01X685464Y127408D02*
X685431Y127401D01*
G01X685495Y127428D02*
X685464Y127408D01*
G01X685521Y127459D02*
X685495Y127428D01*
G01X685128Y124599D02*
X685161Y124606D01*
G01X685098Y124580D02*
X685128Y124599D01*
G01X685072Y124548D02*
X685098Y124580D01*
G01X685464Y124258D02*
X685431Y124252D01*
G01X685495Y124278D02*
X685464Y124258D01*
G01X685521Y124309D02*
X685495Y124278D01*
G01X685128Y121450D02*
X685161Y121456D01*
G01X685098Y121430D02*
X685128Y121450D01*
G01X685072Y121399D02*
X685098Y121430D01*
G01X685464Y121109D02*
X685431Y121102D01*
G01X685495Y121128D02*
X685464Y121109D01*
G01X685521Y121160D02*
X685495Y121128D01*
G01X685276Y117513D02*
X685309Y117519D01*
G01X685245Y117493D02*
X685276Y117513D01*
G01X685219Y117462D02*
X685245Y117493D01*
G01X685611Y116935D02*
X685578Y116929D01*
G01X685641Y116955D02*
X685611Y116935D01*
G01X685667Y116987D02*
X685641Y116955D01*
G01X685276Y112513D02*
X685309Y112519D01*
G01X685245Y112493D02*
X685276Y112513D01*
G01X685219Y112462D02*
X685245Y112493D01*
G01X692959Y119888D02*
X692926Y119882D01*
G01X692990Y119908D02*
X692959Y119888D01*
G01X693016Y119939D02*
X692990Y119908D01*
G01X693728Y120072D02*
X693761Y120078D01*
G01X693698Y120052D02*
X693728Y120072D01*
G01X693672Y120021D02*
X693698Y120052D01*
G01X690298Y114770D02*
X690265Y114763D01*
G01X690328Y114790D02*
X690298Y114770D01*
G01X690354Y114821D02*
X690328Y114790D01*
G01X691470Y115347D02*
X691504Y115354D01*
G01X691440Y115328D02*
X691470Y115347D01*
G01X691414Y115296D02*
X691440Y115328D01*
G01X698480Y122933D02*
G03X698857Y123012I180J79D01*
G01X698480Y126082D02*
G03X698857Y126161I180J79D01*
G01Y124822D02*
G03X698480Y124901I-197J0D01*
G01X698857Y127972D02*
G03X698480Y128051I-197J0D01*
G01X698857Y121673D02*
G03X698480Y121752I-197J0D01*
G01Y116633D02*
G03X698857Y116713I180J79D01*
G01Y115374D02*
G03X698480Y115452I-197J-1D01*
G01Y113484D02*
G03X698857Y113563I180J79D01*
G01Y118523D02*
G03X698480Y118602I-197J0D01*
G01Y119783D02*
G03X698857Y119862I180J79D01*
G01X696653Y120000D02*
G03X696276Y120078I-197J-1D01*
G01Y121259D02*
G03X696653Y121338I180J79D01*
G01X696276Y127559D02*
G03X696653Y127637I180J79D01*
G01Y126299D02*
G03X696276Y126378I-197J0D01*
G01Y124409D02*
G03X696653Y124488I180J79D01*
G01Y123149D02*
G03X696276Y123228I-197J0D01*
G01X693498Y115157D02*
G03X693302Y115354I-197J0D01*
G01Y116929D02*
G03X693498Y117126I-1J197D01*
G01X691108Y114821D02*
X691414Y115296D01*
G01X690660D02*
X690354Y114821D01*
G01X693619Y119939D02*
X693672Y120021D01*
G01X693069D02*
X693016Y119939D01*
G01X693582Y123031D02*
X693709Y123228D01*
G01X693106D02*
X692979Y123031D01*
G01X695837Y113484D02*
X695758Y113326D01*
G01X695076D02*
X695155Y113484D01*
G01X695837Y116633D02*
X695758Y116476D01*
G01X695076D02*
X695155Y116633D01*
G01X695837Y119783D02*
X695758Y119626D01*
G01X695076D02*
X695155Y119783D01*
G01X695837Y122933D02*
X695758Y122775D01*
G01X695076D02*
X695155Y122933D01*
G01X695837Y126082D02*
X695758Y125925D01*
G01X695076D02*
X695155Y126082D01*
G01X693582Y126181D02*
X693709Y126378D01*
G01X693106D02*
X692979Y126181D01*
G01X685973Y117462D02*
X685667Y116987D01*
G01X684913D02*
X685219Y117462D01*
G01X685675Y121399D02*
X685521Y121160D01*
G01X684918D02*
X685072Y121399D01*
G01X685675Y124548D02*
X685521Y124309D01*
G01X684918D02*
X685072Y124548D01*
G01X685675Y127698D02*
X685521Y127459D01*
G01X684918D02*
X685072Y127698D01*
G01X698857Y126161D02*
Y126680D01*
G01Y124295D02*
Y124822D01*
G01Y123012D02*
Y123531D01*
G01Y121145D02*
Y121673D01*
G01Y119862D02*
Y120381D01*
G01Y116713D02*
Y117232D01*
G01Y114846D02*
Y115374D01*
G01Y113563D02*
Y114082D01*
G01Y118523D02*
Y117995D01*
G01Y127972D02*
Y127444D01*
G01X698621Y140295D02*
Y116988D01*
G01X698249Y113484D02*
Y112303D01*
G01Y116633D02*
Y115452D01*
G01Y119783D02*
Y118602D01*
G01Y122933D02*
Y121752D01*
G01Y126082D02*
Y124901D01*
G01Y129232D02*
Y128051D01*
G01X697397D02*
Y129232D01*
G01Y124901D02*
Y126082D01*
G01Y121752D02*
Y122933D01*
G01Y118602D02*
Y119783D01*
G01Y115452D02*
Y116633D01*
G01Y112303D02*
Y113484D01*
G01X696715D02*
Y112303D01*
G01Y116633D02*
Y115452D01*
G01Y119783D02*
Y118602D01*
G01Y122933D02*
Y121752D01*
G01Y126082D02*
Y124901D01*
G01Y129232D02*
Y128051D01*
G01X696653Y127637D02*
Y128166D01*
G01Y125780D02*
Y126299D01*
G01Y124488D02*
Y125016D01*
G01Y121338D02*
Y121867D01*
G01Y122630D02*
Y123149D01*
G01Y119480D02*
Y120000D01*
G01X695472Y121259D02*
Y120078D01*
G01Y124409D02*
Y123228D01*
G01Y127559D02*
Y126378D01*
G01X695093Y113326D02*
Y112460D01*
G01Y116476D02*
Y115610D01*
G01Y119626D02*
Y118759D01*
G01Y122775D02*
Y121909D01*
G01Y125925D02*
Y125059D01*
G01Y129074D02*
Y128208D01*
G01X694718Y121259D02*
Y120078D01*
G01Y124409D02*
Y123228D01*
G01Y127559D02*
Y126378D01*
G01X694411Y128208D02*
Y129074D01*
G01Y125059D02*
Y125925D01*
G01Y121909D02*
Y122775D01*
G01Y118759D02*
Y119626D01*
G01Y115610D02*
Y116476D01*
G01Y112460D02*
Y113326D01*
G01X694250Y121574D02*
Y119763D01*
G01Y124724D02*
Y122913D01*
G01Y127874D02*
Y126063D01*
G01X694115Y120078D02*
Y121259D01*
G01Y124409D02*
Y123228D01*
G01Y127559D02*
Y126378D01*
G01X693559Y113326D02*
Y112460D01*
G01Y116476D02*
Y115610D01*
G01Y119626D02*
Y118759D01*
G01Y122775D02*
Y121909D01*
G01Y125925D02*
Y125059D01*
G01Y129074D02*
Y128208D01*
G01X693498Y117126D02*
Y118110D01*
G01Y114173D02*
Y115157D01*
G01X692711Y116929D02*
Y115354D01*
G01X691957Y116929D02*
Y115354D01*
G01X691867Y119536D02*
Y119094D01*
G01Y122686D02*
Y121802D01*
G01Y125835D02*
Y124952D01*
G01Y128985D02*
Y128101D01*
G01X691668Y122913D02*
Y124724D01*
G01Y121574D02*
Y119763D01*
G01Y127874D02*
Y126063D01*
G01X691274D02*
Y127874D01*
G01Y121574D02*
Y119763D01*
G01Y124724D02*
Y122913D01*
G01X691203Y115354D02*
Y116929D01*
G01X690944Y137992D02*
Y119094D01*
G01X690803Y128208D02*
Y129074D01*
G01Y118759D02*
Y119626D01*
G01Y112460D02*
Y113326D01*
G01Y116476D02*
Y115610D01*
G01Y122775D02*
Y121909D01*
G01Y125925D02*
Y125059D01*
G01X685100Y115354D02*
Y116929D01*
G01X684346D02*
Y115354D01*
G01X684267Y126535D02*
Y127401D01*
G01Y123385D02*
Y124252D01*
G01Y120236D02*
Y121102D01*
G01X683664Y126535D02*
Y127401D01*
G01Y123385D02*
Y124252D01*
G01Y120236D02*
Y121102D01*
G01X683593Y116929D02*
Y115354D01*
G01X695758Y128208D02*
X695837Y128051D01*
G01X695155D02*
X695076Y128208D01*
G01X695758Y125059D02*
X695837Y124901D01*
G01X695155D02*
X695076Y125059D01*
G01X695758Y121909D02*
X695837Y121752D01*
G01X695155D02*
X695076Y121909D01*
G01X695758Y118759D02*
X695837Y118602D01*
G01X695155D02*
X695076Y118759D01*
G01X692424Y119763D02*
X691867Y119536D01*
G01X692424Y122913D02*
X691867Y122686D01*
G01X692424Y126063D02*
X691867Y125835D01*
G01X695758Y115610D02*
X695837Y115452D01*
G01X695155D02*
X695076Y115610D01*
G01X695758Y112460D02*
X695837Y112303D01*
G01X695155D02*
X695076Y112460D01*
G01X693709Y127559D02*
X693582Y127756D01*
G01X692979D02*
X693106Y127559D01*
G01X693709Y124409D02*
X693582Y124606D01*
G01X692979D02*
X693106Y124409D01*
G01X693672Y121317D02*
X693619Y121399D01*
G01X693016D02*
X693069Y121317D01*
G01X685521Y126478D02*
X685675Y126239D01*
G01X691414Y116987D02*
X691108Y117462D01*
G01X685072Y126239D02*
X684918Y126478D01*
G01X690354Y117462D02*
X690660Y116987D01*
G01X685521Y123328D02*
X685675Y123089D01*
G01X685072D02*
X684918Y123328D01*
G01X685521Y120178D02*
X685675Y119939D01*
G01X685072D02*
X684918Y120178D01*
G01X685667Y115296D02*
X685973Y114821D01*
G01X685219D02*
X684913Y115296D01*
G01X691867Y128101D02*
X692424Y127874D01*
G01X691867Y124952D02*
X692424Y124724D01*
G01X691867Y121802D02*
X692424Y121574D01*
G01X695758Y128208D02*
X690803D01*
G01X696653Y128166D02*
X696850D01*
G01X691867Y128101D02*
X690944D01*
G01X695155Y128051D02*
X698480D01*
G01X694250Y127874D02*
X690944D01*
G01X685161Y127756D02*
X693582D01*
G01X685072Y127698D02*
X685675D01*
G01X693106Y127559D02*
X696276D01*
G01X685521Y127459D02*
X684918D01*
G01X698857Y127444D02*
X699054D01*
G01X698857Y126680D02*
X699054D01*
G01X684918Y126478D02*
X685521D01*
G01X693106Y126378D02*
X696276D01*
G01X685675Y126239D02*
X685072D01*
G01X685161Y126181D02*
X693582D01*
G01X695155Y126082D02*
X698480D01*
G01X690944Y126063D02*
X694250D01*
G01X690803Y125925D02*
X695758D01*
G01X691867Y125835D02*
X690944D01*
G01X696850Y125780D02*
X696653D01*
G01X695758Y125059D02*
X690803D01*
G01X696653Y125016D02*
X696850D01*
G01X690944Y124952D02*
X691867D01*
G01X695155Y124901D02*
X698480D01*
G01X694250Y124724D02*
X690944D01*
G01X685161Y124606D02*
X693582D01*
G01X685072Y124548D02*
X685675D01*
G01X693106Y124409D02*
X696276D01*
G01X685521Y124309D02*
X684918D01*
G01X699054Y124295D02*
X698857D01*
G01Y123531D02*
X699054D01*
G01X684918Y123328D02*
X685521D01*
G01X693106Y123228D02*
X696276D01*
G01X685675Y123089D02*
X685072D01*
G01X685161Y123031D02*
X693582D01*
G01X695155Y122933D02*
X698480D01*
G01X690944Y122913D02*
X694250D01*
G01X690803Y122775D02*
X695758D01*
G01X691867Y122686D02*
X690944D01*
G01X696850Y122630D02*
X696653D01*
G01X695758Y121909D02*
X690803D01*
G01X696850Y121867D02*
X696653D01*
G01X690944Y121802D02*
X691867D01*
G01X695155Y121752D02*
X698480D01*
G01X694250Y121574D02*
X690944D01*
G01X685161Y121456D02*
X693530D01*
G01X685072Y121399D02*
X685675D01*
G01X693619D02*
X693016D01*
G01X693069Y121317D02*
X693672D01*
G01X693158Y121259D02*
X696276D01*
G01X685521Y121160D02*
X684918D01*
G01X699054Y121145D02*
X698857D01*
G01X699054Y120381D02*
X698857D01*
G01X684918Y120178D02*
X685521D01*
G01X693158Y120078D02*
X696276D01*
G01X693672Y120021D02*
X693069D01*
G01X693016Y119939D02*
X693619D01*
G01X685675D02*
X685072D01*
G01X685161Y119882D02*
X693530D01*
G01X695155Y119783D02*
X698480D01*
G01X690944Y119763D02*
X694250D01*
G01X690803Y119626D02*
X695758D01*
G01X690944Y119536D02*
X691867D01*
G01X696850Y119480D02*
X696653D01*
G01X696850Y119094D02*
X690944D01*
G01X695758Y118759D02*
X690803D01*
G01X695155Y118602D02*
X698480D01*
G01X693498Y118110D02*
X696850D01*
G01X698857Y117995D02*
X699054D01*
G01X685309Y117519D02*
X691019D01*
G01X685973Y117462D02*
X685219D01*
G01X691108D02*
X690354D01*
G01X698857Y117232D02*
X699054D01*
G01Y116988D02*
X698621D01*
G01X684913Y116987D02*
X685667D01*
G01X691414D02*
X690660D01*
G01X690749Y116929D02*
X693302D01*
G01X695155Y116633D02*
X698480D01*
G01X690803Y116476D02*
X695758D01*
G01Y115610D02*
X690803D01*
G01X695155Y115452D02*
X698480D01*
G01X690749Y115354D02*
X693302D01*
G01X684913Y115296D02*
X685667D01*
G01X691414D02*
X690660D01*
G01X699054Y114846D02*
X698857D01*
G01X690354Y114821D02*
X691108D01*
G01X685973D02*
X685219D01*
G01X691019Y114763D02*
X685309D01*
G01X693498Y114173D02*
X696850D01*
G01X699054Y114082D02*
X698857D01*
G01X695155Y113484D02*
X698480D01*
G01X690803Y113326D02*
X695758D01*
G01X693498Y113110D02*
X696850D01*
G01X685309Y112519D02*
X691019D01*
G01X690354Y112462D02*
X690803Y112460D01*
G01X685973Y112462D02*
X685219D01*
G01X695758Y112460D02*
X690803D01*
G01X695155Y112303D02*
X698480D01*
G01X693593Y129357D02*
X693619Y129388D01*
G01X693563Y129337D02*
X693593Y129357D01*
G01X693530Y129330D02*
X693563Y129337D01*
G01X693094Y129501D02*
X693069Y129470D01*
G01X693125Y129520D02*
X693094Y129501D01*
G01X693158Y129527D02*
X693125Y129520D01*
G01X684892Y130577D02*
X684918Y130609D01*
G01X684861Y130558D02*
X684892Y130577D01*
G01X684828Y130551D02*
X684861Y130558D01*
G01X685701Y130879D02*
X685675Y130848D01*
G01X685731Y130898D02*
X685701Y130879D01*
G01X685764Y130905D02*
X685731Y130898D01*
G01X684892Y133727D02*
X684918Y133758D01*
G01X684861Y133707D02*
X684892Y133727D01*
G01X684828Y133700D02*
X684861Y133707D01*
G01X685701Y134028D02*
X685675Y133997D01*
G01X685731Y134048D02*
X685701Y134028D01*
G01X685764Y134055D02*
X685731Y134048D01*
G01X684892Y136876D02*
X684918Y136908D01*
G01X684861Y136857D02*
X684892Y136876D01*
G01X684828Y136850D02*
X684861Y136857D01*
G01X685701Y137178D02*
X685675Y137147D01*
G01X685731Y137198D02*
X685701Y137178D01*
G01X685764Y137204D02*
X685731Y137198D01*
G01X691082Y139790D02*
X691108Y139821D01*
G01X691052Y139770D02*
X691082Y139790D01*
G01X691019Y139763D02*
X691052Y139770D01*
G01X690686Y140328D02*
X690660Y140296D01*
G01X690717Y140347D02*
X690686Y140328D01*
G01X690749Y140354D02*
X690717Y140347D01*
G01X684887Y141955D02*
X684913Y141987D01*
G01X684857Y141935D02*
X684887Y141955D01*
G01X684824Y141929D02*
X684857Y141935D01*
G01X685999Y142493D02*
X685973Y142462D01*
G01X686030Y142513D02*
X685999Y142493D01*
G01X686063Y142519D02*
X686030Y142513D01*
G01X691082Y144790D02*
X691108Y144821D01*
G01X691052Y144770D02*
X691082Y144790D01*
G01X691019Y144763D02*
X691052Y144770D01*
G01X685098Y129357D02*
X685072Y129388D01*
G01X685128Y129337D02*
X685098Y129357D01*
G01X685161Y129330D02*
X685128Y129337D01*
G01X685495Y129658D02*
X685521Y129627D01*
G01X685464Y129678D02*
X685495Y129658D01*
G01X685431Y129685D02*
X685464Y129678D01*
G01X693698Y130735D02*
X693672Y130766D01*
G01X693728Y130715D02*
X693698Y130735D01*
G01X693761Y130708D02*
X693728Y130715D01*
G01X685098Y132506D02*
X685072Y132538D01*
G01X685128Y132487D02*
X685098Y132506D01*
G01X685161Y132480D02*
X685128Y132487D01*
G01X692990Y130879D02*
X693016Y130848D01*
G01X692959Y130898D02*
X692990Y130879D01*
G01X692926Y130905D02*
X692959Y130898D01*
G01X685495Y132808D02*
X685521Y132777D01*
G01X685464Y132828D02*
X685495Y132808D01*
G01X685431Y132834D02*
X685464Y132828D01*
G01X685098Y135656D02*
X685072Y135687D01*
G01X685128Y135636D02*
X685098Y135656D01*
G01X685161Y135630D02*
X685128Y135636D01*
G01X685495Y135958D02*
X685521Y135926D01*
G01X685464Y135977D02*
X685495Y135958D01*
G01X685431Y135984D02*
X685464Y135977D01*
G01X685245Y139790D02*
X685219Y139821D01*
G01X685276Y139770D02*
X685245Y139790D01*
G01X685309Y139763D02*
X685276Y139770D01*
G01X685641Y140328D02*
X685667Y140296D01*
G01X685611Y140347D02*
X685641Y140328D01*
G01X685578Y140354D02*
X685611Y140347D01*
G01X691440Y141955D02*
X691414Y141987D01*
G01X691470Y141935D02*
X691440Y141955D01*
G01X691504Y141929D02*
X691470Y141935D01*
G01X690328Y142493D02*
X690354Y142462D01*
G01X690298Y142513D02*
X690328Y142493D01*
G01X690265Y142519D02*
X690298Y142513D01*
G01X685245Y144790D02*
X685219Y144821D01*
G01X685276Y144770D02*
X685245Y144790D01*
G01X685309Y144763D02*
X685276Y144770D01*
G01X684861Y129678D02*
X684828Y129685D01*
G01X684892Y129658D02*
X684861Y129678D01*
G01X684918Y129627D02*
X684892Y129658D01*
G01X685731Y129337D02*
X685764Y129330D01*
G01X685701Y129357D02*
X685731Y129337D01*
G01X685675Y129388D02*
X685701Y129357D01*
G01X684861Y132828D02*
X684828Y132834D01*
G01X684892Y132808D02*
X684861Y132828D01*
G01X684918Y132777D02*
X684892Y132808D01*
G01X685731Y132487D02*
X685764Y132480D01*
G01X685701Y132506D02*
X685731Y132487D01*
G01X685675Y132538D02*
X685701Y132506D01*
G01X684861Y135977D02*
X684828Y135984D01*
G01X684892Y135958D02*
X684861Y135977D01*
G01X684918Y135926D02*
X684892Y135958D01*
G01X685731Y135636D02*
X685764Y135630D01*
G01X685701Y135656D02*
X685731Y135636D01*
G01X685675Y135687D02*
X685701Y135656D01*
G01X684857Y140347D02*
X684824Y140354D01*
G01X684887Y140328D02*
X684857Y140347D01*
G01X684913Y140296D02*
X684887Y140328D01*
G01X693125Y130715D02*
X693158Y130708D01*
G01X693094Y130735D02*
X693125Y130715D01*
G01X693069Y130766D02*
X693094Y130735D01*
G01X686030Y139770D02*
X686063Y139763D01*
G01X685999Y139790D02*
X686030Y139770D01*
G01X685973Y139821D02*
X685999Y139790D01*
G01X693563Y130898D02*
X693530Y130905D01*
G01X693593Y130879D02*
X693563Y130898D01*
G01X693619Y130848D02*
X693593Y130879D01*
G01X686030Y144770D02*
X686063Y144763D01*
G01X685999Y144790D02*
X686030Y144770D01*
G01X685973Y144821D02*
X685999Y144790D01*
G01X690717Y141935D02*
X690749Y141929D01*
G01X690686Y141955D02*
X690717Y141935D01*
G01X690660Y141987D02*
X690686Y141955D01*
G01X691052Y142513D02*
X691019Y142519D01*
G01X691082Y142493D02*
X691052Y142513D01*
G01X691108Y142462D02*
X691082Y142493D01*
G01X685276Y142513D02*
X685309Y142519D01*
G01X685245Y142493D02*
X685276Y142513D01*
G01X685219Y142462D02*
X685245Y142493D01*
G01X685611Y141935D02*
X685578Y141929D01*
G01X685641Y141955D02*
X685611Y141935D01*
G01X685667Y141987D02*
X685641Y141955D01*
G01X690298Y144770D02*
X690265Y144763D01*
G01X690328Y144790D02*
X690298Y144770D01*
G01X690354Y144821D02*
X690328Y144790D01*
G01X685128Y137198D02*
X685161Y137204D01*
G01X685098Y137178D02*
X685128Y137198D01*
G01X685072Y137147D02*
X685098Y137178D01*
G01X685464Y136857D02*
X685431Y136850D01*
G01X685495Y136876D02*
X685464Y136857D01*
G01X685521Y136908D02*
X685495Y136876D01*
G01X685128Y134048D02*
X685161Y134055D01*
G01X685098Y134028D02*
X685128Y134048D01*
G01X685072Y133997D02*
X685098Y134028D01*
G01X690298Y139770D02*
X690265Y139763D01*
G01X690328Y139790D02*
X690298Y139770D01*
G01X690354Y139821D02*
X690328Y139790D01*
G01X685464Y133707D02*
X685431Y133700D01*
G01X685495Y133727D02*
X685464Y133707D01*
G01X685521Y133758D02*
X685495Y133727D01*
G01X691470Y140347D02*
X691504Y140354D01*
G01X691440Y140328D02*
X691470Y140347D01*
G01X691414Y140296D02*
X691440Y140328D01*
G01X685128Y130898D02*
X685161Y130905D01*
G01X685098Y130879D02*
X685128Y130898D01*
G01X685072Y130848D02*
X685098Y130879D01*
G01X685464Y130558D02*
X685431Y130551D01*
G01X685495Y130577D02*
X685464Y130558D01*
G01X685521Y130609D02*
X685495Y130577D01*
G01X692959Y129337D02*
X692926Y129330D01*
G01X692990Y129357D02*
X692959Y129337D01*
G01X693016Y129388D02*
X692990Y129357D01*
G01X693728Y129520D02*
X693761Y129527D01*
G01X693698Y129501D02*
X693728Y129520D01*
G01X693672Y129470D02*
X693698Y129501D01*
G01X698857Y143720D02*
G03X698480Y143799I-197J0D01*
G01Y144980D02*
G03X698857Y145059I180J79D01*
G01X698480Y141830D02*
G03X698857Y141909I180J79D01*
G01Y140570D02*
G03X698480Y140649I-197J0D01*
G01Y135531D02*
G03X698857Y135610I180J79D01*
G01Y134271D02*
G03X698480Y134350I-197J0D01*
G01X698857Y137421D02*
G03X698480Y137500I-197J0D01*
G01Y138681D02*
G03X698857Y138759I180J79D01*
G01X698480Y132382D02*
G03X698857Y132461I180J79D01*
G01Y131122D02*
G03X698480Y131200I-197J-1D01*
G01Y129232D02*
G03X698857Y129311I180J79D01*
G01X696276Y137008D02*
G03X696653Y137086I180J79D01*
G01Y135748D02*
G03X696276Y135826I-197J-1D01*
G01Y133858D02*
G03X696653Y133937I180J79D01*
G01Y132598D02*
G03X696276Y132677I-197J0D01*
G01X693498Y145157D02*
G03X693302Y145354I-197J0D01*
G01X693498Y140157D02*
G03X693302Y140354I-197J0D01*
G01Y141929D02*
G03X693498Y142126I-1J197D01*
G01X696653Y129448D02*
G03X696276Y129527I-197J0D01*
G01Y130708D02*
G03X696653Y130787I180J79D01*
G01X695837Y129232D02*
X695758Y129074D01*
G01X695076D02*
X695155Y129232D01*
G01X695837Y132382D02*
X695758Y132224D01*
G01X695076D02*
X695155Y132382D01*
G01X693619Y129388D02*
X693672Y129470D01*
G01X693069D02*
X693016Y129388D01*
G01X693582Y132480D02*
X693709Y132677D01*
G01X693106D02*
X692979Y132480D01*
G01X693582Y135630D02*
X693709Y135826D01*
G01X693106D02*
X692979Y135630D01*
G01X685675Y130848D02*
X685521Y130609D01*
G01X691108Y139821D02*
X691414Y140296D01*
G01X684918Y130609D02*
X685072Y130848D01*
G01X690660Y140296D02*
X690354Y139821D01*
G01X685675Y133997D02*
X685521Y133758D01*
G01X684918D02*
X685072Y133997D01*
G01X691108Y144821D02*
X691414Y145296D01*
G01X685675Y137147D02*
X685521Y136908D01*
G01X690660Y145296D02*
X690354Y144821D01*
G01X684918Y136908D02*
X685072Y137147D01*
G01X685973Y142462D02*
X685667Y141987D01*
G01X684913D02*
X685219Y142462D01*
G01X695837Y135531D02*
X695758Y135374D01*
G01X695076D02*
X695155Y135531D01*
G01X695837Y138681D02*
X695758Y138523D01*
G01X695076D02*
X695155Y138681D01*
G01X695837Y141830D02*
X695758Y141673D01*
G01X695076D02*
X695155Y141830D01*
G01X695837Y144980D02*
X695758Y144822D01*
G01X695076D02*
X695155Y144980D01*
G01X698857Y145059D02*
Y145578D01*
G01Y143192D02*
Y143720D01*
G01Y141909D02*
Y142428D01*
G01Y140043D02*
Y140570D01*
G01Y138759D02*
Y139279D01*
G01Y135610D02*
Y136129D01*
G01Y133743D02*
Y134271D01*
G01Y132461D02*
Y132980D01*
G01Y130594D02*
Y131122D01*
G01Y129311D02*
Y129830D01*
G01Y137421D02*
Y136893D01*
G01X698249Y132382D02*
Y131200D01*
G01Y135531D02*
Y134350D01*
G01Y138681D02*
Y137500D01*
G01Y141830D02*
Y140649D01*
G01Y144980D02*
Y143799D01*
G01X697397D02*
Y144980D01*
G01Y140649D02*
Y141830D01*
G01Y137500D02*
Y138681D01*
G01Y134350D02*
Y135531D01*
G01Y131200D02*
Y132382D01*
G01X696715D02*
Y131200D01*
G01Y135531D02*
Y134350D01*
G01Y138681D02*
Y137500D01*
G01Y141830D02*
Y140649D01*
G01Y144980D02*
Y143799D01*
G01X696653Y137086D02*
Y137615D01*
G01Y135228D02*
Y135748D01*
G01Y133937D02*
Y134465D01*
G01Y132079D02*
Y132598D01*
G01Y130787D02*
Y131315D01*
G01Y128929D02*
Y129448D01*
G01X695472Y130708D02*
Y129527D01*
G01Y133858D02*
Y132677D01*
G01Y137008D02*
Y135826D01*
G01X695093Y132224D02*
Y131358D01*
G01Y135374D02*
Y134508D01*
G01Y138523D02*
Y137657D01*
G01Y141673D02*
Y140807D01*
G01Y144822D02*
Y143956D01*
G01X694718Y130708D02*
Y129527D01*
G01Y133858D02*
Y132677D01*
G01Y137008D02*
Y135826D01*
G01X694411Y143956D02*
Y144822D01*
G01Y140807D02*
Y141673D01*
G01Y137657D02*
Y138523D01*
G01Y134508D02*
Y135374D01*
G01Y131358D02*
Y132224D01*
G01X694250Y131023D02*
Y129212D01*
G01Y134173D02*
Y132362D01*
G01Y137322D02*
Y135511D01*
G01X694115Y129527D02*
Y130708D01*
G01Y133858D02*
Y132677D01*
G01Y137008D02*
Y135826D01*
G01X693559Y132224D02*
Y131358D01*
G01Y135374D02*
Y134508D01*
G01Y138523D02*
Y137657D01*
G01Y141673D02*
Y140807D01*
G01Y144822D02*
Y143956D01*
G01X693498Y144173D02*
Y145157D01*
G01Y142126D02*
Y143110D01*
G01Y140157D02*
Y139173D01*
G01X692711Y140354D02*
Y141929D01*
G01X691957D02*
Y140354D01*
G01X691867Y132135D02*
Y131251D01*
G01Y135284D02*
Y134400D01*
G01Y137992D02*
Y137550D01*
G01X691668Y135511D02*
Y137322D01*
G01Y132362D02*
Y134173D01*
G01Y131023D02*
Y129212D01*
G01X691274D02*
Y131023D01*
G01Y134173D02*
Y132362D01*
G01Y137322D02*
Y135511D01*
G01X691203Y141929D02*
Y140354D01*
G01X690803Y143956D02*
Y144822D01*
G01Y137657D02*
Y138523D01*
G01Y132224D02*
Y131358D01*
G01Y135374D02*
Y134508D01*
G01Y141673D02*
Y140807D01*
G01X685100Y140354D02*
Y141929D01*
G01X684346D02*
Y140354D01*
G01X684267Y135984D02*
Y136850D01*
G01Y132834D02*
Y133700D01*
G01Y129685D02*
Y130551D01*
G01X683664Y135984D02*
Y136850D01*
G01Y132834D02*
Y133700D01*
G01Y129685D02*
Y130551D01*
G01X683593Y141929D02*
Y140354D01*
G01X695758Y143956D02*
X695837Y143799D01*
G01X695155D02*
X695076Y143956D01*
G01X695758Y140807D02*
X695837Y140649D01*
G01X695155D02*
X695076Y140807D01*
G01X695758Y137657D02*
X695837Y137500D01*
G01X695155D02*
X695076Y137657D01*
G01X695758Y134508D02*
X695837Y134350D01*
G01X695155D02*
X695076Y134508D01*
G01X695758Y131358D02*
X695837Y131200D01*
G01X695155D02*
X695076Y131358D01*
G01X692424Y129212D02*
X691867Y128985D01*
G01X691414Y141987D02*
X691108Y142462D01*
G01X690354D02*
X690660Y141987D01*
G01X693709Y137008D02*
X693582Y137204D01*
G01X692979D02*
X693106Y137008D01*
G01X693709Y133858D02*
X693582Y134055D01*
G01X692979D02*
X693106Y133858D01*
G01X685667Y145296D02*
X685973Y144821D01*
G01X685219D02*
X684913Y145296D01*
G01X693672Y130766D02*
X693619Y130848D01*
G01X693016D02*
X693069Y130766D01*
G01X685667Y140296D02*
X685973Y139821D01*
G01X685219D02*
X684913Y140296D01*
G01X685521Y135926D02*
X685675Y135687D01*
G01X685072D02*
X684918Y135926D01*
G01X685521Y132777D02*
X685675Y132538D01*
G01X685072D02*
X684918Y132777D01*
G01X685521Y129627D02*
X685675Y129388D01*
G01X685072D02*
X684918Y129627D01*
G01X692424Y132362D02*
X691867Y132135D01*
G01X692424Y135511D02*
X691867Y135284D01*
G01Y137550D02*
X692424Y137322D01*
G01X691867Y134400D02*
X692424Y134173D01*
G01X691867Y131251D02*
X692424Y131023D01*
G01X695155Y144980D02*
X698480D01*
G01X690803Y144822D02*
X695758D01*
G01X690354Y144821D02*
X690803Y144822D01*
G01X685973Y144821D02*
X685219D01*
G01X691019Y144763D02*
X685309D01*
G01X696850Y144173D02*
X693498D01*
G01X695758Y143956D02*
X690803D01*
G01X695155Y143799D02*
X698480D01*
G01X699054Y143192D02*
X698857D01*
G01X693498Y143110D02*
X696850D01*
G01X685309Y142519D02*
X691019D01*
G01X690354Y142462D02*
X691108D01*
G01X685973D02*
X685219D01*
G01X698857Y142428D02*
X699054D01*
G01X685667Y141987D02*
X684913D01*
G01X691414D02*
X690660D01*
G01X690749Y141929D02*
X693302D01*
G01X695155Y141830D02*
X698480D01*
G01X690803Y141673D02*
X695758D01*
G01Y140807D02*
X690803D01*
G01X695155Y140649D02*
X698480D01*
G01X690749Y140354D02*
X693302D01*
G01X684913Y140296D02*
X685667D01*
G01X691414D02*
X690660D01*
G01X699054Y140295D02*
X698621D01*
G01X699054Y140043D02*
X698857D01*
G01X690354Y139821D02*
X691108D01*
G01X685973D02*
X685219D01*
G01X691019Y139763D02*
X685309D01*
G01X699054Y139279D02*
X698857D01*
G01X696850Y139173D02*
X693498D01*
G01X695155Y138681D02*
X698480D01*
G01X690803Y138523D02*
X695758D01*
G01X690944Y137992D02*
X696850D01*
G01X695758Y137657D02*
X690803D01*
G01X696653Y137615D02*
X696850D01*
G01X691867Y137550D02*
X690944D01*
G01X695155Y137500D02*
X698480D01*
G01X694250Y137322D02*
X690944D01*
G01X685161Y137204D02*
X693582D01*
G01X685072Y137147D02*
X685675D01*
G01X693106Y137008D02*
X696276D01*
G01X685521Y136908D02*
X684918D01*
G01X698857Y136893D02*
X699054D01*
G01X698857Y136129D02*
X699054D01*
G01X684918Y135926D02*
X685521D01*
G01X693106Y135826D02*
X696276D01*
G01X685675Y135687D02*
X685072D01*
G01X685161Y135630D02*
X693582D01*
G01X695155Y135531D02*
X698480D01*
G01X690944Y135511D02*
X694250D01*
G01X690803Y135374D02*
X695758D01*
G01X690944Y135284D02*
X691867D01*
G01X696850Y135228D02*
X696653D01*
G01X695758Y134508D02*
X690803D01*
G01X696653Y134465D02*
X696850D01*
G01X690944Y134400D02*
X691867D01*
G01X695155Y134350D02*
X698480D01*
G01X694250Y134173D02*
X690944D01*
G01X685161Y134055D02*
X693582D01*
G01X685072Y133997D02*
X685675D01*
G01X693106Y133858D02*
X696276D01*
G01X685521Y133758D02*
X684918D01*
G01X699054Y133743D02*
X698857D01*
G01Y132980D02*
X699054D01*
G01X684918Y132777D02*
X685521D01*
G01X693106Y132677D02*
X696276D01*
G01X685675Y132538D02*
X685072D01*
G01X685161Y132480D02*
X693582D01*
G01X695155Y132382D02*
X698480D01*
G01X690944Y132362D02*
X694250D01*
G01X690803Y132224D02*
X695758D01*
G01X690944Y132135D02*
X691867D01*
G01X696850Y132079D02*
X696653D01*
G01X695758Y131358D02*
X690803D01*
G01X696850Y131315D02*
X696653D01*
G01X690944Y131251D02*
X691867D01*
G01X695155Y131200D02*
X698480D01*
G01X694250Y131023D02*
X690944D01*
G01X685161Y130905D02*
X693530D01*
G01X685072Y130848D02*
X685675D01*
G01X693619D02*
X693016D01*
G01X693069Y130766D02*
X693672D01*
G01X693158Y130708D02*
X696276D01*
G01X685521Y130609D02*
X684918D01*
G01X699054Y130594D02*
X698857D01*
G01X699054Y129830D02*
X698857D01*
G01X684918Y129627D02*
X685521D01*
G01X693158Y129527D02*
X696276D01*
G01X693672Y129470D02*
X693069D01*
G01X693016Y129388D02*
X693619D01*
G01X685675D02*
X685072D01*
G01X685161Y129330D02*
X693530D01*
G01X695155Y129232D02*
X698480D01*
G01X690944Y129212D02*
X694250D01*
G01X690803Y129074D02*
X695758D01*
G01X690944Y128985D02*
X691867D01*
G01X696850Y128929D02*
X696653D01*
G01X690686Y145328D02*
X690660Y145296D01*
G01X690717Y145347D02*
X690686Y145328D01*
G01X690749Y145354D02*
X690717Y145347D01*
G01X684887Y146955D02*
X684913Y146987D01*
G01X684857Y146935D02*
X684887Y146955D01*
G01X684824Y146929D02*
X684857Y146935D01*
G01X685999Y147493D02*
X685973Y147462D01*
G01X686030Y147513D02*
X685999Y147493D01*
G01X686063Y147519D02*
X686030Y147513D01*
G01X691082Y149790D02*
X691108Y149821D01*
G01X691052Y149770D02*
X691082Y149790D01*
G01X691019Y149763D02*
X691052Y149770D01*
G01X690686Y150328D02*
X690660Y150296D01*
G01X690717Y150347D02*
X690686Y150328D01*
G01X690749Y150354D02*
X690717Y150347D01*
G01X684887Y151955D02*
X684913Y151987D01*
G01X684857Y151935D02*
X684887Y151955D01*
G01X684824Y151929D02*
X684857Y151935D01*
G01X685999Y152493D02*
X685973Y152462D01*
G01X686030Y152513D02*
X685999Y152493D01*
G01X686063Y152519D02*
X686030Y152513D01*
G01X691082Y154790D02*
X691108Y154821D01*
G01X691052Y154770D02*
X691082Y154790D01*
G01X691019Y154763D02*
X691052Y154770D01*
G01X690686Y155328D02*
X690660Y155296D01*
G01X690717Y155347D02*
X690686Y155328D01*
G01X690749Y155354D02*
X690717Y155347D01*
G01X684887Y156955D02*
X684913Y156987D01*
G01X684857Y156935D02*
X684887Y156955D01*
G01X684824Y156929D02*
X684857Y156935D01*
G01X685999Y157493D02*
X685973Y157462D01*
G01X686030Y157513D02*
X685999Y157493D01*
G01X686063Y157519D02*
X686030Y157513D01*
G01X691082Y159790D02*
X691108Y159821D01*
G01X691052Y159770D02*
X691082Y159790D01*
G01X691019Y159763D02*
X691052Y159770D01*
G01X690686Y160328D02*
X690660Y160296D01*
G01X690717Y160347D02*
X690686Y160328D01*
G01X690749Y160354D02*
X690717Y160347D01*
G01X685641Y145328D02*
X685667Y145296D01*
G01X685611Y145347D02*
X685641Y145328D01*
G01X685578Y145354D02*
X685611Y145347D01*
G01X691440Y146955D02*
X691414Y146987D01*
G01X691470Y146935D02*
X691440Y146955D01*
G01X691504Y146929D02*
X691470Y146935D01*
G01X690328Y147493D02*
X690354Y147462D01*
G01X690298Y147513D02*
X690328Y147493D01*
G01X690265Y147519D02*
X690298Y147513D01*
G01X685245Y149790D02*
X685219Y149821D01*
G01X685276Y149770D02*
X685245Y149790D01*
G01X685309Y149763D02*
X685276Y149770D01*
G01X685641Y150328D02*
X685667Y150296D01*
G01X685611Y150347D02*
X685641Y150328D01*
G01X685578Y150354D02*
X685611Y150347D01*
G01X691440Y151955D02*
X691414Y151987D01*
G01X691470Y151935D02*
X691440Y151955D01*
G01X691504Y151929D02*
X691470Y151935D01*
G01X690328Y152493D02*
X690354Y152462D01*
G01X690298Y152513D02*
X690328Y152493D01*
G01X690265Y152519D02*
X690298Y152513D01*
G01X685245Y154790D02*
X685219Y154821D01*
G01X685276Y154770D02*
X685245Y154790D01*
G01X685309Y154763D02*
X685276Y154770D01*
G01X685641Y155328D02*
X685667Y155296D01*
G01X685611Y155347D02*
X685641Y155328D01*
G01X685578Y155354D02*
X685611Y155347D01*
G01X691440Y156955D02*
X691414Y156987D01*
G01X691470Y156935D02*
X691440Y156955D01*
G01X691504Y156929D02*
X691470Y156935D01*
G01X690328Y157493D02*
X690354Y157462D01*
G01X690298Y157513D02*
X690328Y157493D01*
G01X690265Y157519D02*
X690298Y157513D01*
G01X685245Y159790D02*
X685219Y159821D01*
G01X685276Y159770D02*
X685245Y159790D01*
G01X685309Y159763D02*
X685276Y159770D01*
G01X685641Y160328D02*
X685667Y160296D01*
G01X685611Y160347D02*
X685641Y160328D01*
G01X685578Y160354D02*
X685611Y160347D01*
G01X684857Y145347D02*
X684824Y145354D01*
G01X684887Y145328D02*
X684857Y145347D01*
G01X684913Y145296D02*
X684887Y145328D01*
G01X684857Y150347D02*
X684824Y150354D01*
G01X684887Y150328D02*
X684857Y150347D01*
G01X684913Y150296D02*
X684887Y150328D01*
G01X686030Y149770D02*
X686063Y149763D01*
G01X685999Y149790D02*
X686030Y149770D01*
G01X685973Y149821D02*
X685999Y149790D01*
G01X690717Y146935D02*
X690749Y146929D01*
G01X690686Y146955D02*
X690717Y146935D01*
G01X690660Y146987D02*
X690686Y146955D01*
G01X691052Y147513D02*
X691019Y147519D01*
G01X691082Y147493D02*
X691052Y147513D01*
G01X691108Y147462D02*
X691082Y147493D01*
G01X684857Y155347D02*
X684824Y155354D01*
G01X684887Y155328D02*
X684857Y155347D01*
G01X684913Y155296D02*
X684887Y155328D01*
G01X686030Y154770D02*
X686063Y154763D01*
G01X685999Y154790D02*
X686030Y154770D01*
G01X685973Y154821D02*
X685999Y154790D01*
G01X690717Y151935D02*
X690749Y151929D01*
G01X690686Y151955D02*
X690717Y151935D01*
G01X690660Y151987D02*
X690686Y151955D01*
G01X691052Y152513D02*
X691019Y152519D01*
G01X691082Y152493D02*
X691052Y152513D01*
G01X691108Y152462D02*
X691082Y152493D01*
G01X684857Y160347D02*
X684824Y160354D01*
G01X684887Y160328D02*
X684857Y160347D01*
G01X684913Y160296D02*
X684887Y160328D01*
G01X686030Y159770D02*
X686063Y159763D01*
G01X685999Y159790D02*
X686030Y159770D01*
G01X685973Y159821D02*
X685999Y159790D01*
G01X690717Y156935D02*
X690749Y156929D01*
G01X690686Y156955D02*
X690717Y156935D01*
G01X690660Y156987D02*
X690686Y156955D01*
G01X691052Y157513D02*
X691019Y157519D01*
G01X691082Y157493D02*
X691052Y157513D01*
G01X691108Y157462D02*
X691082Y157493D01*
G01X685276Y157513D02*
X685309Y157519D01*
G01X685245Y157493D02*
X685276Y157513D01*
G01X685219Y157462D02*
X685245Y157493D01*
G01X685611Y156935D02*
X685578Y156929D01*
G01X685641Y156955D02*
X685611Y156935D01*
G01X685667Y156987D02*
X685641Y156955D01*
G01X690298Y159770D02*
X690265Y159763D01*
G01X690328Y159790D02*
X690298Y159770D01*
G01X690354Y159821D02*
X690328Y159790D01*
G01X691470Y160347D02*
X691504Y160354D01*
G01X691440Y160328D02*
X691470Y160347D01*
G01X691414Y160296D02*
X691440Y160328D01*
G01X685276Y152513D02*
X685309Y152519D01*
G01X685245Y152493D02*
X685276Y152513D01*
G01X685219Y152462D02*
X685245Y152493D01*
G01X685611Y151935D02*
X685578Y151929D01*
G01X685641Y151955D02*
X685611Y151935D01*
G01X685667Y151987D02*
X685641Y151955D01*
G01X690298Y154770D02*
X690265Y154763D01*
G01X690328Y154790D02*
X690298Y154770D01*
G01X690354Y154821D02*
X690328Y154790D01*
G01X691470Y155347D02*
X691504Y155354D01*
G01X691440Y155328D02*
X691470Y155347D01*
G01X691414Y155296D02*
X691440Y155328D01*
G01X685276Y147513D02*
X685309Y147519D01*
G01X685245Y147493D02*
X685276Y147513D01*
G01X685219Y147462D02*
X685245Y147493D01*
G01X685611Y146935D02*
X685578Y146929D01*
G01X685641Y146955D02*
X685611Y146935D01*
G01X685667Y146987D02*
X685641Y146955D01*
G01X690298Y149770D02*
X690265Y149763D01*
G01X690328Y149790D02*
X690298Y149770D01*
G01X690354Y149821D02*
X690328Y149790D01*
G01X691470Y150347D02*
X691504Y150354D01*
G01X691440Y150328D02*
X691470Y150347D01*
G01X691414Y150296D02*
X691440Y150328D01*
G01X691470Y145347D02*
X691504Y145354D01*
G01X691440Y145328D02*
X691470Y145347D01*
G01X691414Y145296D02*
X691440Y145328D01*
G01X698480Y157578D02*
G03X698857Y157658I180J79D01*
G01Y156319D02*
G03X698480Y156397I-197J-1D01*
G01Y160728D02*
G03X698857Y160807I180J79D01*
G01Y159468D02*
G03X698480Y159547I-197J0D01*
G01X698857Y153169D02*
G03X698480Y153248I-197J0D01*
G01Y154429D02*
G03X698857Y154508I180J79D01*
G01X698480Y148130D02*
G03X698857Y148209I180J79D01*
G01Y146870D02*
G03X698480Y146948I-197J-1D01*
G01Y151279D02*
G03X698857Y151358I180J79D01*
G01Y150019D02*
G03X698480Y150098I-197J0D01*
G01X693498Y150157D02*
G03X693302Y150354I-197J0D01*
G01Y151929D02*
G03X693498Y152126I-1J197D01*
G01X693302Y146929D02*
G03X693498Y147126I-1J197D01*
G01Y160157D02*
G03X693302Y160354I-197J0D01*
G01X693498Y155157D02*
G03X693302Y155354I-197J0D01*
G01Y156929D02*
G03X693498Y157126I-1J197D01*
G01X691108Y149821D02*
X691414Y150296D01*
G01X690660D02*
X690354Y149821D01*
G01X695837Y148130D02*
X695758Y147972D01*
G01X695076D02*
X695155Y148130D01*
G01X695837Y151279D02*
X695758Y151122D01*
G01X695076D02*
X695155Y151279D01*
G01X695837Y154429D02*
X695758Y154271D01*
G01X695076D02*
X695155Y154429D01*
G01X695837Y157578D02*
X695758Y157421D01*
G01X695076D02*
X695155Y157578D01*
G01X695837Y160728D02*
X695758Y160570D01*
G01X695076D02*
X695155Y160728D01*
G01X698857Y160807D02*
Y161326D01*
G01Y158940D02*
Y159468D01*
G01Y157658D02*
Y158176D01*
G01Y155791D02*
Y156319D01*
G01Y154508D02*
Y155027D01*
G01Y151358D02*
Y151877D01*
G01Y149491D02*
Y150019D01*
G01Y148209D02*
Y148728D01*
G01Y146342D02*
Y146870D01*
G01Y153169D02*
Y152641D01*
G01X698249Y148130D02*
Y146948D01*
G01Y151279D02*
Y150098D01*
G01Y154429D02*
Y153248D01*
G01Y157578D02*
Y156397D01*
G01Y160728D02*
Y159547D01*
G01X697397D02*
Y160728D01*
G01Y156397D02*
Y157578D01*
G01Y153248D02*
Y154429D01*
G01Y150098D02*
Y151279D01*
G01Y146948D02*
Y148130D01*
G01X696715D02*
Y146948D01*
G01Y151279D02*
Y150098D01*
G01Y154429D02*
Y153248D01*
G01Y157578D02*
Y156397D01*
G01Y160728D02*
Y159547D01*
G01X695093Y147972D02*
Y147106D01*
G01Y151122D02*
Y150256D01*
G01Y154271D02*
Y153405D01*
G01Y157421D02*
Y156555D01*
G01Y160570D02*
Y159704D01*
G01X694411D02*
Y160570D01*
G01Y156555D02*
Y157421D01*
G01Y153405D02*
Y154271D01*
G01Y150256D02*
Y151122D01*
G01Y147106D02*
Y147972D01*
G01X693559D02*
Y147106D01*
G01Y151122D02*
Y150256D01*
G01Y154271D02*
Y153405D01*
G01Y157421D02*
Y156555D01*
G01Y160570D02*
Y159704D01*
G01X693498Y159173D02*
Y160157D01*
G01Y154173D02*
Y155157D01*
G01Y152126D02*
Y153110D01*
G01Y149173D02*
Y150157D01*
G01Y147126D02*
Y148110D01*
G01Y158110D02*
Y157126D01*
G01X692711Y155354D02*
Y156929D01*
G01Y146929D02*
Y145354D01*
G01Y151929D02*
Y150354D01*
G01Y161929D02*
Y160354D01*
G01X691957Y146929D02*
Y145354D01*
G01Y151929D02*
Y150354D01*
G01Y156929D02*
Y155354D01*
G01Y161929D02*
Y160354D01*
G01X691203D02*
Y161929D01*
G01Y155354D02*
Y156929D01*
G01Y150354D02*
Y151929D01*
G01Y145354D02*
Y146929D01*
G01X690803Y153405D02*
Y154271D01*
G01Y147972D02*
Y147106D01*
G01Y151122D02*
Y150256D01*
G01Y157421D02*
Y156555D01*
G01Y160570D02*
Y159704D01*
G01X685100Y160354D02*
Y161929D01*
G01Y155354D02*
Y156929D01*
G01Y150354D02*
Y151929D01*
G01Y145354D02*
Y146929D01*
G01X695758Y159704D02*
X695837Y159547D01*
G01X695155D02*
X695076Y159704D01*
G01X695758Y156555D02*
X695837Y156397D01*
G01X695155D02*
X695076Y156555D01*
G01X691108Y154821D02*
X691414Y155296D01*
G01X685973Y147462D02*
X685667Y146987D01*
G01X690660Y155296D02*
X690354Y154821D01*
G01X684913Y146987D02*
X685219Y147462D01*
G01X691108Y159821D02*
X691414Y160296D01*
G01X685973Y152462D02*
X685667Y151987D01*
G01X690660Y160296D02*
X690354Y159821D01*
G01X684913Y151987D02*
X685219Y152462D01*
G01X685973Y157462D02*
X685667Y156987D01*
G01X684913D02*
X685219Y157462D01*
G01X684346Y146929D02*
Y145354D01*
G01Y151929D02*
Y150354D01*
G01Y156929D02*
Y155354D01*
G01Y161929D02*
Y160354D01*
G01X683593Y146929D02*
Y145354D01*
G01Y151929D02*
Y150354D01*
G01Y156929D02*
Y155354D01*
G01Y161929D02*
Y160354D01*
G01X695758Y153405D02*
X695837Y153248D01*
G01X695155D02*
X695076Y153405D01*
G01X695758Y150256D02*
X695837Y150098D01*
G01X695155D02*
X695076Y150256D01*
G01X695758Y147106D02*
X695837Y146948D01*
G01X695155D02*
X695076Y147106D01*
G01X691414Y156987D02*
X691108Y157462D01*
G01X690354D02*
X690660Y156987D01*
G01X691414Y151987D02*
X691108Y152462D01*
G01X685667Y160296D02*
X685973Y159821D01*
G01X690354Y152462D02*
X690660Y151987D01*
G01X685219Y159821D02*
X684913Y160296D01*
G01X691414Y146987D02*
X691108Y147462D01*
G01X685667Y155296D02*
X685973Y154821D01*
G01X690354Y147462D02*
X690660Y146987D01*
G01X685219Y154821D02*
X684913Y155296D01*
G01X685667Y150296D02*
X685973Y149821D01*
G01X685219D02*
X684913Y150296D01*
G01X698857Y161326D02*
X699054D01*
G01X695155Y160728D02*
X698480D01*
G01X690803Y160570D02*
X695758D01*
G01X690749Y160354D02*
X693302D01*
G01X684913Y160296D02*
X685667D01*
G01X691414D02*
X690660D01*
G01X690354Y159821D02*
X691108D01*
G01X685973D02*
X685219D01*
G01X691019Y159763D02*
X685309D01*
G01X695758Y159704D02*
X690803D01*
G01X695155Y159547D02*
X698480D01*
G01X696850Y159173D02*
X693498D01*
G01X699054Y158940D02*
X698857D01*
G01Y158176D02*
X699054D01*
G01X693498Y158110D02*
X696850D01*
G01X695155Y157578D02*
X698480D01*
G01X685309Y157519D02*
X691019D01*
G01X685973Y157462D02*
X685219D01*
G01X691108D02*
X690354D01*
G01X690803Y157421D02*
X695758D01*
G01X684913Y156987D02*
X685667D01*
G01X691414D02*
X690660D01*
G01X690749Y156929D02*
X693302D01*
G01X695758Y156555D02*
X690803D01*
G01X695155Y156397D02*
X698480D01*
G01X699054Y155791D02*
X698857D01*
G01X690749Y155354D02*
X693302D01*
G01X684913Y155296D02*
X685667D01*
G01X691414D02*
X690660D01*
G01X699054Y155027D02*
X698857D01*
G01X690354Y154821D02*
X691108D01*
G01X685973D02*
X685219D01*
G01X691019Y154763D02*
X685309D01*
G01X695155Y154429D02*
X698480D01*
G01X690803Y154271D02*
X695758D01*
G01X696850Y154173D02*
X693498D01*
G01X695758Y153405D02*
X690803D01*
G01X695155Y153248D02*
X698480D01*
G01X693498Y153110D02*
X696850D01*
G01X698857Y152641D02*
X699054D01*
G01X685309Y152519D02*
X691019D01*
G01X685973Y152462D02*
X685219D01*
G01X691108D02*
X690354D01*
G01X684913Y151987D02*
X685667D01*
G01X691414D02*
X690660D01*
G01X690749Y151929D02*
X693302D01*
G01X698857Y151877D02*
X699054D01*
G01X695155Y151279D02*
X698480D01*
G01X690803Y151122D02*
X695758D01*
G01X690749Y150354D02*
X693302D01*
G01X684913Y150296D02*
X685667D01*
G01X691414D02*
X690660D01*
G01X695758Y150256D02*
X690803D01*
G01X695155Y150098D02*
X698480D01*
G01X690354Y149821D02*
X691108D01*
G01X685973D02*
X685219D01*
G01X691019Y149763D02*
X685309D01*
G01X699054Y149491D02*
X698857D01*
G01X693498Y149173D02*
X696850D01*
G01X698857Y148728D02*
X699054D01*
G01X695155Y148130D02*
X698480D01*
G01X693498Y148110D02*
X696850D01*
G01X690803Y147972D02*
X695758D01*
G01X685309Y147519D02*
X691019D01*
G01X690354Y147462D02*
X691108D01*
G01X685973D02*
X685219D01*
G01X695758Y147106D02*
X690803D01*
G01X685667Y146987D02*
X684913D01*
G01X691414D02*
X690660D01*
G01X695155Y146948D02*
X698480D01*
G01X690749Y146929D02*
X693302D01*
G01X699054Y146342D02*
X698857D01*
G01X699054Y145578D02*
X698857D01*
G01X690749Y145354D02*
X693302D01*
G01X684913Y145296D02*
X685667D01*
G01X691414D02*
X690660D01*
G01X684887Y161955D02*
X684913Y161987D01*
G01X684857Y161935D02*
X684887Y161955D01*
G01X684824Y161929D02*
X684857Y161935D01*
G01X685999Y162493D02*
X685973Y162462D01*
G01X686030Y162513D02*
X685999Y162493D01*
G01X686063Y162519D02*
X686030Y162513D01*
G01X691082Y164790D02*
X691108Y164821D01*
G01X691052Y164770D02*
X691082Y164790D01*
G01X691019Y164763D02*
X691052Y164770D01*
G01X690686Y165328D02*
X690660Y165296D01*
G01X690717Y165347D02*
X690686Y165328D01*
G01X690749Y165354D02*
X690717Y165347D01*
G01X684887Y166955D02*
X684913Y166987D01*
G01X684857Y166935D02*
X684887Y166955D01*
G01X684824Y166929D02*
X684857Y166935D01*
G01X685999Y167493D02*
X685973Y167462D01*
G01X686030Y167513D02*
X685999Y167493D01*
G01X686063Y167519D02*
X686030Y167513D01*
G01X691082Y169790D02*
X691108Y169821D01*
G01X691052Y169770D02*
X691082Y169790D01*
G01X691019Y169763D02*
X691052Y169770D01*
G01X690686Y170328D02*
X690660Y170296D01*
G01X690717Y170347D02*
X690686Y170328D01*
G01X690749Y170354D02*
X690717Y170347D01*
G01X684887Y171955D02*
X684913Y171987D01*
G01X684857Y171935D02*
X684887Y171955D01*
G01X684824Y171929D02*
X684857Y171935D01*
G01X685999Y172493D02*
X685973Y172462D01*
G01X686030Y172513D02*
X685999Y172493D01*
G01X686063Y172519D02*
X686030Y172513D01*
G01X691440Y161955D02*
X691414Y161987D01*
G01X691470Y161935D02*
X691440Y161955D01*
G01X691504Y161929D02*
X691470Y161935D01*
G01X690328Y162493D02*
X690354Y162462D01*
G01X690298Y162513D02*
X690328Y162493D01*
G01X690265Y162519D02*
X690298Y162513D01*
G01X685245Y164790D02*
X685219Y164821D01*
G01X685276Y164770D02*
X685245Y164790D01*
G01X685309Y164763D02*
X685276Y164770D01*
G01X685641Y165328D02*
X685667Y165296D01*
G01X685611Y165347D02*
X685641Y165328D01*
G01X685578Y165354D02*
X685611Y165347D01*
G01X691440Y166955D02*
X691414Y166987D01*
G01X691470Y166935D02*
X691440Y166955D01*
G01X691504Y166929D02*
X691470Y166935D01*
G01X690328Y167493D02*
X690354Y167462D01*
G01X690298Y167513D02*
X690328Y167493D01*
G01X690265Y167519D02*
X690298Y167513D01*
G01X685245Y169790D02*
X685219Y169821D01*
G01X685276Y169770D02*
X685245Y169790D01*
G01X685309Y169763D02*
X685276Y169770D01*
G01X685641Y170328D02*
X685667Y170296D01*
G01X685611Y170347D02*
X685641Y170328D01*
G01X685578Y170354D02*
X685611Y170347D01*
G01X691440Y171955D02*
X691414Y171987D01*
G01X691470Y171935D02*
X691440Y171955D01*
G01X691504Y171929D02*
X691470Y171935D01*
G01X690328Y172493D02*
X690354Y172462D01*
G01X690298Y172513D02*
X690328Y172493D01*
G01X690265Y172519D02*
X690298Y172513D01*
G01X684857Y165347D02*
X684824Y165354D01*
G01X684887Y165328D02*
X684857Y165347D01*
G01X684913Y165296D02*
X684887Y165328D01*
G01X686030Y164770D02*
X686063Y164763D01*
G01X685999Y164790D02*
X686030Y164770D01*
G01X685973Y164821D02*
X685999Y164790D01*
G01X690717Y161935D02*
X690749Y161929D01*
G01X690686Y161955D02*
X690717Y161935D01*
G01X690660Y161987D02*
X690686Y161955D01*
G01X691052Y162513D02*
X691019Y162519D01*
G01X691082Y162493D02*
X691052Y162513D01*
G01X691108Y162462D02*
X691082Y162493D01*
G01X684857Y170347D02*
X684824Y170354D01*
G01X684887Y170328D02*
X684857Y170347D01*
G01X684913Y170296D02*
X684887Y170328D01*
G01X686030Y169770D02*
X686063Y169763D01*
G01X685999Y169790D02*
X686030Y169770D01*
G01X685973Y169821D02*
X685999Y169790D01*
G01X690717Y166935D02*
X690749Y166929D01*
G01X690686Y166955D02*
X690717Y166935D01*
G01X690660Y166987D02*
X690686Y166955D01*
G01X691052Y167513D02*
X691019Y167519D01*
G01X691082Y167493D02*
X691052Y167513D01*
G01X691108Y167462D02*
X691082Y167493D01*
G01X685276Y172513D02*
X685309Y172519D01*
G01X685245Y172493D02*
X685276Y172513D01*
G01X685219Y172462D02*
X685245Y172493D01*
G01X685611Y171935D02*
X685578Y171929D01*
G01X685641Y171955D02*
X685611Y171935D01*
G01X685667Y171987D02*
X685641Y171955D01*
G01X685276Y167513D02*
X685309Y167519D01*
G01X685245Y167493D02*
X685276Y167513D01*
G01X685219Y167462D02*
X685245Y167493D01*
G01X685611Y166935D02*
X685578Y166929D01*
G01X685641Y166955D02*
X685611Y166935D01*
G01X685667Y166987D02*
X685641Y166955D01*
G01X690298Y169770D02*
X690265Y169763D01*
G01X690328Y169790D02*
X690298Y169770D01*
G01X690354Y169821D02*
X690328Y169790D01*
G01X691470Y170347D02*
X691504Y170354D01*
G01X691440Y170328D02*
X691470Y170347D01*
G01X691414Y170296D02*
X691440Y170328D01*
G01X685276Y162513D02*
X685309Y162519D01*
G01X685245Y162493D02*
X685276Y162513D01*
G01X685219Y162462D02*
X685245Y162493D01*
G01X685611Y161935D02*
X685578Y161929D01*
G01X685641Y161955D02*
X685611Y161935D01*
G01X685667Y161987D02*
X685641Y161955D01*
G01X690717Y171935D02*
X690749Y171929D01*
G01X690686Y171955D02*
X690717Y171935D01*
G01X690660Y171987D02*
X690686Y171955D01*
G01X691052Y172513D02*
X691019Y172519D01*
G01X691082Y172493D02*
X691052Y172513D01*
G01X691108Y172462D02*
X691082Y172493D01*
G01X690298Y164770D02*
X690265Y164763D01*
G01X690328Y164790D02*
X690298Y164770D01*
G01X690354Y164821D02*
X690328Y164790D01*
G01X691470Y165347D02*
X691504Y165354D01*
G01X691440Y165328D02*
X691470Y165347D01*
G01X691414Y165296D02*
X691440Y165328D01*
G01X698480Y170177D02*
G03X698857Y170256I180J79D01*
G01Y168917D02*
G03X698480Y168996I-197J0D01*
G01Y167027D02*
G03X698857Y167106I180J79D01*
G01Y165767D02*
G03X698480Y165846I-197J0D01*
G01Y163878D02*
G03X698857Y163956I180J79D01*
G01X701180Y171319D02*
G03X699212Y173287I-1968J0D01*
G01X701180Y171319D02*
G03X699212Y173287I-1968J0D01*
G01X698857Y162618D02*
G03X698480Y162696I-197J-1D01*
G01X693302Y161929D02*
G03X693498Y162126I-1J197D01*
G01Y165157D02*
G03X693302Y165354I-197J0D01*
G01Y166929D02*
G03X693498Y167126I-1J197D01*
G01Y170157D02*
G03X693302Y170354I-197J0D01*
G01Y171929D02*
G03X693498Y172126I-1J197D01*
G01X692125Y175256D02*
G03X694094Y173287I1969J0D01*
G01X692125Y175256D02*
G03X694094Y173287I1969J0D01*
G01X701180Y171319D02*
G03X699212Y173287I-1968J0D01*
G01X692125Y175256D02*
G03X694094Y173287I1969J0D01*
G01X692125Y175256D02*
G03X694094Y173287I1969J0D01*
G01X701180Y171319D02*
G03X699212Y173287I-1968J0D01*
G01X695837Y163878D02*
X695758Y163720D01*
G01X695076D02*
X695155Y163878D01*
G01X695837Y167027D02*
X695758Y166870D01*
G01X695076D02*
X695155Y167027D01*
G01X695837Y170177D02*
X695758Y170019D01*
G01X695076D02*
X695155Y170177D01*
G01X699054Y173287D02*
Y174448D01*
G01X698857Y170256D02*
Y170775D01*
G01Y168389D02*
Y168917D01*
G01Y167106D02*
Y167625D01*
G01Y165239D02*
Y165767D01*
G01Y163956D02*
Y164476D01*
G01Y162090D02*
Y162618D01*
G01X698249Y163878D02*
Y162696D01*
G01Y167027D02*
Y165846D01*
G01Y170177D02*
Y168996D01*
G01X697397D02*
Y170177D01*
G01Y165846D02*
Y167027D01*
G01Y162696D02*
Y163878D01*
G01X696850Y174448D02*
Y173287D01*
G01X696715Y163878D02*
Y162696D01*
G01Y167027D02*
Y165846D01*
G01Y170177D02*
Y168996D01*
G01X695669Y178224D02*
Y189606D01*
G01X695093Y163720D02*
Y162854D01*
G01Y166870D02*
Y166004D01*
G01Y170019D02*
Y169153D01*
G01X694411D02*
Y170019D01*
G01Y166004D02*
Y166870D01*
G01Y162854D02*
Y163720D01*
G01X693559D02*
Y162854D01*
G01Y166870D02*
Y166004D01*
G01Y170019D02*
Y169153D01*
G01X693498Y169173D02*
Y170157D01*
G01Y167126D02*
Y168110D01*
G01Y164173D02*
Y165157D01*
G01Y162126D02*
Y163110D01*
G01Y173110D02*
Y172126D01*
G01X693306Y190000D02*
Y177204D01*
G01X692711Y170354D02*
Y171929D01*
G01Y166929D02*
Y165354D01*
G01X692519Y174448D02*
Y192756D01*
G01X692125Y191988D02*
Y175256D01*
G01Y191988D02*
Y175256D01*
G01X691957Y166929D02*
Y165354D01*
G01Y171929D02*
Y170354D01*
G01X691203D02*
Y171929D01*
G01Y165354D02*
Y166929D01*
G01X690803Y162854D02*
Y163720D01*
G01Y166870D02*
Y166004D01*
G01Y170019D02*
Y169153D01*
G01X690550Y192756D02*
Y174448D01*
G01X685100Y170354D02*
Y171929D01*
G01Y165354D02*
Y166929D01*
G01X695758Y169153D02*
X695837Y168996D01*
G01X695155D02*
X695076Y169153D01*
G01X695758Y166004D02*
X695837Y165846D01*
G01X695155D02*
X695076Y166004D01*
G01X695758Y162854D02*
X695837Y162696D01*
G01X695155D02*
X695076Y162854D01*
G01X691108Y164821D02*
X691414Y165296D01*
G01X690660D02*
X690354Y164821D01*
G01X691108Y169821D02*
X691414Y170296D01*
G01X685973Y162462D02*
X685667Y161987D01*
G01X690660Y170296D02*
X690354Y169821D01*
G01X684913Y161987D02*
X685219Y162462D01*
G01X685973Y167462D02*
X685667Y166987D01*
G01X684913D02*
X685219Y167462D01*
G01X685973Y172462D02*
X685667Y171987D01*
G01X684913D02*
X685219Y172462D01*
G01X684346Y166929D02*
Y165354D01*
G01Y171929D02*
Y170354D01*
G01X683593Y166929D02*
Y165354D01*
G01Y171929D02*
Y170354D01*
G01X691414Y171987D02*
X691108Y172462D01*
G01X690354D02*
X690660Y171987D01*
G01X691414Y166987D02*
X691108Y167462D01*
G01X690354D02*
X690660Y166987D01*
G01X691414Y161987D02*
X691108Y162462D01*
G01X685667Y170296D02*
X685973Y169821D01*
G01X690354Y162462D02*
X690660Y161987D01*
G01X685219Y169821D02*
X684913Y170296D01*
G01X685667Y165296D02*
X685973Y164821D01*
G01X685219D02*
X684913Y165296D01*
G01X693306Y177204D02*
X696062Y174448D01*
G01X703149Y174736D02*
X695669Y178224D01*
G01X692311Y174448D02*
X721259D01*
G01X694094Y173287D02*
X699212D01*
G01X694094D02*
X699212D01*
G01X693498Y173110D02*
X696850D01*
G01X685309Y172519D02*
X691019D01*
G01X685973Y172462D02*
X685219D01*
G01X691108D02*
X690354D01*
G01X684913Y171987D02*
X685667D01*
G01X691414D02*
X690660D01*
G01X690749Y171929D02*
X693302D01*
G01X698857Y170775D02*
X699054D01*
G01X690749Y170354D02*
X693302D01*
G01X684913Y170296D02*
X685667D01*
G01X691414D02*
X690660D01*
G01X695155Y170177D02*
X698480D01*
G01X690803Y170019D02*
X695758D01*
G01X690354Y169821D02*
X691108D01*
G01X685973D02*
X685219D01*
G01X691019Y169763D02*
X685309D01*
G01X696850Y169173D02*
X693498D01*
G01X695758Y169153D02*
X690803D01*
G01X695155Y168996D02*
X698480D01*
G01X699054Y168389D02*
X698857D01*
G01X693498Y168110D02*
X696850D01*
G01X698857Y167625D02*
X699054D01*
G01X685309Y167519D02*
X691019D01*
G01X685973Y167462D02*
X685219D01*
G01X691108D02*
X690354D01*
G01X695155Y167027D02*
X698480D01*
G01X684913Y166987D02*
X685667D01*
G01X691414D02*
X690660D01*
G01X690749Y166929D02*
X693302D01*
G01X690803Y166870D02*
X695758D01*
G01Y166004D02*
X690803D01*
G01X695155Y165846D02*
X698480D01*
G01X690749Y165354D02*
X693302D01*
G01X684913Y165296D02*
X685667D01*
G01X691414D02*
X690660D01*
G01X699054Y165239D02*
X698857D01*
G01X690354Y164821D02*
X691108D01*
G01X685973D02*
X685219D01*
G01X691019Y164763D02*
X685309D01*
G01X699054Y164476D02*
X698857D01*
G01X693498Y164173D02*
X696850D01*
G01X695155Y163878D02*
X698480D01*
G01X690803Y163720D02*
X695758D01*
G01X693498Y163110D02*
X696850D01*
G01X695758Y162854D02*
X690803D01*
G01X695155Y162696D02*
X698480D01*
G01X685309Y162519D02*
X691019D01*
G01X690354Y162462D02*
X691108D01*
G01X685973D02*
X685219D01*
G01X699054Y162090D02*
X698857D01*
G01X685667Y161987D02*
X684913D01*
G01X691414D02*
X690660D01*
G01X690749Y161929D02*
X693302D01*
G01X692125Y191988D02*
Y175256D01*
G01X694094Y173287D02*
X699212D01*
G01X694094D02*
X699212D01*
G01X692125Y175256D02*
Y191988D01*
G01X692124Y175256D02*
G03X694094Y173287I1969J0D01*
G01X699212D02*
X694094D01*
G01X701181Y171319D02*
G03X699212Y173287I-1969J-1D01*
G01X694094Y193956D02*
G03X692125Y191988I-1J-1968D01*
G01X694094Y193956D02*
G03X692125Y191988I-1J-1968D01*
G01X694094Y193956D02*
G03X692125Y191988I-1J-1968D01*
G01X694094Y193956D02*
G03X692125Y191988I-1J-1968D01*
G01X698424Y193956D02*
Y192756D01*
G01Y203582D02*
Y193956D01*
G01X692519Y193106D02*
Y203582D01*
G01Y192756D02*
Y193106D01*
G01X690157Y180689D02*
Y190137D01*
G01X696062Y192756D02*
X693306Y190000D01*
G01X692519Y194724D02*
X722440D01*
G01X720472Y193956D02*
X694094D01*
G01X720472D02*
X694094D01*
G01X692285Y192756D02*
X722440D01*
G01X720394Y189606D02*
X695669D01*
G01Y188819D02*
X692519D01*
G01X722440Y188425D02*
X695669D01*
G01X722440Y185669D02*
X695669D01*
G01X687864Y185413D02*
X687204D01*
G01X722440Y184488D02*
X695669D01*
G01X720472Y193956D02*
X694094D01*
G01X720472D02*
X694094D01*
G01Y193957D02*
X720472D01*
G01X694094D02*
G03X692124Y191988I-1J-1969D01*
G01X698976Y199252D02*
Y198070D01*
G01X698385Y199252D02*
Y198070D01*
G01X692519Y203582D02*
X702361D01*
G01Y200472D02*
X692519D01*
G01Y199882D02*
X702361D01*
G01X722440Y199291D02*
X692519D01*
G01X698385Y199252D02*
X716180D01*
G01X698385Y198070D02*
X716180D01*
G01X692519Y198031D02*
X722440D01*
G01Y197441D02*
X692519D01*
G01X722440Y196850D02*
X692519D01*
G01X684645Y363425D02*
Y320118D01*
G01X700484Y373984D02*
G03I-4291J0D01*
G01X683652Y363425D02*
G03Y371299I0J3937D01*
G01X703429Y-749384D02*
X703977Y-748649D01*
X704447Y-748229D01*
X705074Y-748019D01*
X705622Y-748229D01*
X706014Y-748649D01*
X706327Y-749279D01*
X706405Y-750014D01*
X706327Y-750644D01*
X706014Y-751274D01*
X705544Y-751799D01*
X704995Y-752009D01*
X704369Y-751799D01*
X703820Y-751169D01*
X703507Y-750224D01*
X703429Y-749174D01*
X703585Y-747809D01*
X703820Y-747074D01*
X704212Y-746339D01*
X704760Y-745814D01*
X705309Y-745709D01*
X705857Y-745919D01*
X706249Y-746444D01*
G01X708848Y-113228D02*
X722440D01*
G01X708848Y-105354D02*
G03Y-113228I1J-3937D01*
G01X714566Y-105354D02*
G03X722440Y-97480I0J7874D01*
G01X714566Y-105354D02*
G03X722440Y-97480I0J7874D01*
G01X714566Y-105354D02*
G03X722440Y-97480I0J7874D01*
G01X714566Y-105354D02*
G03X722440Y-97480I0J7874D01*
G01X714566Y-105354D02*
G03X722440Y-97480I0J7874D01*
G01Y-15748D02*
G03X714566Y-7874I-7874J0D01*
G01X722440Y-15748D02*
G03X714566Y-7874I-7874J0D01*
G01X722440Y-15748D02*
G03X714566Y-7874I-7874J0D01*
G01X722440Y-15748D02*
G03X714566Y-7874I-7874J0D01*
G01X708848Y0D02*
G03Y-7874I1J-3937D01*
G01X722440Y-15748D02*
G03X714566Y-7874I-7874J0D01*
G01X702952Y10196D02*
G03X704133Y9015I1181J0D01*
G01X710432D02*
G03X711613Y10196I0J1181D01*
G01Y16960D02*
Y10196D01*
G01X702952D02*
Y16960D01*
G01X710432Y9015D02*
X704133D01*
G01X711031Y17989D02*
X711022Y17970D01*
G01X711131Y18020D02*
X711031Y17989D01*
G01X711335Y18030D02*
X711131Y18020D01*
G01X703536Y19142D02*
X703541Y19115D01*
G01X703463Y19188D02*
X703536Y19142D01*
G01X703332Y19207D02*
X703463Y19188D01*
G01X703151Y19212D02*
X703332Y19207D01*
G01X711410Y17260D02*
X711595Y16741D01*
G01X711226Y17671D02*
X711410Y17260D01*
G01X711042Y17936D02*
X711226Y17671D01*
G01X711023Y19109D02*
Y19115D01*
G01X711042Y19060D02*
X711023Y19109D01*
G01X711611Y16664D02*
X711613Y16624D01*
G01X711605Y16703D02*
X711611Y16664D01*
G01X711595Y16741D02*
X711605Y16703D01*
G01X703365Y18026D02*
X703184Y18031D01*
G01X703486Y18011D02*
X703365Y18026D01*
G01X703540Y17981D02*
X703486Y18011D01*
G01X703543Y17970D02*
X703540Y17981D01*
G01X711226Y18635D02*
X711042Y19060D01*
G01X711410Y17978D02*
X711226Y18635D01*
G01X711595Y17146D02*
X711410Y17978D01*
G01X711605Y17085D02*
X711595Y17146D01*
G01X711611Y17023D02*
X711605Y17085D01*
G01X711613Y16960D02*
X711611Y17023D01*
G01X702960Y16703D02*
X702971Y16741D01*
G01X702954Y16664D02*
X702960Y16703D01*
G01X702952Y16624D02*
X702954Y16664D01*
G01Y17023D02*
X702952Y16960D01*
G01X702960Y17085D02*
X702954Y17023D01*
G01X702971Y17146D02*
X702960Y17085D01*
G01X703339Y17671D02*
X703524Y17936D01*
G01X703155Y17260D02*
X703339Y17671D01*
G01X702971Y16741D02*
X703155Y17260D01*
G01X711315Y19211D02*
X711413Y19212D01*
G01X711223Y19206D02*
X711315Y19211D01*
G01X711141Y19196D02*
X711223Y19206D01*
G01X711076Y19179D02*
X711141Y19196D01*
G01X711035Y19150D02*
X711076Y19179D01*
G01X711023Y19115D02*
X711035Y19150D01*
G01X703155Y17978D02*
X702971Y17146D01*
G01X703339Y18635D02*
X703155Y17978D01*
G01X703524Y19060D02*
X703339Y18635D01*
G01X700039Y17598D02*
X700432Y17992D01*
G01X703524Y17936D02*
X703543Y17970D01*
G01X703541Y19115D02*
X703524Y19060D01*
G01X716180Y18031D02*
Y19212D01*
G01X716141Y23366D02*
Y24527D01*
G01Y13700D02*
Y23366D01*
G01X715590Y18031D02*
Y19212D01*
G01X714566Y27677D02*
Y24527D01*
G01X714291Y18031D02*
Y19212D01*
G01X713813Y18031D02*
Y19212D01*
G01X713728D02*
Y18031D01*
G01X713481D02*
Y19212D01*
G01X712478D02*
Y18031D01*
G01X712401D02*
Y19212D01*
G01X712204Y13700D02*
Y17992D01*
G01X711613Y18031D02*
Y19212D01*
G01X711595Y17147D02*
Y16740D01*
G01X711042Y17936D02*
Y19060D01*
G01X711023Y19115D02*
Y17970D01*
G01X710354Y18031D02*
Y19212D01*
G01X709960D02*
Y18031D01*
G01X709172Y19212D02*
Y18031D01*
G01X705393Y19212D02*
Y18031D01*
G01X704606Y19212D02*
Y18031D01*
G01X704212Y19212D02*
Y18031D01*
G01X703543Y17970D02*
Y19115D01*
G01X703524Y19060D02*
Y17936D01*
G01X702971Y16740D02*
Y17147D01*
G01X702952Y19212D02*
Y18031D01*
G01X702361Y17992D02*
Y13700D01*
G01X702165Y19212D02*
Y18031D01*
G01X702087D02*
Y19212D01*
G01X701084D02*
Y18031D01*
G01X700837D02*
Y19212D01*
G01X700752D02*
Y18031D01*
G01X700432Y17598D02*
Y19645D01*
G01X700275Y18031D02*
Y19212D01*
G01X700039Y19645D02*
Y17598D01*
G01X711022Y17970D02*
X711042Y17936D01*
G01X700039Y19645D02*
X700432Y19252D01*
G01Y19645D02*
X700039D01*
G01Y17598D02*
X700432D01*
G01X712204D02*
X702361D01*
G01X712204Y17401D02*
X722440D01*
G01Y16811D02*
X712204D01*
G01X711613Y16063D02*
X702952D01*
G01X712204Y13700D02*
X722440D01*
G01X703543Y46063D02*
G03X703444Y46036I1J-197D01*
G01X704725Y44921D02*
G03X704674Y44914I1J-197D01*
G01X707537Y44863D02*
G03X707398Y44921I-139J-139D01*
G01X707816Y44585D02*
G03X707955Y44527I140J139D01*
G01X703149Y45866D02*
X703444Y46036D01*
G01X704330Y44291D02*
Y42834D01*
G01X703149Y179882D02*
Y37401D01*
G01X701180Y171319D02*
Y46004D01*
G01Y171319D02*
Y46004D01*
G01X707460Y46063D02*
X707657Y45866D01*
G01X707537Y44863D02*
X707816Y44585D01*
G01X705117Y35433D02*
X703149Y37401D01*
G01X707460Y46063D02*
X703543D01*
G01X720078Y45866D02*
X707657D01*
G01X707398Y44921D02*
X704725D01*
G01X717429Y44527D02*
X707955D01*
G01X703149Y44291D02*
X704330D01*
G01X705117Y35433D02*
X720393D01*
G01X703149Y44506D02*
X704674Y44914D01*
G01X701180Y171319D02*
Y46004D01*
G01Y171319D02*
Y46004D01*
G01X701181D02*
Y171319D01*
G01X703508Y61808D02*
X703543Y61811D01*
G01X703475Y61799D02*
X703508Y61808D01*
G01X703444Y61784D02*
X703475Y61799D01*
G01X703508Y58658D02*
X703543Y58661D01*
G01X703475Y58649D02*
X703508Y58658D01*
G01X703444Y58635D02*
X703475Y58649D01*
G01X703508Y52359D02*
X703543Y52362D01*
G01X703475Y52350D02*
X703508Y52359D01*
G01X703444Y52335D02*
X703475Y52350D01*
G01X703508Y49209D02*
X703543Y49212D01*
G01X703475Y49200D02*
X703508Y49209D01*
G01X703444Y49186D02*
X703475Y49200D01*
G01X707436Y61753D02*
G03X707296Y61811I-140J-139D01*
G01X707517Y61672D02*
G03X707657Y61614I140J139D01*
G01X707436Y58604D02*
G03X707296Y58661I-139J-140D01*
G01X707517Y58522D02*
G03X707657Y58464I140J139D01*
G01X707955Y57756D02*
G03X707816Y57698I1J-197D01*
G01X707398Y57362D02*
G03X707537Y57420I0J197D01*
G01Y59863D02*
G03X707398Y59921I-139J-139D01*
G01X707816Y59585D02*
G03X707955Y59527I140J139D01*
G01Y62756D02*
G03X707816Y62698I1J-197D01*
G01X707398Y62362D02*
G03X707537Y62420I0J197D01*
G01X707436Y52304D02*
G03X707296Y52362I-140J-139D01*
G01X707517Y52223D02*
G03X707657Y52165I140J139D01*
G01X707436Y49155D02*
G03X707296Y49212I-139J-140D01*
G01X707517Y49073D02*
G03X707657Y49015I140J139D01*
G01X707955Y47756D02*
G03X707816Y47698I1J-197D01*
G01X707398Y47362D02*
G03X707537Y47420I0J197D01*
G01Y49863D02*
G03X707398Y49921I-139J-139D01*
G01X707816Y49585D02*
G03X707955Y49527I140J139D01*
G01Y52756D02*
G03X707816Y52698I1J-197D01*
G01X707398Y52362D02*
G03X707537Y52420I0J197D01*
G01Y54863D02*
G03X707398Y54921I-139J-139D01*
G01X707816Y54585D02*
G03X707955Y54527I140J139D01*
G01X706557Y60236D02*
G03X706418Y60178I1J-197D01*
G01X706197Y60039D02*
G03X706336Y60097I0J197D01*
G01X703444Y60065D02*
G03X703543Y60039I98J171D01*
G01X703444Y56916D02*
G03X703543Y56889I100J170D01*
G01X704674Y57369D02*
G03X704725Y57362I52J190D01*
G01Y59921D02*
G03X704674Y59914I1J-197D01*
G01Y62369D02*
G03X704725Y62362I52J190D01*
G01X703543Y55511D02*
G03X703444Y55485I-1J-197D01*
G01X706557Y53937D02*
G03X706418Y53879I1J-197D01*
G01X706197Y53740D02*
G03X706336Y53798I0J197D01*
G01X703444Y53766D02*
G03X703543Y53740I98J171D01*
G01X706557Y50787D02*
G03X706418Y50730I0J-197D01*
G01X706197Y50590D02*
G03X706336Y50648I-1J197D01*
G01X703444Y50617D02*
G03X703543Y50590I100J170D01*
G01X703444Y47467D02*
G03X703543Y47441I98J171D01*
G01X704674Y47369D02*
G03X704725Y47362I52J190D01*
G01Y49921D02*
G03X704674Y49914I1J-197D01*
G01Y52369D02*
G03X704725Y52362I52J190D01*
G01Y54921D02*
G03X704674Y54914I1J-197D01*
G01X707816Y47698D02*
X707537Y47420D01*
G01X706476Y47637D02*
X706279Y47441D01*
G01X706418Y50730D02*
X706336Y50648D01*
G01X707816Y52698D02*
X707537Y52420D01*
G01X703149Y49015D02*
X703444Y49186D01*
G01X703149Y52165D02*
X703444Y52335D01*
G01X703149Y55315D02*
X703444Y55485D01*
G01X706418Y53879D02*
X706336Y53798D01*
G01X707816Y57698D02*
X707537Y57420D01*
G01X706476Y57086D02*
X706279Y56889D01*
G01X706418Y60178D02*
X706336Y60097D01*
G01X707816Y62698D02*
X707537Y62420D01*
G01X703149Y58464D02*
X703444Y58635D01*
G01X703149Y61614D02*
X703444Y61784D01*
G01X704330Y57992D02*
Y59291D01*
G01Y52992D02*
Y54291D01*
G01Y47992D02*
Y49291D01*
G01X707436Y61753D02*
X707517Y61672D01*
G01X707537Y59863D02*
X707816Y59585D01*
G01X707436Y58604D02*
X707517Y58522D01*
G01X707460Y55511D02*
X707657Y55315D01*
G01X707537Y54863D02*
X707816Y54585D01*
G01X707436Y52304D02*
X707517Y52223D01*
G01X707537Y49863D02*
X707816Y49585D01*
G01X707436Y49155D02*
X707517Y49073D01*
G01X703444Y60065D02*
X703149Y60236D01*
G01X703444Y56916D02*
X703149Y57086D01*
G01X703444Y53766D02*
X703149Y53937D01*
G01X703444Y50617D02*
X703149Y50787D01*
G01X703444Y47467D02*
X703149Y47637D01*
G01X704674Y62369D02*
X703149Y62778D01*
G01X704674Y57369D02*
X703149Y57778D01*
G01X704674Y52369D02*
X703149Y52778D01*
G01X704674Y47369D02*
X703149Y47778D01*
G01X704725Y62362D02*
X707398D01*
G01X703543Y61811D02*
X707296D01*
G01X718109Y61614D02*
X707657D01*
G01X706557Y60236D02*
X718109D01*
G01X703543Y60039D02*
X706197D01*
G01X707398Y59921D02*
X704725D01*
G01X717524Y59527D02*
X707955D01*
G01X703149Y59291D02*
X704330D01*
G01X703543Y58661D02*
X707296D01*
G01X718109Y58464D02*
X707657D01*
G01X703149Y57992D02*
X704330D01*
G01X707955Y57756D02*
X717524D01*
G01X704725Y57362D02*
X707398D01*
G01X706476Y57086D02*
X720078D01*
G01X703543Y56889D02*
X706279D01*
G01X707460Y55511D02*
X703543D01*
G01X720078Y55315D02*
X707657D01*
G01X707398Y54921D02*
X704725D01*
G01X717524Y54527D02*
X707955D01*
G01X703149Y54291D02*
X704330D01*
G01X706557Y53937D02*
X718109D01*
G01X703543Y53740D02*
X706197D01*
G01X704330Y52992D02*
X703149D01*
G01X707955Y52756D02*
X717429D01*
G01X707296Y52362D02*
X707398D01*
G01X703543D02*
X707296D01*
G01X718109Y52165D02*
X707657D01*
G01X706557Y50787D02*
X718109D01*
G01X703543Y50590D02*
X706197D01*
G01X707398Y49921D02*
X704725D01*
G01X717429Y49527D02*
X707955D01*
G01X704330Y49291D02*
X703149D01*
G01X703543Y49212D02*
X707296D01*
G01X718109Y49015D02*
X707657D01*
G01X704330Y47992D02*
X703149D01*
G01X707955Y47756D02*
X717429D01*
G01X706476Y47637D02*
X720078D01*
G01X703543Y47441D02*
X706279D01*
G01X704725Y47362D02*
X707398D01*
G01X703149Y59506D02*
X704674Y59914D01*
G01X703149Y54506D02*
X704674Y54914D01*
G01X703149Y49506D02*
X704674Y49914D01*
G01X703508Y77556D02*
X703543Y77559D01*
G01X703475Y77547D02*
X703508Y77556D01*
G01X703444Y77532D02*
X703475Y77547D01*
G01X703508Y71257D02*
X703543Y71259D01*
G01X703475Y71248D02*
X703508Y71257D01*
G01X703444Y71233D02*
X703475Y71248D01*
G01X703508Y68107D02*
X703543Y68110D01*
G01X703475Y68098D02*
X703508Y68107D01*
G01X703444Y68083D02*
X703475Y68098D01*
G01X707436Y77501D02*
G03X707296Y77559I-140J-139D01*
G01X707517Y77420D02*
G03X707657Y77362I140J139D01*
G01X707436Y71202D02*
G03X707296Y71259I-138J-140D01*
G01X707517Y71120D02*
G03X707657Y71063I139J140D01*
G01X707436Y68052D02*
G03X707296Y68110I-140J-139D01*
G01X707517Y67971D02*
G03X707657Y67913I140J139D01*
G01X707955Y67756D02*
G03X707816Y67698I1J-197D01*
G01X707398Y67362D02*
G03X707537Y67420I0J197D01*
G01Y69863D02*
G03X707398Y69921I-139J-139D01*
G01X707816Y69585D02*
G03X707955Y69527I140J139D01*
G01Y72756D02*
G03X707816Y72698I1J-197D01*
G01X707398Y72362D02*
G03X707537Y72420I0J197D01*
G01Y74863D02*
G03X707398Y74921I-139J-139D01*
G01X707816Y74585D02*
G03X707955Y74527I140J139D01*
G01Y77756D02*
G03X707816Y77698I1J-197D01*
G01X707398Y77362D02*
G03X707537Y77420I0J197D01*
G01Y64863D02*
G03X707398Y64921I-139J-139D01*
G01X707816Y64585D02*
G03X707955Y64527I140J139D01*
G01X706557Y79133D02*
G03X706418Y79076I-1J-197D01*
G01X706197Y78937D02*
G03X706336Y78995I0J197D01*
G01X703444Y78963D02*
G03X703543Y78937I98J171D01*
G01X703444Y75813D02*
G03X703543Y75787I98J171D01*
G01Y74409D02*
G03X703444Y74383I-1J-197D01*
G01X706557Y72834D02*
G03X706418Y72777I0J-197D01*
G01X706197Y72637D02*
G03X706336Y72695I-1J197D01*
G01X703444Y72664D02*
G03X703543Y72637I100J170D01*
G01X706557Y69685D02*
G03X706418Y69627I1J-197D01*
G01X706197Y69488D02*
G03X706336Y69546I0J197D01*
G01X703444Y69514D02*
G03X703543Y69488I98J171D01*
G01X704674Y67369D02*
G03X704725Y67362I52J190D01*
G01Y69921D02*
G03X704674Y69914I1J-197D01*
G01Y72369D02*
G03X704725Y72362I52J190D01*
G01Y74921D02*
G03X704674Y74914I1J-197D01*
G01Y77369D02*
G03X704725Y77362I52J190D01*
G01X703444Y66365D02*
G03X703543Y66338I100J170D01*
G01Y64960D02*
G03X703444Y64934I-1J-197D01*
G01X706557Y63385D02*
G03X706418Y63328I-1J-197D01*
G01X706197Y63189D02*
G03X706336Y63246I1J197D01*
G01X703444Y63215D02*
G03X703543Y63189I98J171D01*
G01X704725Y64921D02*
G03X704674Y64914I1J-197D01*
G01X706418Y63328D02*
X706336Y63246D01*
G01X707816Y67698D02*
X707537Y67420D01*
G01X706476Y66535D02*
X706279Y66338D01*
G01X706418Y69627D02*
X706336Y69546D01*
G01X707816Y72698D02*
X707537Y72420D01*
G01X706418Y72777D02*
X706336Y72695D01*
G01X703149Y64763D02*
X703444Y64934D01*
G01X703149Y67913D02*
X703444Y68083D01*
G01X703149Y71063D02*
X703444Y71233D01*
G01X703149Y74212D02*
X703444Y74383D01*
G01X706476Y75984D02*
X706279Y75787D01*
G01X707816Y77698D02*
X707537Y77420D01*
G01X706418Y79076D02*
X706336Y78995D01*
G01X703149Y77362D02*
X703444Y77532D01*
G01X704330Y72992D02*
Y74291D01*
G01Y67992D02*
Y69291D01*
G01Y62992D02*
Y64291D01*
G01Y79291D02*
Y77992D01*
G01X707436Y77501D02*
X707517Y77420D01*
G01X707537Y74863D02*
X707816Y74585D01*
G01X707460Y74409D02*
X707657Y74212D01*
G01X707436Y71202D02*
X707517Y71120D01*
G01X707537Y69863D02*
X707816Y69585D01*
G01X707436Y68052D02*
X707517Y67971D01*
G01X707460Y64960D02*
X707657Y64763D01*
G01X707537Y64863D02*
X707816Y64585D01*
G01X703444Y78963D02*
X703149Y79133D01*
G01X703444Y75813D02*
X703149Y75984D01*
G01X703444Y72664D02*
X703149Y72834D01*
G01X703444Y69514D02*
X703149Y69685D01*
G01X703444Y66365D02*
X703149Y66535D01*
G01X703444Y63215D02*
X703149Y63385D01*
G01X704674Y77369D02*
X703149Y77778D01*
G01X704674Y72369D02*
X703149Y72778D01*
G01X704674Y67369D02*
X703149Y67778D01*
G01X706557Y79133D02*
X718109D01*
G01X703543Y78937D02*
X706197D01*
G01X703149Y77992D02*
X704330D01*
G01X707955Y77756D02*
X717429D01*
G01X703543Y77559D02*
X707296D01*
G01X704725Y77362D02*
X707398D01*
G01X718109D02*
X707657D01*
G01X706476Y75984D02*
X720078D01*
G01X703543Y75787D02*
X706279D01*
G01X707398Y74921D02*
X704725D01*
G01X717429Y74527D02*
X707955D01*
G01X707460Y74409D02*
X703543D01*
G01X704330Y74291D02*
X703149D01*
G01X720078Y74212D02*
X707657D01*
G01X703149Y72992D02*
X704330D01*
G01X706557Y72834D02*
X718109D01*
G01X707955Y72756D02*
X717524D01*
G01X703543Y72637D02*
X706197D01*
G01X704725Y72362D02*
X707398D01*
G01X703543Y71259D02*
X707296D01*
G01X718109Y71063D02*
X707657D01*
G01X707398Y69921D02*
X704725D01*
G01X706557Y69685D02*
X718109D01*
G01X717524Y69527D02*
X707955D01*
G01X703543Y69488D02*
X706197D01*
G01X703149Y69291D02*
X704330D01*
G01X703543Y68110D02*
X707296D01*
G01X703149Y67992D02*
X704330D01*
G01X718109Y67913D02*
X707657D01*
G01X707955Y67756D02*
X717429D01*
G01X704725Y67362D02*
X707398D01*
G01X706476Y66535D02*
X720078D01*
G01X703543Y66338D02*
X706279D01*
G01X707460Y64960D02*
X703543D01*
G01X707398Y64921D02*
X704725D01*
G01X720078Y64763D02*
X707657D01*
G01X717429Y64527D02*
X707955D01*
G01X703149Y64291D02*
X704330D01*
G01X706557Y63385D02*
X718109D01*
G01X703543Y63189D02*
X706197D01*
G01X703149Y62992D02*
X704330D01*
G01X707955Y62756D02*
X717524D01*
G01X703149Y74506D02*
X704674Y74914D01*
G01X703149Y69506D02*
X704674Y69914D01*
G01X703149Y64506D02*
X704674Y64914D01*
G01X703508Y90154D02*
X703543Y90157D01*
G01X703475Y90145D02*
X703508Y90154D01*
G01X703444Y90131D02*
X703475Y90145D01*
G01X703508Y87005D02*
X703543Y87008D01*
G01X703475Y86996D02*
X703508Y87005D01*
G01X703444Y86981D02*
X703475Y86996D01*
G01X703508Y80706D02*
X703543Y80708D01*
G01X703475Y80696D02*
X703508Y80706D01*
G01X703444Y80682D02*
X703475Y80696D01*
G01X703444Y94711D02*
G03X703543Y94685I98J171D01*
G01Y93307D02*
G03X703444Y93280I0J-197D01*
G01X707436Y90100D02*
G03X707296Y90157I-139J-140D01*
G01X707517Y90018D02*
G03X707657Y89960I140J139D01*
G01X706557Y91732D02*
G03X706418Y91674I0J-197D01*
G01X706197Y91535D02*
G03X706336Y91593I-1J197D01*
G01X703444Y91561D02*
G03X703543Y91535I98J171D01*
G01X704725Y89921D02*
G03X704674Y89914I1J-197D01*
G01X707537Y89863D02*
G03X707398Y89921I-139J-139D01*
G01X707816Y89585D02*
G03X707955Y89527I140J139D01*
G01Y92756D02*
G03X707816Y92698I1J-197D01*
G01X707398Y92362D02*
G03X707537Y92420I0J197D01*
G01X704674Y92369D02*
G03X704725Y92362I52J190D01*
G01Y94921D02*
G03X704674Y94914I1J-197D01*
G01X707537Y94863D02*
G03X707398Y94921I-139J-139D01*
G01X707816Y94585D02*
G03X707955Y94527I140J139D01*
G01X707436Y86950D02*
G03X707296Y87008I-140J-139D01*
G01X707517Y86869D02*
G03X707657Y86811I139J139D01*
G01X707436Y80651D02*
G03X707296Y80708I-139J-140D01*
G01X707517Y80569D02*
G03X707657Y80511I140J139D01*
G01X707537Y79863D02*
G03X707398Y79921I-139J-139D01*
G01X707816Y79585D02*
G03X707955Y79527I140J139D01*
G01Y82756D02*
G03X707816Y82698I1J-197D01*
G01X707398Y82362D02*
G03X707537Y82420I0J197D01*
G01Y84863D02*
G03X707398Y84921I-139J-139D01*
G01X707816Y84585D02*
G03X707955Y84527I140J139D01*
G01Y87756D02*
G03X707816Y87698I1J-197D01*
G01X707398Y87362D02*
G03X707537Y87420I0J197D01*
G01X706557Y88582D02*
G03X706418Y88525I-1J-197D01*
G01X706197Y88385D02*
G03X706336Y88443I-1J197D01*
G01X703444Y88412D02*
G03X703543Y88385I100J170D01*
G01X703444Y85262D02*
G03X703543Y85236I98J171D01*
G01Y83858D02*
G03X703444Y83832I-1J-197D01*
G01X706557Y82283D02*
G03X706418Y82226I0J-197D01*
G01X706197Y82086D02*
G03X706336Y82144I-1J197D01*
G01X703444Y82113D02*
G03X703543Y82086I100J170D01*
G01X704725Y79921D02*
G03X704674Y79914I1J-197D01*
G01Y82369D02*
G03X704725Y82362I52J190D01*
G01Y84921D02*
G03X704674Y84914I1J-197D01*
G01Y87369D02*
G03X704725Y87362I52J190D01*
G01X707816Y82698D02*
X707537Y82420D01*
G01X706418Y82226D02*
X706336Y82144D01*
G01X706476Y85433D02*
X706279Y85236D01*
G01X707816Y87698D02*
X707537Y87420D01*
G01X706418Y88525D02*
X706336Y88443D01*
G01X707816Y92698D02*
X707537Y92420D01*
G01X706418Y91674D02*
X706336Y91593D01*
G01X706476Y94882D02*
X706279Y94685D01*
G01X703149Y80511D02*
X703444Y80682D01*
G01X703149Y83661D02*
X703444Y83832D01*
G01X703149Y86811D02*
X703444Y86981D01*
G01X703149Y89960D02*
X703444Y90131D01*
G01X703149Y93110D02*
X703444Y93280D01*
G01X704330Y87992D02*
Y89291D01*
G01Y82992D02*
Y84291D01*
G01Y94291D02*
Y92992D01*
G01X707537Y94863D02*
X707816Y94585D01*
G01X707460Y93307D02*
X707657Y93110D01*
G01X707436Y90100D02*
X707517Y90018D01*
G01X707537Y89863D02*
X707816Y89585D01*
G01X707436Y86950D02*
X707517Y86869D01*
G01X707537Y84863D02*
X707816Y84585D01*
G01X707460Y83858D02*
X707657Y83661D01*
G01X707436Y80651D02*
X707517Y80569D01*
G01X707537Y79863D02*
X707816Y79585D01*
G01X703444Y94711D02*
X703149Y94882D01*
G01X703444Y91561D02*
X703149Y91732D01*
G01X703444Y88412D02*
X703149Y88582D01*
G01X703444Y85262D02*
X703149Y85433D01*
G01X703444Y82113D02*
X703149Y82283D01*
G01X704674Y92369D02*
X703149Y92778D01*
G01X704674Y87369D02*
X703149Y87778D01*
G01X704674Y82369D02*
X703149Y82778D01*
G01X707398Y94921D02*
X704725D01*
G01X706476Y94882D02*
X720078D01*
G01X703543Y94685D02*
X706279D01*
G01X717524Y94527D02*
X707955D01*
G01X704330Y94291D02*
X703149D01*
G01X707460Y93307D02*
X703543D01*
G01X720078Y93110D02*
X707657D01*
G01X703149Y92992D02*
X704330D01*
G01X707955Y92756D02*
X717524D01*
G01X704725Y92362D02*
X707398D01*
G01X706557Y91732D02*
X718109D01*
G01X703543Y91535D02*
X706197D01*
G01X703543Y90157D02*
X707296D01*
G01X718109Y89960D02*
X707657D01*
G01X707398Y89921D02*
X704725D01*
G01X717524Y89527D02*
X707955D01*
G01X704330Y89291D02*
X703149D01*
G01X718109Y88582D02*
X706557D01*
G01X706197Y88385D02*
X703543D01*
G01X703149Y87992D02*
X704330D01*
G01X707955Y87756D02*
X717524D01*
G01X704725Y87362D02*
X707398D01*
G01X707296Y87008D02*
X703543D01*
G01X718109Y86811D02*
X707657D01*
G01X706476Y85433D02*
X720078D01*
G01X703543Y85236D02*
X706279D01*
G01X707398Y84921D02*
X704725D01*
G01X717524Y84527D02*
X707955D01*
G01X704330Y84291D02*
X703149D01*
G01X707460Y83858D02*
X703543D01*
G01X720078Y83661D02*
X707657D01*
G01X704330Y82992D02*
X703149D01*
G01X707955Y82756D02*
X717429D01*
G01X704725Y82362D02*
X707398D01*
G01X706557Y82283D02*
X718109D01*
G01X703543Y82086D02*
X706197D01*
G01X703543Y80708D02*
X707296D01*
G01X718109Y80511D02*
X707657D01*
G01X707398Y79921D02*
X704725D01*
G01X717429Y79527D02*
X707955D01*
G01X704330Y79291D02*
X703149D01*
G01Y94506D02*
X704674Y94914D01*
G01X703149Y89506D02*
X704674Y89914D01*
G01X703149Y84506D02*
X704674Y84914D01*
G01X703149Y79506D02*
X704674Y79914D01*
G01X703508Y109052D02*
X703543Y109055D01*
G01X703475Y109043D02*
X703508Y109052D01*
G01X703444Y109028D02*
X703475Y109043D01*
G01X703508Y105902D02*
X703543Y105905D01*
G01X703475Y105893D02*
X703508Y105902D01*
G01X703444Y105879D02*
X703475Y105893D01*
G01X703508Y99603D02*
X703543Y99606D01*
G01X703475Y99594D02*
X703508Y99603D01*
G01X703444Y99580D02*
X703475Y99594D01*
G01X703508Y96454D02*
X703543Y96456D01*
G01X703475Y96445D02*
X703508Y96454D01*
G01X703444Y96430D02*
X703475Y96445D01*
G01X703543Y112204D02*
G03X703444Y112178I-1J-197D01*
G01X707436Y108997D02*
G03X707296Y109055I-140J-139D01*
G01X707517Y108916D02*
G03X707657Y108858I140J139D01*
G01X706557Y110630D02*
G03X706418Y110572I1J-197D01*
G01X706197Y110433D02*
G03X706336Y110491I0J197D01*
G01X703444Y110459D02*
G03X703543Y110433I98J171D01*
G01X707436Y105848D02*
G03X707296Y105905I-139J-140D01*
G01X707517Y105766D02*
G03X707657Y105708I140J139D01*
G01X706557Y107480D02*
G03X706418Y107422I0J-197D01*
G01X706197Y107283D02*
G03X706336Y107341I-1J197D01*
G01X703444Y107309D02*
G03X703543Y107283I98J171D01*
G01X703444Y104160D02*
G03X703543Y104133I100J170D01*
G01Y102756D02*
G03X703444Y102729I1J-197D01*
G01X706557Y101181D02*
G03X706418Y101123I1J-197D01*
G01X706197Y100984D02*
G03X706336Y101042I0J197D01*
G01X703444Y101010D02*
G03X703543Y100984I98J171D01*
G01X704725Y109921D02*
G03X704674Y109914I1J-197D01*
G01X707537Y109863D02*
G03X707398Y109921I-139J-139D01*
G01X707816Y109585D02*
G03X707955Y109527I140J139D01*
G01Y102756D02*
G03X707816Y102698I1J-197D01*
G01X707398Y102362D02*
G03X707537Y102420I0J197D01*
G01X704674Y102369D02*
G03X704725Y102362I52J190D01*
G01Y104921D02*
G03X704674Y104914I1J-197D01*
G01X707537Y104863D02*
G03X707398Y104921I-139J-139D01*
G01X707816Y104585D02*
G03X707955Y104527I140J139D01*
G01Y107756D02*
G03X707816Y107698I1J-197D01*
G01X707398Y107362D02*
G03X707537Y107420I0J197D01*
G01X704674Y107369D02*
G03X704725Y107362I52J190D01*
G01X707436Y99548D02*
G03X707296Y99606I-140J-139D01*
G01X707517Y99467D02*
G03X707657Y99409I140J139D01*
G01X707436Y96399D02*
G03X707296Y96456I-139J-140D01*
G01X707517Y96317D02*
G03X707657Y96259I140J139D01*
G01X706557Y98031D02*
G03X706418Y97974I0J-197D01*
G01X706197Y97834D02*
G03X706336Y97892I-1J197D01*
G01X703444Y97861D02*
G03X703543Y97834I100J170D01*
G01X707955Y97756D02*
G03X707816Y97698I1J-197D01*
G01X707398Y97362D02*
G03X707537Y97420I0J197D01*
G01X704674Y97369D02*
G03X704725Y97362I52J190D01*
G01Y99921D02*
G03X704674Y99914I1J-197D01*
G01X707537Y99863D02*
G03X707398Y99921I-139J-139D01*
G01X707816Y99585D02*
G03X707955Y99527I140J139D01*
G01X707816Y97698D02*
X707537Y97420D01*
G01X706418Y97974D02*
X706336Y97892D01*
G01X706418Y101123D02*
X706336Y101042D01*
G01X707816Y102698D02*
X707537Y102420D01*
G01X706476Y104330D02*
X706279Y104133D01*
G01X707816Y107698D02*
X707537Y107420D01*
G01X706418Y107422D02*
X706336Y107341D01*
G01X706418Y110572D02*
X706336Y110491D01*
G01X704330Y107992D02*
Y109291D01*
G01Y97992D02*
Y99291D01*
G01Y104291D02*
Y102992D01*
G01X703149Y96259D02*
X703444Y96430D01*
G01X703149Y99409D02*
X703444Y99580D01*
G01X703149Y102559D02*
X703444Y102729D01*
G01X703149Y105708D02*
X703444Y105879D01*
G01X703149Y108858D02*
X703444Y109028D01*
G01X703149Y112008D02*
X703444Y112178D01*
G01X707460Y112204D02*
X707657Y112008D01*
G01X707537Y109863D02*
X707816Y109585D01*
G01X707436Y108997D02*
X707517Y108916D01*
G01X707436Y105848D02*
X707517Y105766D01*
G01X707537Y104863D02*
X707816Y104585D01*
G01X707460Y102756D02*
X707657Y102559D01*
G01X707537Y99863D02*
X707816Y99585D01*
G01X707436Y99548D02*
X707517Y99467D01*
G01X707436Y96399D02*
X707517Y96317D01*
G01X703444Y110459D02*
X703149Y110630D01*
G01X703444Y107309D02*
X703149Y107480D01*
G01X703444Y104160D02*
X703149Y104330D01*
G01X703444Y101010D02*
X703149Y101181D01*
G01X703444Y97861D02*
X703149Y98031D01*
G01X704674Y107369D02*
X703149Y107778D01*
G01X704674Y102369D02*
X703149Y102778D01*
G01X704674Y97369D02*
X703149Y97778D01*
G01X707460Y112204D02*
X703543D01*
G01X720078Y112008D02*
X707657D01*
G01X706557Y110630D02*
X718109D01*
G01X703543Y110433D02*
X706197D01*
G01X707398Y109921D02*
X704725D01*
G01X717429Y109527D02*
X707955D01*
G01X704330Y109291D02*
X703149D01*
G01X703543Y109055D02*
X707296D01*
G01X718109Y108858D02*
X707657D01*
G01X704330Y107992D02*
X703149D01*
G01X707955Y107756D02*
X717524D01*
G01X706557Y107480D02*
X718109D01*
G01X704725Y107362D02*
X707398D01*
G01X703543Y107283D02*
X706197D01*
G01X703543Y105905D02*
X707296D01*
G01X718109Y105708D02*
X707657D01*
G01X707398Y104921D02*
X704725D01*
G01X717524Y104527D02*
X707955D01*
G01X706476Y104330D02*
X720078D01*
G01X704330Y104291D02*
X703149D01*
G01X703543Y104133D02*
X706279D01*
G01X704330Y102992D02*
X703149D01*
G01X707955Y102756D02*
X717524D01*
G01X707460D02*
X703543D01*
G01X720078Y102559D02*
X707657D01*
G01X704725Y102362D02*
X707398D01*
G01X706557Y101181D02*
X718109D01*
G01X703543Y100984D02*
X706197D01*
G01X707398Y99921D02*
X704725D01*
G01X703543Y99606D02*
X707296D01*
G01X717524Y99527D02*
X707955D01*
G01X718109Y99409D02*
X707657D01*
G01X703149Y99291D02*
X704330D01*
G01X706557Y98031D02*
X718109D01*
G01X704330Y97992D02*
X703149D01*
G01X703543Y97834D02*
X706197D01*
G01X707955Y97756D02*
X717524D01*
G01X704725Y97362D02*
X707398D01*
G01X703543Y96456D02*
X707296D01*
G01X718109Y96259D02*
X707657D01*
G01X703149Y109506D02*
X704674Y109914D01*
G01X703149Y104506D02*
X704674Y104914D01*
G01X703508Y99603D02*
X704674Y99914D01*
G01X703149Y99506D02*
X703475Y99594D01*
G01X703508Y124800D02*
X703543Y124803D01*
G01X703475Y124791D02*
X703508Y124800D01*
G01X703444Y124776D02*
X703475Y124791D01*
G01X703508Y121650D02*
X703543Y121653D01*
G01X703475Y121641D02*
X703508Y121650D01*
G01X703444Y121627D02*
X703475Y121641D01*
G01X703508Y115351D02*
X703543Y115354D01*
G01X703475Y115342D02*
X703508Y115351D01*
G01X703444Y115328D02*
X703475Y115342D01*
G01X703543Y127952D02*
G03X703444Y127926I-1J-197D01*
G01X707436Y124745D02*
G03X707296Y124803I-140J-139D01*
G01X707517Y124664D02*
G03X707657Y124606I140J139D01*
G01X706557Y126378D02*
G03X706418Y126320I1J-197D01*
G01X706197Y126181D02*
G03X706336Y126239I0J197D01*
G01X703444Y126207D02*
G03X703543Y126181I98J171D01*
G01X706557Y123228D02*
G03X706418Y123170I0J-197D01*
G01X706197Y123031D02*
G03X706336Y123089I-1J197D01*
G01X703444Y123058D02*
G03X703543Y123031I100J170D01*
G01X707436Y121596D02*
G03X707296Y121653I-139J-140D01*
G01X707517Y121514D02*
G03X707657Y121456I140J139D01*
G01X703444Y119908D02*
G03X703543Y119882I98J171D01*
G01Y118504D02*
G03X703444Y118477I1J-197D01*
G01X707436Y115296D02*
G03X707296Y115354I-139J-139D01*
G01X707517Y115215D02*
G03X707657Y115157I140J139D01*
G01X706557Y116929D02*
G03X706418Y116871I1J-197D01*
G01X706197Y116732D02*
G03X706336Y116790I0J197D01*
G01X703444Y116758D02*
G03X703543Y116732I98J171D01*
G01X703444Y113609D02*
G03X703543Y113582I100J170D01*
G01X707955Y112756D02*
G03X707816Y112698I1J-197D01*
G01X707398Y112362D02*
G03X707537Y112420I0J197D01*
G01X704674Y112369D02*
G03X704725Y112362I52J190D01*
G01Y114921D02*
G03X704674Y114914I1J-197D01*
G01X707537Y114863D02*
G03X707398Y114921I-139J-139D01*
G01X707816Y114585D02*
G03X707955Y114527I140J139D01*
G01Y117756D02*
G03X707816Y117698I1J-197D01*
G01X707398Y117362D02*
G03X707537Y117420I0J197D01*
G01X704674Y117369D02*
G03X704725Y117362I52J190D01*
G01X703202Y122933D02*
G03X703149Y122926I-1J-197D01*
G01Y124712D02*
G03X703202Y124704I56J189D01*
G01Y126082D02*
G03X703149Y126075I-1J-197D01*
G01Y127861D02*
G03X703202Y127854I52J190D01*
G01Y119783D02*
G03X703149Y119776I-1J-197D01*
G01Y121562D02*
G03X703202Y121555I52J190D01*
G01X707816Y112698D02*
X707537Y112420D01*
G01X706476Y113779D02*
X706279Y113582D01*
G01X707816Y117698D02*
X707537Y117420D01*
G01X706418Y116871D02*
X706336Y116790D01*
G01X706476Y120078D02*
X706279Y119882D01*
G01X706418Y123170D02*
X706336Y123089D01*
G01X704330Y114291D02*
Y112992D01*
G01Y119094D02*
Y117992D01*
G01X706418Y126320D02*
X706336Y126239D01*
G01X703149Y115157D02*
X703444Y115328D01*
G01X703149Y118307D02*
X703444Y118477D01*
G01X703149Y121456D02*
X703444Y121627D01*
G01X703149Y124606D02*
X703444Y124776D01*
G01X703149Y127756D02*
X703444Y127926D01*
G01X707460Y127952D02*
X707657Y127756D01*
G01X707436Y124745D02*
X707517Y124664D01*
G01X707436Y121596D02*
X707517Y121514D01*
G01X707460Y118504D02*
X707657Y118307D01*
G01X707436Y115296D02*
X707517Y115215D01*
G01X707537Y114863D02*
X707816Y114585D01*
G01X703444Y126207D02*
X703149Y126378D01*
G01X703444Y123058D02*
X703149Y123228D01*
G01X703444Y119908D02*
X703149Y120078D01*
G01X703444Y116758D02*
X703149Y116929D01*
G01X703444Y113609D02*
X703149Y113779D01*
G01X704674Y117369D02*
X703149Y117778D01*
G01X704674Y112369D02*
X703149Y112778D01*
G01X707460Y127952D02*
X703543D01*
G01X703202Y127854D02*
X718109D01*
G01X720078Y127756D02*
X707657D01*
G01X706557Y126378D02*
X718109D01*
G01X703543Y126181D02*
X706197D01*
G01X718109Y126082D02*
X703202D01*
G01X703543Y124803D02*
X707296D01*
G01X703202Y124704D02*
X718109D01*
G01Y124606D02*
X707657D01*
G01X706557Y123228D02*
X718109D01*
G01X703543Y123031D02*
X706197D01*
G01X718109Y122933D02*
X703202D01*
G01X703543Y121653D02*
X707296D01*
G01X703202Y121555D02*
X720078D01*
G01X718109Y121456D02*
X707657D01*
G01X706476Y120078D02*
X720078D01*
G01X703543Y119882D02*
X706279D01*
G01X720078Y119783D02*
X703202D01*
G01X720865Y119094D02*
X703149D01*
G01X707460Y118504D02*
X703543D01*
G01X720078Y118307D02*
X707657D01*
G01X703149Y117992D02*
X704330D01*
G01X707955Y117756D02*
X717429D01*
G01X704725Y117362D02*
X707398D01*
G01X706557Y116929D02*
X718109D01*
G01X703543Y116732D02*
X706197D01*
G01X703543Y115354D02*
X707296D01*
G01X718109Y115157D02*
X707657D01*
G01X707398Y114921D02*
X704725D01*
G01X717429Y114527D02*
X707955D01*
G01X703149Y114291D02*
X704330D01*
G01X706476Y113779D02*
X720078D01*
G01X703543Y113582D02*
X706279D01*
G01X704330Y112992D02*
X703149D01*
G01X707955Y112756D02*
X717429D01*
G01X704725Y112362D02*
X707398D01*
G01X703149Y114506D02*
X704674Y114914D01*
G01X703508Y140548D02*
X703543Y140551D01*
G01X703475Y140539D02*
X703508Y140548D01*
G01X703444Y140524D02*
X703475Y140539D01*
G01X703508Y134249D02*
X703543Y134252D01*
G01X703475Y134240D02*
X703508Y134249D01*
G01X703444Y134225D02*
X703475Y134240D01*
G01X703508Y131099D02*
X703543Y131102D01*
G01X703475Y131090D02*
X703508Y131099D01*
G01X703444Y131076D02*
X703475Y131090D01*
G01X703543Y143700D02*
G03X703444Y143674I-1J-197D01*
G01Y145105D02*
G03X703543Y145078I100J170D01*
G01X704725Y144921D02*
G03X704674Y144914I1J-197D01*
G01X707537Y144863D02*
G03X707398Y144921I-139J-139D01*
G01X707816Y144585D02*
G03X707955Y144527I140J139D01*
G01X707517Y134113D02*
G03X707657Y134055I140J139D01*
G01X706557Y135826D02*
G03X706418Y135769I-1J-197D01*
G01X706197Y135630D02*
G03X706336Y135687I1J197D01*
G01X703444Y135656D02*
G03X703543Y135630I98J171D01*
G01X707436Y134194D02*
G03X707296Y134252I-140J-139D01*
G01X703543Y137401D02*
G03X703444Y137375I-1J-197D01*
G01Y138806D02*
G03X703543Y138779I100J170D01*
G01X706197Y132480D02*
G03X706336Y132538I0J197D01*
G01X703444Y132506D02*
G03X703543Y132480I98J171D01*
G01X703444Y141955D02*
G03X703543Y141929I98J171D01*
G01X706197D02*
G03X706336Y141987I0J197D01*
G01X706557Y142126D02*
G03X706418Y142068I1J-197D01*
G01X707517Y140412D02*
G03X707657Y140354I140J139D01*
G01X707436Y140493D02*
G03X707296Y140551I-140J-139D01*
G01X704725Y139921D02*
G03X704674Y139914I1J-197D01*
G01X707537Y139863D02*
G03X707398Y139921I-139J-139D01*
G01X707816Y139585D02*
G03X707955Y139527I140J139D01*
G01Y142756D02*
G03X707816Y142698I1J-197D01*
G01X707398Y142362D02*
G03X707537Y142420I0J197D01*
G01X704674Y142369D02*
G03X704725Y142362I52J190D01*
G01X703149Y134161D02*
G03X703202Y134153I56J189D01*
G01Y135531D02*
G03X703149Y135524I-1J-197D01*
G01Y137310D02*
G03X703202Y137303I52J190D01*
G01X707436Y131045D02*
G03X707296Y131102I-139J-140D01*
G01X707517Y130963D02*
G03X707657Y130905I140J139D01*
G01X706557Y132677D02*
G03X706418Y132619I1J-197D01*
G01X703444Y129357D02*
G03X703543Y129330I100J170D01*
G01X703202Y129232D02*
G03X703149Y129225I-1J-197D01*
G01Y131011D02*
G03X703202Y131004I52J190D01*
G01Y132382D02*
G03X703149Y132374I3J-197D01*
G01X704330Y142992D02*
Y144291D01*
G01Y138189D02*
Y139291D01*
G01X706476Y129527D02*
X706279Y129330D01*
G01X706418Y132619D02*
X706336Y132538D01*
G01X706418Y135769D02*
X706336Y135687D01*
G01X706476Y138976D02*
X706279Y138779D01*
G01X707816Y142698D02*
X707537Y142420D01*
G01X706418Y142068D02*
X706336Y141987D01*
G01X706476Y145275D02*
X706279Y145078D01*
G01X703149Y130905D02*
X703444Y131076D01*
G01X703149Y134055D02*
X703444Y134225D01*
G01X703149Y137204D02*
X703444Y137375D01*
G01X703149Y140354D02*
X703444Y140524D01*
G01X703149Y143504D02*
X703444Y143674D01*
G01X707537Y144863D02*
X707816Y144585D01*
G01X707460Y143700D02*
X707657Y143504D01*
G01X707436Y140493D02*
X707517Y140412D01*
G01X707537Y139863D02*
X707816Y139585D01*
G01X707460Y137401D02*
X707657Y137204D01*
G01X707436Y134194D02*
X707517Y134113D01*
G01X707436Y131045D02*
X707517Y130963D01*
G01X703444Y145105D02*
X703149Y145275D01*
G01X703444Y141955D02*
X703149Y142126D01*
G01X703444Y138806D02*
X703149Y138976D01*
G01X703444Y135656D02*
X703149Y135826D01*
G01X703444Y132506D02*
X703149Y132677D01*
G01X703444Y129357D02*
X703149Y129527D01*
G01X704674Y142369D02*
X703149Y142778D01*
G01X703543Y145078D02*
X706279D01*
G01X707398Y144921D02*
X704725D01*
G01X717429Y144527D02*
X707955D01*
G01X704330Y144291D02*
X703149D01*
G01X707460Y143700D02*
X703543D01*
G01X720078Y143504D02*
X707657D01*
G01X704330Y142992D02*
X703149D01*
G01X707955Y142756D02*
X717524D01*
G01X704725Y142362D02*
X707398D01*
G01X706557Y142126D02*
X718109D01*
G01X703543Y141929D02*
X706197D01*
G01X703543Y140551D02*
X707296D01*
G01X718109Y140354D02*
X707657D01*
G01X707398Y139921D02*
X704725D01*
G01X717524Y139527D02*
X707955D01*
G01X703149Y139291D02*
X704330D01*
G01X706476Y138976D02*
X720078D01*
G01X703543Y138779D02*
X706279D01*
G01X703149Y138189D02*
X720865D01*
G01X707460Y137401D02*
X703543D01*
G01X703202Y137303D02*
X718109D01*
G01X720078Y137204D02*
X707657D01*
G01X706557Y135826D02*
X718109D01*
G01X703543Y135630D02*
X706197D01*
G01X718109Y135531D02*
X703202D01*
G01X703543Y134252D02*
X707296D01*
G01X703202Y134153D02*
X718109D01*
G01Y134055D02*
X707657D01*
G01X706557Y132677D02*
X718109D01*
G01X703543Y132480D02*
X706197D01*
G01X718109Y132382D02*
X703202D01*
G01X703543Y131102D02*
X707296D01*
G01X703202Y131004D02*
X720078D01*
G01X718109Y130905D02*
X707657D01*
G01X706476Y129527D02*
X720078D01*
G01X703543Y129330D02*
X706279D01*
G01X720078Y129232D02*
X703202D01*
G01X703149Y144506D02*
X704674Y144914D01*
G01X703149Y139506D02*
X704674Y139914D01*
G01X703508Y159446D02*
X703543Y159448D01*
G01X703475Y159437D02*
X703508Y159446D01*
G01X703444Y159422D02*
X703475Y159437D01*
G01X703508Y156296D02*
X703543Y156299D01*
G01X703475Y156287D02*
X703508Y156296D01*
G01X703444Y156272D02*
X703475Y156287D01*
G01X703508Y149997D02*
X703543Y150000D01*
G01X703475Y149988D02*
X703508Y149997D01*
G01X703444Y149973D02*
X703475Y149988D01*
G01X703508Y146847D02*
X703543Y146850D01*
G01X703475Y146838D02*
X703508Y146847D01*
G01X703444Y146824D02*
X703475Y146838D01*
G01X703543Y153149D02*
G03X703444Y153123I-1J-197D01*
G01Y154554D02*
G03X703543Y154527I100J170D01*
G01X703444Y157703D02*
G03X703543Y157677I98J171D01*
G01X706197D02*
G03X706336Y157735I0J197D01*
G01X706557Y157874D02*
G03X706418Y157816I1J-197D01*
G01X707517Y156160D02*
G03X707657Y156102I140J139D01*
G01X707436Y156241D02*
G03X707296Y156299I-140J-139D01*
G01X703444Y160853D02*
G03X703543Y160826I100J170D01*
G01X706197D02*
G03X706336Y160884I-1J197D01*
G01X706557Y161023D02*
G03X706418Y160966I0J-197D01*
G01X707517Y159309D02*
G03X707657Y159252I139J140D01*
G01X707436Y159391D02*
G03X707296Y159448I-138J-140D01*
G01X704725Y154921D02*
G03X704674Y154914I1J-197D01*
G01X707537Y154863D02*
G03X707398Y154921I-139J-139D01*
G01X707816Y154585D02*
G03X707955Y154527I140J139D01*
G01Y157756D02*
G03X707816Y157698I1J-197D01*
G01X707398Y157362D02*
G03X707537Y157420I0J197D01*
G01X704674Y157369D02*
G03X704725Y157362I52J190D01*
G01Y159921D02*
G03X704674Y159914I1J-197D01*
G01X707537Y159863D02*
G03X707398Y159921I-139J-139D01*
G01X707816Y159585D02*
G03X707955Y159527I140J139D01*
G01X703444Y148254D02*
G03X703543Y148228I98J171D01*
G01X706197D02*
G03X706336Y148286I0J197D01*
G01X706557Y148425D02*
G03X706418Y148367I1J-197D01*
G01X707517Y146711D02*
G03X707657Y146653I140J139D01*
G01X707436Y146793D02*
G03X707296Y146850I-139J-140D01*
G01X703444Y151404D02*
G03X703543Y151378I98J171D01*
G01X706197D02*
G03X706336Y151435I1J197D01*
G01X706557Y151574D02*
G03X706418Y151517I-1J-197D01*
G01X707517Y149861D02*
G03X707657Y149803I140J139D01*
G01X707436Y149942D02*
G03X707296Y150000I-140J-139D01*
G01X707955Y147756D02*
G03X707816Y147698I1J-197D01*
G01X707398Y147362D02*
G03X707537Y147420I0J197D01*
G01X704674Y147369D02*
G03X704725Y147362I52J190D01*
G01Y149921D02*
G03X704674Y149914I1J-197D01*
G01X707537Y149863D02*
G03X707398Y149921I-139J-139D01*
G01X707816Y149585D02*
G03X707955Y149527I140J139D01*
G01Y152756D02*
G03X707816Y152698I1J-197D01*
G01X707398Y152362D02*
G03X707537Y152420I0J197D01*
G01X704674Y152369D02*
G03X704725Y152362I52J190D01*
G01X704330Y147992D02*
Y149291D01*
G01Y154291D02*
Y152992D01*
G01Y159291D02*
Y157992D01*
G01X707816Y147698D02*
X707537Y147420D01*
G01X706418Y148367D02*
X706336Y148286D01*
G01X707816Y152698D02*
X707537Y152420D01*
G01X706418Y151517D02*
X706336Y151435D01*
G01X706476Y154724D02*
X706279Y154527D01*
G01X707816Y157698D02*
X707537Y157420D01*
G01X706418Y157816D02*
X706336Y157735D01*
G01X706418Y160966D02*
X706336Y160884D01*
G01X703149Y146653D02*
X703444Y146824D01*
G01X703149Y149803D02*
X703444Y149973D01*
G01X707537Y159863D02*
X707816Y159585D01*
G01X707436Y159391D02*
X707517Y159309D01*
G01X707436Y156241D02*
X707517Y156160D01*
G01X707537Y154863D02*
X707816Y154585D01*
G01X707460Y153149D02*
X707657Y152952D01*
G01X707537Y149863D02*
X707816Y149585D01*
G01X707436Y149942D02*
X707517Y149861D01*
G01X707436Y146793D02*
X707517Y146711D01*
G01X703149Y152952D02*
X703444Y153123D01*
G01X703149Y156102D02*
X703444Y156272D01*
G01X703149Y159252D02*
X703444Y159422D01*
G01Y160853D02*
X703149Y161023D01*
G01X703444Y157703D02*
X703149Y157874D01*
G01X703444Y154554D02*
X703149Y154724D01*
G01X703444Y151404D02*
X703149Y151574D01*
G01X703444Y148254D02*
X703149Y148425D01*
G01X704674Y157369D02*
X703149Y157778D01*
G01X704674Y152369D02*
X703149Y152778D01*
G01X704674Y147369D02*
X703149Y147778D01*
G01X706557Y161023D02*
X718109D01*
G01X703543Y160826D02*
X706197D01*
G01X707398Y159921D02*
X704725D01*
G01X717429Y159527D02*
X707955D01*
G01X703543Y159448D02*
X707296D01*
G01X703149Y159291D02*
X704330D01*
G01X718109Y159252D02*
X707657D01*
G01X704330Y157992D02*
X703149D01*
G01X706557Y157874D02*
X718109D01*
G01X707955Y157756D02*
X717524D01*
G01X703543Y157677D02*
X706197D01*
G01X704725Y157362D02*
X707398D01*
G01X703543Y156299D02*
X707296D01*
G01X718109Y156102D02*
X707657D01*
G01X707398Y154921D02*
X704725D01*
G01X706476Y154724D02*
X720078D01*
G01X703543Y154527D02*
X706279D01*
G01X717524D02*
X707955D01*
G01X704330Y154291D02*
X703149D01*
G01X707460Y153149D02*
X703543D01*
G01X704330Y152992D02*
X703149D01*
G01X720078Y152952D02*
X707657D01*
G01X707955Y152756D02*
X717429D01*
G01X704725Y152362D02*
X707398D01*
G01X706557Y151574D02*
X718109D01*
G01X703543Y151378D02*
X706197D01*
G01X703543Y150000D02*
X707296D01*
G01X707398Y149921D02*
X704725D01*
G01X718109Y149803D02*
X707657D01*
G01X717429Y149527D02*
X707955D01*
G01X704330Y149291D02*
X703149D01*
G01X706557Y148425D02*
X718109D01*
G01X703543Y148228D02*
X706197D01*
G01X703149Y147992D02*
X704330D01*
G01X707955Y147756D02*
X717429D01*
G01X704725Y147362D02*
X707398D01*
G01X703543Y146850D02*
X707296D01*
G01X718109Y146653D02*
X707657D01*
G01X706476Y145275D02*
X720078D01*
G01X703149Y159506D02*
X704674Y159914D01*
G01X703149Y154506D02*
X704674Y154914D01*
G01X703149Y149506D02*
X704674Y149914D01*
G01X703508Y168895D02*
X703543Y168897D01*
G01X703475Y168885D02*
X703508Y168895D01*
G01X703444Y168871D02*
X703475Y168885D01*
G01X703508Y165745D02*
X703543Y165748D01*
G01X703475Y165736D02*
X703508Y165745D01*
G01X703444Y165721D02*
X703475Y165736D01*
G01X703444Y164002D02*
G03X703543Y163976I98J171D01*
G01X703444Y167152D02*
G03X703543Y167126I98J171D01*
G01X706197D02*
G03X706336Y167183I1J197D01*
G01X706557Y167322D02*
G03X706418Y167265I-1J-197D01*
G01X707517Y165609D02*
G03X707657Y165551I140J139D01*
G01X707436Y165690D02*
G03X707296Y165748I-140J-139D01*
G01X703444Y170302D02*
G03X703543Y170275I100J170D01*
G01X706197D02*
G03X706336Y170333I-1J197D01*
G01X706557Y170472D02*
G03X706418Y170415I0J-197D01*
G01X707517Y168758D02*
G03X707657Y168700I140J139D01*
G01X707436Y168840D02*
G03X707296Y168897I-139J-140D01*
G01X704725Y164921D02*
G03X704674Y164914I1J-197D01*
G01X707537Y164863D02*
G03X707398Y164921I-139J-139D01*
G01X707816Y164585D02*
G03X707955Y164527I140J139D01*
G01Y167756D02*
G03X707816Y167698I1J-197D01*
G01X707398Y167362D02*
G03X707537Y167420I0J197D01*
G01X704674Y167369D02*
G03X704725Y167362I52J190D01*
G01Y169921D02*
G03X704674Y169914I1J-197D01*
G01X707537Y169863D02*
G03X707398Y169921I-139J-139D01*
G01X707816Y169585D02*
G03X707955Y169527I140J139D01*
G01Y172756D02*
G03X707816Y172698I1J-197D01*
G01X707398Y172362D02*
G03X707537Y172420I0J197D01*
G01X704674Y172369D02*
G03X704725Y172362I52J190D01*
G01X703543Y162598D02*
G03X703444Y162572I-1J-197D01*
G01X707955Y162756D02*
G03X707816Y162698I1J-197D01*
G01X707398Y162362D02*
G03X707537Y162420I0J197D01*
G01X704674Y162369D02*
G03X704725Y162362I52J190D01*
G01X704330Y162992D02*
Y164291D01*
G01Y169291D02*
Y167992D01*
G01Y174448D02*
Y172992D01*
G01X707816Y162698D02*
X707537Y162420D01*
G01X706476Y164173D02*
X706279Y163976D01*
G01X707816Y167698D02*
X707537Y167420D01*
G01X706418Y167265D02*
X706336Y167183D01*
G01X706418Y170415D02*
X706336Y170333D01*
G01X707537Y169863D02*
X707816Y169585D01*
G01X707436Y168840D02*
X707517Y168758D01*
G01X707816Y172698D02*
X707537Y172420D01*
G01X707436Y165690D02*
X707517Y165609D01*
G01X707537Y164863D02*
X707816Y164585D01*
G01X707460Y162598D02*
X707657Y162401D01*
G01X703149D02*
X703444Y162572D01*
G01X703149Y165551D02*
X703444Y165721D01*
G01X703149Y168700D02*
X703444Y168871D01*
G01Y170302D02*
X703149Y170472D01*
G01X703444Y167152D02*
X703149Y167322D01*
G01X703444Y164002D02*
X703149Y164173D01*
G01X704674Y172369D02*
X703149Y172778D01*
G01X704674Y167369D02*
X703149Y167778D01*
G01X704674Y162369D02*
X703149Y162778D01*
G01X704330Y172992D02*
X703149D01*
G01X707955Y172756D02*
X717524D01*
G01X704725Y172362D02*
X707398D01*
G01X718109Y170472D02*
X706557D01*
G01X706197Y170275D02*
X703543D01*
G01X707398Y169921D02*
X704725D01*
G01X717524Y169527D02*
X707955D01*
G01X703149Y169291D02*
X704330D01*
G01X707296Y168897D02*
X703543D01*
G01X718109Y168700D02*
X707657D01*
G01X703149Y167992D02*
X704330D01*
G01X707955Y167756D02*
X717429D01*
G01X704725Y167362D02*
X707398D01*
G01X706557Y167322D02*
X718109D01*
G01X703543Y167126D02*
X706197D01*
G01X703543Y165748D02*
X707296D01*
G01X718109Y165551D02*
X707657D01*
G01X707398Y164921D02*
X704725D01*
G01X717429Y164527D02*
X707955D01*
G01X703149Y164291D02*
X704330D01*
G01X706476Y164173D02*
X720078D01*
G01X703543Y163976D02*
X706279D01*
G01X703149Y162992D02*
X704330D01*
G01X707955Y162756D02*
X717429D01*
G01X707460Y162598D02*
X703543D01*
G01X720078Y162401D02*
X707657D01*
G01X704725Y162362D02*
X707398D01*
G01X703149Y169506D02*
X704674Y169914D01*
G01X703149Y164506D02*
X704674Y164914D01*
G01X716141Y193956D02*
Y203582D01*
G01Y192756D02*
Y193956D01*
G01X714566Y189606D02*
Y192756D01*
G01X703149Y179882D02*
X705117Y181850D01*
G01D02*
X720393D01*
G01X703534Y199294D02*
X703543Y199313D01*
G01X703435Y199263D02*
X703534Y199294D01*
G01X703231Y199253D02*
X703435Y199263D01*
G01X711141Y198086D02*
X711052Y198117D01*
G01X711274Y198074D02*
X711141Y198086D01*
G01X711436Y198071D02*
X711274Y198074D01*
G01X711168Y199259D02*
X711360Y199252D01*
G01X711052Y199281D02*
X711168Y199259D01*
G01X711026Y199327D02*
X711023Y199313D01*
G01X711042Y199347D02*
X711026Y199327D01*
G01X711023Y198162D02*
Y198169D01*
G01X711032Y198138D02*
X711023Y198162D01*
G01X711052Y198117D02*
X711032Y198138D01*
G01X703250Y198072D02*
X703153Y198071D01*
G01X703343Y198077D02*
X703250Y198072D01*
G01X703424Y198086D02*
X703343Y198077D01*
G01X703489Y198104D02*
X703424Y198086D01*
G01X703530Y198133D02*
X703489Y198104D01*
G01X703543Y198169D02*
X703530Y198133D01*
G01X711226Y199612D02*
X711042Y199347D01*
G01X711410Y200023D02*
X711226Y199612D01*
G01X711595Y200542D02*
X711410Y200023D01*
G01Y199305D02*
X711595Y200136D01*
G01X711226Y198647D02*
X711410Y199305D01*
G01X711042Y198223D02*
X711226Y198647D01*
G01X703155Y200023D02*
X702971Y200542D01*
G01X703339Y199612D02*
X703155Y200023D01*
G01X703524Y199347D02*
X703339Y199612D01*
G01X703543Y198174D02*
Y198169D01*
G01X703524Y198223D02*
X703543Y198174D01*
G01X711032Y199294D02*
X711052Y199281D01*
G01X711023Y199309D02*
X711032Y199294D01*
G01X711023Y199313D02*
Y199309D01*
G01X702960Y200198D02*
X702971Y200136D01*
G01X702954Y200260D02*
X702960Y200198D01*
G01X702952Y200323D02*
X702954Y200260D01*
G01X711605Y200580D02*
X711595Y200542D01*
G01X711611Y200619D02*
X711605Y200580D01*
G01X711613Y200659D02*
X711611Y200619D01*
G01X711026Y198191D02*
X711042Y198223D01*
G01X711023Y198169D02*
X711026Y198191D01*
G01X711611Y200260D02*
X711613Y200323D01*
G01X711605Y200198D02*
X711611Y200260D01*
G01X711595Y200136D02*
X711605Y200198D01*
G01X702954Y200619D02*
X702952Y200659D01*
G01X702960Y200580D02*
X702954Y200619D01*
G01X702971Y200542D02*
X702960Y200580D01*
G01X703339Y198647D02*
X703524Y198223D01*
G01X703155Y199305D02*
X703339Y198647D01*
G01X702971Y200136D02*
X703155Y199305D01*
G01X704133Y208267D02*
G03X702952Y207086I0J-1181D01*
G01X711613D02*
G03X710432Y208267I-1181J0D01*
G01X716180Y199252D02*
Y198070D01*
G01X715590Y199252D02*
Y198070D01*
G01X714291Y199252D02*
Y198070D01*
G01X713813D02*
Y199252D01*
G01X713728D02*
Y198070D01*
G01X713481D02*
Y199252D01*
G01X712478D02*
Y198070D01*
G01X712401D02*
Y199252D01*
G01X712204Y199291D02*
Y203582D01*
G01X711613Y200323D02*
Y207086D01*
G01Y198070D02*
Y199252D01*
G01X711595Y200543D02*
Y200136D01*
G01X711052Y198117D02*
Y199281D01*
G01X711042Y199347D02*
Y198223D01*
G01X711023Y199313D02*
Y198169D01*
G01X710354Y198070D02*
Y199252D01*
G01X709960D02*
Y198070D01*
G01X709172D02*
Y199252D01*
G01X705393Y198070D02*
Y199252D01*
G01X704606D02*
Y198070D01*
G01X704212Y199252D02*
Y198070D01*
G01X703543Y198169D02*
Y199313D01*
G01X703524Y199347D02*
Y198223D01*
G01X702971Y200136D02*
Y200543D01*
G01X702952Y200323D02*
Y207086D01*
G01Y198070D02*
Y199252D01*
G01X702361Y199291D02*
Y203582D01*
G01X702165Y199252D02*
Y198070D01*
G01X702087D02*
Y199252D01*
G01X703543Y199313D02*
X703524Y199347D01*
G01X701084Y199252D02*
Y198070D01*
G01X700837D02*
Y199252D01*
G01X700752D02*
Y198070D01*
G01X700432Y197637D02*
Y199685D01*
G01X700275Y199252D02*
Y198070D01*
G01X700039Y197637D02*
Y199685D01*
G01X700432Y199291D02*
X700039Y199685D01*
G01X700432Y198031D02*
X700039Y197637D01*
G01X704133Y208267D02*
X710432D01*
G01X712204Y203582D02*
X722440D01*
G01X711613Y201220D02*
X702952D01*
G01X722440Y200472D02*
X712204D01*
G01X722440Y199882D02*
X712204D01*
G01X700039Y199685D02*
X700432D01*
G01X712204D02*
X702361D01*
G01X700432Y197637D02*
X700039D01*
G01X710629Y219567D02*
G03X712598Y217598I1969J0D01*
G01X710629Y219567D02*
G03X712598Y217598I1969J0D01*
G01X710629Y219567D02*
G03X712598Y217598I1969J0D01*
G01X710629Y219567D02*
G03X712598Y217598I1969J0D01*
G01X710629Y274842D02*
Y219567D01*
G01Y274842D02*
Y219567D01*
G01X720472Y217598D02*
X712598D01*
G01X720472D02*
X712598D01*
G01X710629Y274842D02*
Y219567D01*
G01Y274842D02*
Y219567D01*
G01X720472Y217598D02*
X712598D01*
G01X720472D02*
X712598D01*
G01X710629Y219567D02*
Y274843D01*
G01Y219567D02*
G03X712598Y217598I1969J0D01*
G01X720472D02*
X712598D01*
G01Y276811D02*
G03X710629Y274842I0J-1969D01*
G01X712598Y276811D02*
G03X710629Y274842I0J-1969D01*
G01X712598Y276811D02*
G03X710629Y274842I0J-1969D01*
G01X712598Y276811D02*
G03X710629Y274842I0J-1969D01*
G01X720472Y276811D02*
X712598D01*
G01X720472D02*
X712598D01*
G01X720472D02*
X712598D01*
G01X720472D02*
X712598D01*
G01D02*
X720472D01*
G01X712598D02*
G03X710629Y274843I0J-1969D01*
G01X708848Y371299D02*
X722440D01*
G01X708848D02*
G03Y363425I1J-3937D01*
G01X722440Y355551D02*
G03X714566Y363425I-7874J0D01*
G01X722440Y355551D02*
G03X714566Y363425I-7874J0D01*
G01X722440Y355551D02*
G03X714566Y363425I-7874J0D01*
G01X722440Y355551D02*
G03X714566Y363425I-7874J0D01*
G01X722439Y355551D02*
G03X714566Y363425I-7874J0D01*
G01X722440Y416767D02*
X712597D01*
X714565Y415291D01*
G01X722440D02*
Y418243D01*
G01Y426610D02*
X722276Y427471D01*
X721784Y428455D01*
X720964Y429071D01*
X719815Y429317D01*
X718667Y429071D01*
X717683Y428332D01*
X717190Y427225D01*
Y425995D01*
X716862Y425257D01*
X716042Y424641D01*
X714894Y424395D01*
X713745Y424765D01*
X712925Y425626D01*
X712597Y426610D01*
X712925Y427594D01*
X713745Y428455D01*
X714894Y428825D01*
X716042Y428578D01*
X716862Y427963D01*
X717190Y427225D01*
Y425995D01*
X717683Y424888D01*
X718667Y424149D01*
X719815Y423903D01*
X720964Y424149D01*
X721784Y424765D01*
X722276Y425749D01*
X722440Y426610D01*
G01X720472Y433746D02*
X721620Y434484D01*
X722276Y435469D01*
X722440Y436576D01*
X722276Y437560D01*
X721456Y438545D01*
X720472Y439160D01*
X719487Y439283D01*
X718339Y439037D01*
X717519Y438175D01*
X717190Y437314D01*
Y436207D01*
G01Y437314D02*
X716698Y438052D01*
X715878Y438668D01*
X714894Y438914D01*
X713909Y438668D01*
X713089Y438052D01*
X712597Y436945D01*
X712761Y435838D01*
X713417Y434731D01*
G01X722768Y446296D02*
X722604Y446050D01*
X722276D01*
X722112Y446296D01*
X722276Y446542D01*
X722604D01*
X722768Y446296D01*
G01X720964Y453432D02*
X721784Y454170D01*
X722276Y455032D01*
X722440Y456139D01*
X722112Y457246D01*
X721456Y458107D01*
X720308Y458723D01*
X718995Y458846D01*
X717683Y458600D01*
X716862Y457984D01*
X716206Y457123D01*
X716042Y456262D01*
X716206Y455401D01*
X716862Y454294D01*
X712597Y454663D01*
Y457984D01*
G01Y465982D02*
X712925Y464998D01*
X713745Y464260D01*
X714729Y463767D01*
X716042Y463398D01*
X717519Y463275D01*
X718995Y463398D01*
X720308Y463767D01*
X721292Y464260D01*
X722112Y464998D01*
X722440Y465982D01*
X722112Y466966D01*
X721292Y467704D01*
X720308Y468197D01*
X718995Y468566D01*
X717519Y468689D01*
X716042Y468566D01*
X714729Y468197D01*
X713745Y467704D01*
X712925Y466966D01*
X712597Y465982D01*
G01X703429Y611246D02*
X703977Y611981D01*
X704447Y612401D01*
X705074Y612611D01*
X705622Y612401D01*
X706014Y611981D01*
X706327Y611351D01*
X706405Y610616D01*
X706327Y609986D01*
X706014Y609356D01*
X705544Y608831D01*
X704995Y608621D01*
X704369Y608831D01*
X703820Y609461D01*
X703507Y610406D01*
X703429Y611456D01*
X703585Y612821D01*
X703820Y613556D01*
X704212Y614291D01*
X704760Y614816D01*
X705309Y614921D01*
X705857Y614711D01*
X706249Y614186D01*
G01X722440Y-97480D02*
Y-15748D01*
G01Y-97480D02*
Y-15748D01*
G01Y-97480D02*
Y-15748D01*
G01Y-97480D02*
Y-15748D01*
G01Y-97480D02*
Y-15748D01*
G01X720472Y0D02*
G03X722440Y1968I0J1968D01*
G01X720472Y0D02*
G03X722440Y1968I0J1968D01*
G01X720472Y0D02*
G03X722440Y1968I0J1968D01*
G01X720472Y0D02*
G03X722440Y1968I0J1968D01*
G01D02*
Y21397D01*
G01Y1968D02*
Y21397D01*
G01Y1968D02*
Y21397D01*
G01Y1968D02*
Y21397D01*
G01Y1969D02*
Y21398D01*
G01X720472Y0D02*
G03X722440Y1969I0J1968D01*
G01Y21397D02*
G03X720472Y23366I-1968J1D01*
G01X722440Y21397D02*
G03X720472Y23366I-1968J1D01*
G01X722440Y21397D02*
G03X720472Y23366I-1968J1D01*
G01X722440Y21397D02*
G03X720472Y23366I-1968J1D01*
G01X720394Y27677D02*
X720711Y28858D01*
G01X722440Y21397D02*
Y33385D01*
G01Y13700D02*
Y21397D01*
G01X720394Y27677D02*
X720393Y35433D01*
G01X722440Y27859D02*
X720711Y28858D01*
G01X722440Y26496D02*
X720394Y27677D01*
G01X722439Y21398D02*
G03X720472Y23366I-1968J0D01*
G01X720427Y46052D02*
X720373Y46006D01*
G01X720460Y46110D02*
X720427Y46052D01*
G01X720472Y46176D02*
X720460Y46110D01*
G01X720078Y45866D02*
G03X720176Y45892I0J197D01*
G01X717429Y44527D02*
G03X717494Y44538I0J197D01*
G01X717665Y44586D02*
G03X717600Y44575I0J-197D01*
G01X718029Y44586D02*
G03X718167Y44643I-1J197D01*
G01X722440Y44015D02*
X721259Y42834D01*
G01X718167Y44643D02*
X718346Y44817D01*
G01X720176Y45892D02*
X720373Y46006D01*
G01X717600Y44575D02*
X717494Y44538D01*
G01X722440Y44015D02*
Y173267D01*
G01X721259Y42834D02*
Y174448D01*
G01X720472Y46176D02*
Y47327D01*
G01X720205Y45909D02*
Y47595D01*
G01X720100Y47636D02*
Y45867D01*
G01X718346Y47465D02*
Y44817D01*
G01X717799Y47696D02*
Y44586D01*
G01X717623Y44582D02*
Y47701D01*
G01X722440Y33385D02*
X720393Y35433D01*
G01X718029Y44586D02*
X717665D01*
G01X720461Y47392D02*
X720472Y47327D01*
G01X720428Y47451D02*
X720461Y47392D01*
G01X720373Y47498D02*
X720428Y47451D01*
G01X720461Y56841D02*
X720472Y56776D01*
G01X720428Y56900D02*
X720461Y56841D01*
G01X720373Y56946D02*
X720428Y56900D01*
G01X718459Y50602D02*
X718405Y50647D01*
G01X718492Y50543D02*
X718459Y50602D01*
G01X718503Y50477D02*
X718492Y50543D01*
G01X718459Y53751D02*
X718405Y53797D01*
G01X718492Y53693D02*
X718459Y53751D01*
G01X718503Y53626D02*
X718492Y53693D01*
G01X718459Y60050D02*
X718405Y60096D01*
G01X718492Y59992D02*
X718459Y60050D01*
G01X718503Y59926D02*
X718492Y59992D01*
G01X720427Y55500D02*
X720373Y55455D01*
G01X720460Y55559D02*
X720427Y55500D01*
G01X720472Y55625D02*
X720460Y55559D01*
G01X718492Y61859D02*
X718503Y61924D01*
G01X718459Y61800D02*
X718492Y61859D01*
G01X718405Y61754D02*
X718459Y61800D01*
G01X718492Y58710D02*
X718503Y58775D01*
G01X718459Y58651D02*
X718492Y58710D01*
G01X718405Y58604D02*
X718459Y58651D01*
G01X718492Y52411D02*
X718503Y52476D01*
G01X718459Y52352D02*
X718492Y52411D01*
G01X718405Y52305D02*
X718459Y52352D01*
G01X718492Y49261D02*
X718503Y49326D01*
G01X718459Y49202D02*
X718492Y49261D01*
G01X718405Y49156D02*
X718459Y49202D01*
G01X718109Y61614D02*
G03X718208Y61640I1J197D01*
G01X718109Y58464D02*
G03X718208Y58491I-1J197D01*
G01Y60209D02*
G03X718109Y60236I-99J-170D01*
G01X720176Y57060D02*
G03X720078Y57086I-98J-171D01*
G01X720135Y57641D02*
G03X719998Y57696I-136J-142D01*
G01X717524Y57756D02*
G03X717665Y57696I142J137D01*
G01Y59586D02*
G03X717524Y59527I-1J-197D01*
G01X719998Y59586D02*
G03X720135Y59643I-1J197D01*
G01Y62641D02*
G03X719998Y62696I-136J-142D01*
G01X717524Y62756D02*
G03X717665Y62696I142J137D01*
G01X720078Y55315D02*
G03X720176Y55341I0J197D01*
G01X718109Y52165D02*
G03X718208Y52191I1J197D01*
G01Y53910D02*
G03X718109Y53937I-99J-170D01*
G01Y49015D02*
G03X718208Y49042I-1J197D01*
G01Y50761D02*
G03X718109Y50787I-98J-171D01*
G01X720176Y47611D02*
G03X720078Y47637I-98J-171D01*
G01X718167Y47641D02*
G03X718029Y47696I-136J-142D01*
G01X717600Y47708D02*
G03X717665Y47696I68J185D01*
G01X717494Y47745D02*
G03X717429Y47756I-65J-186D01*
G01Y49527D02*
G03X717494Y49538I0J197D01*
G01X717665Y49586D02*
G03X717600Y49575I0J-197D01*
G01X718029Y49586D02*
G03X718167Y49643I-1J197D01*
G01Y52641D02*
G03X718029Y52696I-136J-142D01*
G01X717600Y52708D02*
G03X717665Y52696I68J185D01*
G01X717494Y52745D02*
G03X717429Y52756I-65J-186D01*
G01X717665Y54586D02*
G03X717524Y54527I-1J-197D01*
G01X719998Y54586D02*
G03X720135Y54643I-1J197D01*
G01X718167Y49643D02*
X718346Y49817D01*
G01X720135Y54643D02*
X720314Y54817D01*
G01X720135Y59643D02*
X720314Y59817D01*
G01X718208Y49042D02*
X718405Y49156D01*
G01X718208Y52191D02*
X718405Y52305D01*
G01X720176Y55341D02*
X720373Y55455D01*
G01X718208Y58491D02*
X718405Y58604D01*
G01X718208Y61640D02*
X718405Y61754D01*
G01X717600Y49575D02*
X717494Y49538D01*
G01X720472Y55625D02*
Y56776D01*
G01X720314Y57465D02*
Y54817D01*
G01Y62465D02*
Y59817D01*
G01X720205Y55358D02*
Y57044D01*
G01X720100Y57085D02*
Y55316D01*
G01X719767Y59586D02*
Y62696D01*
G01Y54586D02*
Y57696D01*
G01X719591Y59586D02*
Y62696D01*
G01Y54586D02*
Y57696D01*
G01X718503Y50477D02*
Y49326D01*
G01Y53626D02*
Y52476D01*
G01Y59926D02*
Y58775D01*
G01Y63075D02*
Y61924D01*
G01X718346Y52465D02*
Y49817D01*
G01X718236Y61657D02*
Y63343D01*
G01Y58507D02*
Y60193D01*
G01Y52208D02*
Y53894D01*
G01Y49058D02*
Y50745D01*
G01X718132Y50786D02*
Y49017D01*
G01Y53935D02*
Y52167D01*
G01Y60235D02*
Y58466D01*
G01Y63384D02*
Y61615D01*
G01X717799Y52696D02*
Y49586D01*
G01X717623Y49582D02*
Y52701D01*
G01X720314Y62465D02*
X720135Y62641D01*
G01X720314Y57465D02*
X720135Y57641D01*
G01X718346Y52465D02*
X718167Y52641D01*
G01X718346Y47465D02*
X718167Y47641D01*
G01X718208Y60209D02*
X718405Y60096D01*
G01X720373Y56946D02*
X720176Y57060D01*
G01X718208Y53910D02*
X718405Y53797D01*
G01X718208Y50761D02*
X718405Y50647D01*
G01X720373Y47498D02*
X720176Y47611D01*
G01X717494Y52745D02*
X717600Y52708D01*
G01X717494Y47745D02*
X717600Y47708D01*
G01X717665Y62696D02*
X719998D01*
G01Y59586D02*
X717665D01*
G01Y57696D02*
X719998D01*
G01Y54586D02*
X717665D01*
G01Y52696D02*
X718029D01*
G01Y49586D02*
X717665D01*
G01Y47696D02*
X718029D01*
G01X720461Y66290D02*
X720472Y66225D01*
G01X720428Y66348D02*
X720461Y66290D01*
G01X720373Y66395D02*
X720428Y66348D01*
G01X720461Y75739D02*
X720472Y75674D01*
G01X720428Y75797D02*
X720461Y75739D01*
G01X720373Y75844D02*
X720428Y75797D01*
G01X718459Y63200D02*
X718405Y63246D01*
G01X718492Y63141D02*
X718459Y63200D01*
G01X718503Y63075D02*
X718492Y63141D01*
G01X718459Y69499D02*
X718405Y69545D01*
G01X718492Y69441D02*
X718459Y69499D01*
G01X718503Y69374D02*
X718492Y69441D01*
G01X718459Y72649D02*
X718405Y72695D01*
G01X718492Y72590D02*
X718459Y72649D01*
G01X718503Y72524D02*
X718492Y72590D01*
G01X718459Y78948D02*
X718405Y78994D01*
G01X718492Y78889D02*
X718459Y78948D01*
G01X718503Y78823D02*
X718492Y78889D01*
G01X720427Y74398D02*
X720373Y74352D01*
G01X720460Y74457D02*
X720427Y74398D01*
G01X720472Y74523D02*
X720460Y74457D01*
G01X720427Y64949D02*
X720373Y64904D01*
G01X720460Y65008D02*
X720427Y64949D01*
G01X720472Y65074D02*
X720460Y65008D01*
G01X718492Y77608D02*
X718503Y77672D01*
G01X718459Y77548D02*
X718492Y77608D01*
G01X718405Y77502D02*
X718459Y77548D01*
G01X718492Y71308D02*
X718503Y71373D01*
G01X718459Y71249D02*
X718492Y71308D01*
G01X718405Y71203D02*
X718459Y71249D01*
G01X718492Y68159D02*
X718503Y68224D01*
G01X718459Y68100D02*
X718492Y68159D01*
G01X718405Y68053D02*
X718459Y68100D01*
G01X718208Y79107D02*
G03X718109Y79133I-98J-171D01*
G01Y77362D02*
G03X718208Y77388I1J197D01*
G01X720078Y74212D02*
G03X720176Y74239I-1J197D01*
G01Y75958D02*
G03X720078Y75984I-98J-171D01*
G01X718109Y71063D02*
G03X718208Y71089I1J197D01*
G01Y72808D02*
G03X718109Y72834I-98J-171D01*
G01Y67913D02*
G03X718208Y67939I1J197D01*
G01Y69658D02*
G03X718109Y69685I-99J-170D01*
G01X718167Y67641D02*
G03X718029Y67696I-136J-142D01*
G01X717600Y67708D02*
G03X717665Y67696I68J185D01*
G01X717494Y67745D02*
G03X717429Y67756I-65J-186D01*
G01X717665Y69586D02*
G03X717524Y69527I-1J-197D01*
G01X719998Y69586D02*
G03X720135Y69643I-1J197D01*
G01Y72641D02*
G03X719998Y72696I-136J-142D01*
G01X717524Y72756D02*
G03X717665Y72696I142J137D01*
G01X717429Y74527D02*
G03X717494Y74538I0J197D01*
G01X717665Y74586D02*
G03X717600Y74575I0J-197D01*
G01X718029Y74586D02*
G03X718167Y74643I-1J197D01*
G01Y77641D02*
G03X718029Y77696I-136J-142D01*
G01X717600Y77708D02*
G03X717665Y77696I68J185D01*
G01X717494Y77745D02*
G03X717429Y77756I-65J-186D01*
G01X720078Y64763D02*
G03X720176Y64790I-2J197D01*
G01Y66509D02*
G03X720078Y66535I-98J-171D01*
G01X718208Y63359D02*
G03X718109Y63385I-98J-171D01*
G01X717429Y64527D02*
G03X717494Y64538I0J197D01*
G01X717665Y64586D02*
G03X717600Y64575I0J-197D01*
G01X718029Y64586D02*
G03X718167Y64643I-1J197D01*
G01X720176Y64790D02*
X720373Y64904D01*
G01X718167Y64643D02*
X718346Y64817D01*
G01X720135Y69643D02*
X720314Y69817D01*
G01X718167Y74643D02*
X718346Y74817D01*
G01X718208Y67939D02*
X718405Y68053D01*
G01X718208Y71089D02*
X718405Y71203D01*
G01X720176Y74239D02*
X720373Y74352D01*
G01X718208Y77388D02*
X718405Y77502D01*
G01X720472Y74523D02*
Y75674D01*
G01Y65074D02*
Y66225D01*
G01X720314Y72465D02*
Y69817D01*
G01X720205Y74255D02*
Y75941D01*
G01Y64806D02*
Y66493D01*
G01X720100Y66534D02*
Y64765D01*
G01Y75983D02*
Y74214D01*
G01X719767Y69586D02*
Y72696D01*
G01X719591Y69586D02*
Y72696D01*
G01X718503Y69374D02*
Y68224D01*
G01Y72524D02*
Y71373D01*
G01Y78823D02*
Y77672D01*
G01X718346Y67465D02*
Y64817D01*
G01Y77465D02*
Y74817D01*
G01X718236Y77405D02*
Y79091D01*
G01Y71106D02*
Y72792D01*
G01Y67956D02*
Y69642D01*
G01X718132Y69683D02*
Y67915D01*
G01Y72833D02*
Y71064D01*
G01Y79132D02*
Y77363D01*
G01X717600Y64575D02*
X717494Y64538D01*
G01X717600Y74575D02*
X717494Y74538D01*
G01X717799Y67696D02*
Y64586D01*
G01Y77696D02*
Y74586D01*
G01X717623Y74582D02*
Y77701D01*
G01Y64582D02*
Y67701D01*
G01X718346Y77465D02*
X718167Y77641D01*
G01X720314Y72465D02*
X720135Y72641D01*
G01X718346Y67465D02*
X718167Y67641D01*
G01X718208Y79107D02*
X718405Y78994D01*
G01X720373Y75844D02*
X720176Y75958D01*
G01X718208Y72808D02*
X718405Y72695D01*
G01X718208Y69658D02*
X718405Y69545D01*
G01X720373Y66395D02*
X720176Y66509D01*
G01X718208Y63359D02*
X718405Y63246D01*
G01X717494Y77745D02*
X717600Y77708D01*
G01X717494Y67745D02*
X717600Y67708D01*
G01X717665Y77696D02*
X718029D01*
G01Y74586D02*
X717665D01*
G01Y72696D02*
X719998D01*
G01Y69586D02*
X717665D01*
G01Y67696D02*
X718029D01*
G01Y64586D02*
X717665D01*
G01X720461Y85187D02*
X720472Y85122D01*
G01X720428Y85246D02*
X720461Y85187D01*
G01X720373Y85293D02*
X720428Y85246D01*
G01X720461Y94636D02*
X720472Y94571D01*
G01X720428Y94695D02*
X720461Y94636D01*
G01X720373Y94742D02*
X720428Y94695D01*
G01X718459Y82098D02*
X718405Y82143D01*
G01X718492Y82039D02*
X718459Y82098D01*
G01X718503Y81973D02*
X718492Y82039D01*
G01X718459Y88397D02*
X718405Y88443D01*
G01X718492Y88338D02*
X718459Y88397D01*
G01X718503Y88272D02*
X718492Y88338D01*
G01X718459Y91546D02*
X718405Y91592D01*
G01X718492Y91488D02*
X718459Y91546D01*
G01X718503Y91422D02*
X718492Y91488D01*
G01X720427Y93296D02*
X720373Y93250D01*
G01X720460Y93354D02*
X720427Y93296D01*
G01X720472Y93420D02*
X720460Y93354D01*
G01X720427Y83847D02*
X720373Y83801D01*
G01X720460Y83906D02*
X720427Y83847D01*
G01X720472Y83972D02*
X720460Y83906D01*
G01X718492Y90206D02*
X718503Y90271D01*
G01X718459Y90147D02*
X718492Y90206D01*
G01X718405Y90100D02*
X718459Y90147D01*
G01X718492Y87056D02*
X718503Y87121D01*
G01X718459Y86997D02*
X718492Y87056D01*
G01X718405Y86951D02*
X718459Y86997D01*
G01X718492Y80757D02*
X718503Y80822D01*
G01X718459Y80698D02*
X718492Y80757D01*
G01X718405Y80652D02*
X718459Y80698D01*
G01X720078Y93110D02*
G03X720176Y93136I0J197D01*
G01Y94855D02*
G03X720078Y94882I-100J-170D01*
G01X719998Y89586D02*
G03X720135Y89643I-1J197D01*
G01Y92641D02*
G03X719998Y92696I-136J-142D01*
G01Y94586D02*
G03X720135Y94643I-1J197D01*
G01X718109Y89960D02*
G03X718208Y89987I-1J197D01*
G01Y91706D02*
G03X718109Y91732I-98J-171D01*
G01X717665Y89586D02*
G03X717524Y89527I-1J-197D01*
G01Y92756D02*
G03X717665Y92696I142J137D01*
G01Y94586D02*
G03X717524Y94527I-1J-197D01*
G01X718109Y86811D02*
G03X718208Y86837I1J197D01*
G01Y88556D02*
G03X718109Y88582I-98J-171D01*
G01X720078Y83661D02*
G03X720176Y83687I0J197D01*
G01Y85406D02*
G03X720078Y85433I-99J-170D01*
G01X718109Y80511D02*
G03X718208Y80538I-1J197D01*
G01Y82257D02*
G03X718109Y82283I-98J-171D01*
G01X717429Y79527D02*
G03X717494Y79538I0J197D01*
G01X717665Y79586D02*
G03X717600Y79575I0J-197D01*
G01X718029Y79586D02*
G03X718167Y79643I-1J197D01*
G01Y82641D02*
G03X718029Y82696I-136J-142D01*
G01X717600Y82708D02*
G03X717665Y82696I68J185D01*
G01X717494Y82745D02*
G03X717429Y82756I-65J-186D01*
G01X717665Y84586D02*
G03X717524Y84527I-1J-197D01*
G01X719998Y84586D02*
G03X720135Y84643I-1J197D01*
G01Y87641D02*
G03X719998Y87696I-136J-142D01*
G01X717524Y87756D02*
G03X717665Y87696I142J137D01*
G01X718167Y79643D02*
X718346Y79817D01*
G01X720135Y84643D02*
X720314Y84817D01*
G01X718208Y80538D02*
X718405Y80652D01*
G01X720176Y83687D02*
X720373Y83801D01*
G01X720135Y89643D02*
X720314Y89817D01*
G01X720135Y94643D02*
X720314Y94817D01*
G01X720472Y93420D02*
Y94571D01*
G01Y83972D02*
Y85122D01*
G01X720314Y87465D02*
Y84817D01*
G01Y92465D02*
Y89817D01*
G01Y97465D02*
Y94817D01*
G01X720205Y93153D02*
Y94839D01*
G01Y83704D02*
Y85390D01*
G01X720100Y85432D02*
Y83663D01*
G01Y94880D02*
Y93111D01*
G01X719767Y94586D02*
Y97696D01*
G01Y89586D02*
Y92696D01*
G01Y84586D02*
Y87696D01*
G01X719591Y94586D02*
Y97696D01*
G01Y89586D02*
Y92696D01*
G01Y84586D02*
Y87696D01*
G01X718503Y81973D02*
Y80822D01*
G01Y88272D02*
Y87121D01*
G01Y91422D02*
Y90271D01*
G01X718346Y82465D02*
Y79817D01*
G01X718236Y90003D02*
Y91689D01*
G01Y86854D02*
Y88540D01*
G01Y80554D02*
Y82241D01*
G01X718132Y82282D02*
Y80513D01*
G01Y88581D02*
Y86812D01*
G01Y91731D02*
Y89962D01*
G01X718208Y86837D02*
X718405Y86951D01*
G01X718208Y89987D02*
X718405Y90100D01*
G01X720176Y93136D02*
X720373Y93250D01*
G01X717799Y82696D02*
Y79586D01*
G01X717623Y79582D02*
Y82701D01*
G01X717600Y79575D02*
X717494Y79538D01*
G01X720314Y92465D02*
X720135Y92641D01*
G01X720314Y87465D02*
X720135Y87641D01*
G01X718346Y82465D02*
X718167Y82641D01*
G01X720373Y94742D02*
X720176Y94855D01*
G01X718208Y91706D02*
X718405Y91592D01*
G01X718208Y88556D02*
X718405Y88443D01*
G01X720373Y85293D02*
X720176Y85406D01*
G01X718208Y82257D02*
X718405Y82143D01*
G01X717494Y82745D02*
X717600Y82708D01*
G01X719998Y94586D02*
X717665D01*
G01Y92696D02*
X719998D01*
G01Y89586D02*
X717665D01*
G01Y87696D02*
X719998D01*
G01Y84586D02*
X717665D01*
G01Y82696D02*
X718029D01*
G01Y79586D02*
X717665D01*
G01X720461Y104085D02*
X720472Y104020D01*
G01X720428Y104144D02*
X720461Y104085D01*
G01X720373Y104191D02*
X720428Y104144D01*
G01X718492Y109104D02*
X718503Y109169D01*
G01X718459Y109045D02*
X718492Y109104D01*
G01X718405Y108998D02*
X718459Y109045D01*
G01X718492Y105954D02*
X718503Y106019D01*
G01X718459Y105895D02*
X718492Y105954D01*
G01X718405Y105848D02*
X718459Y105895D01*
G01Y97846D02*
X718405Y97891D01*
G01X718492Y97787D02*
X718459Y97846D01*
G01X718503Y97721D02*
X718492Y97787D01*
G01X718459Y100995D02*
X718405Y101041D01*
G01X718492Y100937D02*
X718459Y100995D01*
G01X718503Y100870D02*
X718492Y100937D01*
G01X718459Y107295D02*
X718405Y107340D01*
G01X718492Y107236D02*
X718459Y107295D01*
G01X718503Y107170D02*
X718492Y107236D01*
G01X718459Y110444D02*
X718405Y110490D01*
G01X718492Y110385D02*
X718459Y110444D01*
G01X718503Y110319D02*
X718492Y110385D01*
G01X720427Y112193D02*
X720373Y112148D01*
G01X720460Y112252D02*
X720427Y112193D01*
G01X720472Y112318D02*
X720460Y112252D01*
G01X720427Y102745D02*
X720373Y102699D01*
G01X720460Y102803D02*
X720427Y102745D01*
G01X720472Y102869D02*
X720460Y102803D01*
G01X718492Y99655D02*
X718503Y99720D01*
G01X718459Y99596D02*
X718492Y99655D01*
G01X718405Y99549D02*
X718459Y99596D01*
G01X718492Y96505D02*
X718503Y96570D01*
G01X718459Y96446D02*
X718492Y96505D01*
G01X718405Y96400D02*
X718459Y96446D01*
G01X720078Y112008D02*
G03X720176Y112034I0J197D01*
G01X720078Y102559D02*
G03X720176Y102585I0J197D01*
G01Y104304D02*
G03X720078Y104330I-98J-171D01*
G01X720135Y102641D02*
G03X719998Y102696I-136J-142D01*
G01Y104586D02*
G03X720135Y104643I-1J197D01*
G01Y107641D02*
G03X719998Y107696I-136J-142D01*
G01X720135Y97641D02*
G03X719998Y97696I-136J-142D01*
G01Y99586D02*
G03X720135Y99643I-1J197D01*
G01X718109Y108858D02*
G03X718208Y108884I1J197D01*
G01Y110603D02*
G03X718109Y110630I-100J-170D01*
G01Y105708D02*
G03X718208Y105735I-1J197D01*
G01Y107454D02*
G03X718109Y107480I-98J-171D01*
G01X718208Y101154D02*
G03X718109Y101181I-99J-170D01*
G01X717429Y109527D02*
G03X717494Y109538I0J197D01*
G01X717665Y109586D02*
G03X717600Y109575I0J-197D01*
G01X718029Y109586D02*
G03X718167Y109643I-1J197D01*
G01X717524Y102756D02*
G03X717665Y102696I142J137D01*
G01Y104586D02*
G03X717524Y104527I-1J-197D01*
G01Y107756D02*
G03X717665Y107696I142J137D01*
G01X718109Y99409D02*
G03X718208Y99435I1J197D01*
G01X718109Y96259D02*
G03X718208Y96286I-1J197D01*
G01Y98005D02*
G03X718109Y98031I-98J-171D01*
G01X717524Y97756D02*
G03X717665Y97696I142J137D01*
G01Y99586D02*
G03X717524Y99527I-1J-197D01*
G01X720135Y99643D02*
X720314Y99817D01*
G01X720135Y104643D02*
X720314Y104817D01*
G01X718167Y109643D02*
X718346Y109817D01*
G01X720472Y102869D02*
Y104020D01*
G01X720314Y102465D02*
Y99817D01*
G01Y107465D02*
Y104817D01*
G01X720205Y112050D02*
Y113737D01*
G01Y102602D02*
Y104288D01*
G01X720100Y104329D02*
Y102560D01*
G01Y113778D02*
Y112009D01*
G01X719767Y104586D02*
Y107696D01*
G01Y99586D02*
Y102696D01*
G01X719591Y104586D02*
Y107696D01*
G01Y99586D02*
Y102696D01*
G01X718503Y97721D02*
Y96570D01*
G01Y100870D02*
Y99720D01*
G01Y107170D02*
Y106019D01*
G01Y110319D02*
Y109169D01*
G01X718346Y112465D02*
Y109817D01*
G01X718236Y108901D02*
Y110587D01*
G01Y105751D02*
Y107437D01*
G01Y99452D02*
Y101138D01*
G01Y96302D02*
Y97989D01*
G01X718132Y98030D02*
Y96261D01*
G01Y101180D02*
Y99411D01*
G01Y107479D02*
Y105710D01*
G01Y110628D02*
Y108859D01*
G01X718208Y96286D02*
X718405Y96400D01*
G01X718208Y99435D02*
X718405Y99549D01*
G01X720176Y102585D02*
X720373Y102699D01*
G01X717799Y109586D02*
Y112696D01*
G01X717623Y112701D02*
Y109582D01*
G01X718208Y105735D02*
X718405Y105848D01*
G01X718208Y108884D02*
X718405Y108998D01*
G01X720176Y112034D02*
X720373Y112148D01*
G01X717600Y109575D02*
X717494Y109538D01*
G01X720314Y107465D02*
X720135Y107641D01*
G01X720314Y102465D02*
X720135Y102641D01*
G01X720314Y97465D02*
X720135Y97641D01*
G01X718208Y110603D02*
X718405Y110490D01*
G01X718208Y107454D02*
X718405Y107340D01*
G01X720373Y104191D02*
X720176Y104304D01*
G01X718208Y101154D02*
X718405Y101041D01*
G01X718208Y98005D02*
X718405Y97891D01*
G01X718029Y109586D02*
X717665D01*
G01Y107696D02*
X719998D01*
G01Y104586D02*
X717665D01*
G01Y102696D02*
X719998D01*
G01Y99586D02*
X717665D01*
G01Y97696D02*
X719998D01*
G01X720461Y113534D02*
X720472Y113469D01*
G01X720428Y113593D02*
X720461Y113534D01*
G01X720373Y113639D02*
X720428Y113593D01*
G01X720461Y119833D02*
X720472Y119768D01*
G01X720428Y119892D02*
X720461Y119833D01*
G01X720373Y119939D02*
X720428Y119892D01*
G01X718491Y126326D02*
X718503Y126393D01*
G01X718457Y126267D02*
X718491Y126326D01*
G01X718405Y126222D02*
X718457Y126267D01*
G01X718492Y124852D02*
X718503Y124917D01*
G01X718459Y124793D02*
X718492Y124852D01*
G01X718405Y124746D02*
X718459Y124793D01*
G01X718492Y121702D02*
X718503Y121767D01*
G01X718459Y121643D02*
X718492Y121702D01*
G01X718405Y121596D02*
X718459Y121643D01*
G01X718492Y115403D02*
X718503Y115468D01*
G01X718459Y115344D02*
X718492Y115403D01*
G01X718405Y115297D02*
X718459Y115344D01*
G01X718491Y123176D02*
X718503Y123243D01*
G01X718457Y123117D02*
X718491Y123176D01*
G01X718405Y123073D02*
X718457Y123117D01*
G01X720460Y120026D02*
X720472Y120094D01*
G01X720426Y119967D02*
X720460Y120026D01*
G01X720373Y119923D02*
X720426Y119967D01*
G01X718457Y124520D02*
X718405Y124565D01*
G01X718491Y124461D02*
X718457Y124520D01*
G01X718503Y124394D02*
X718491Y124461D01*
G01X718457Y127670D02*
X718405Y127714D01*
G01X718491Y127611D02*
X718457Y127670D01*
G01X718503Y127544D02*
X718491Y127611D01*
G01X720426Y121371D02*
X720373Y121415D01*
G01X720460Y121312D02*
X720426Y121371D01*
G01X720472Y121245D02*
X720460Y121312D01*
G01X718459Y116743D02*
X718405Y116789D01*
G01X718492Y116685D02*
X718459Y116743D01*
G01X718503Y116619D02*
X718492Y116685D01*
G01X718459Y123043D02*
X718405Y123088D01*
G01X718492Y122984D02*
X718459Y123043D01*
G01X718503Y122918D02*
X718492Y122984D01*
G01X718459Y126192D02*
X718405Y126238D01*
G01X718492Y126133D02*
X718459Y126192D01*
G01X718503Y126067D02*
X718492Y126133D01*
G01X720427Y127941D02*
X720373Y127896D01*
G01X720460Y128000D02*
X720427Y127941D01*
G01X720472Y128066D02*
X720460Y128000D01*
G01X720427Y118493D02*
X720373Y118447D01*
G01X720460Y118551D02*
X720427Y118493D01*
G01X720472Y118617D02*
X720460Y118551D01*
G01X720078Y127756D02*
G03X720176Y127782I0J197D01*
G01X720078Y118307D02*
G03X720176Y118333I0J197D01*
G01Y120052D02*
G03X720078Y120078I-98J-171D01*
G01X720176Y113753D02*
G03X720078Y113779I-98J-171D01*
G01Y119783D02*
G03X720176Y119809I0J197D01*
G01Y121528D02*
G03X720078Y121555I-99J-170D01*
G01X718109Y124606D02*
G03X718208Y124632I1J197D01*
G01Y126351D02*
G03X718109Y126378I-100J-170D01*
G01X718208Y123202D02*
G03X718109Y123228I-98J-171D01*
G01Y122933D02*
G03X718208Y122959I1J197D01*
G01Y124678D02*
G03X718109Y124704I-98J-171D01*
G01Y126082D02*
G03X718208Y126109I-1J197D01*
G01Y127828D02*
G03X718109Y127854I-98J-171D01*
G01Y121456D02*
G03X718208Y121483I-1J197D01*
G01X718109Y115157D02*
G03X718208Y115183I1J197D01*
G01Y116902D02*
G03X718109Y116929I-99J-170D01*
G01X718167Y112641D02*
G03X718029Y112696I-136J-142D01*
G01X717600Y112708D02*
G03X717665Y112696I68J185D01*
G01X717494Y112745D02*
G03X717429Y112756I-65J-186D01*
G01Y114527D02*
G03X717494Y114538I0J197D01*
G01X717665Y114586D02*
G03X717600Y114575I0J-197D01*
G01X718029Y114586D02*
G03X718167Y114643I-1J197D01*
G01Y117641D02*
G03X718029Y117696I-136J-142D01*
G01X717600Y117708D02*
G03X717665Y117696I68J185D01*
G01X717494Y117745D02*
G03X717429Y117756I-65J-186D01*
G01X720865Y138189D02*
Y119094D01*
G01X720472Y128066D02*
Y129217D01*
G01Y118617D02*
Y119768D01*
G01Y112318D02*
Y113469D01*
G01Y121245D02*
Y120094D01*
G01X720205Y127798D02*
Y129485D01*
G01Y118350D02*
Y120036D01*
G01D02*
Y121512D01*
G01X720100Y120077D02*
Y121554D01*
G01Y120077D02*
Y118308D01*
G01Y129526D02*
Y127757D01*
G01X718503Y116619D02*
Y115468D01*
G01Y122918D02*
Y121767D01*
G01Y126067D02*
Y124917D01*
G01Y124394D02*
Y123243D01*
G01Y127544D02*
Y126393D01*
G01X718346Y117465D02*
Y114817D01*
G01X718236Y124649D02*
Y126335D01*
G01Y121499D02*
Y123185D01*
G01Y115200D02*
Y116886D01*
G01Y124649D02*
Y123185D01*
G01Y127811D02*
Y126335D01*
G01X718132Y126376D02*
Y127853D01*
G01Y123227D02*
Y124608D01*
G01Y116928D02*
Y115159D01*
G01Y123227D02*
Y121458D01*
G01Y126376D02*
Y124608D01*
G01X718167Y114643D02*
X718346Y114817D01*
G01X720865Y119094D02*
X722440Y120669D01*
G01X717799Y114586D02*
Y117696D01*
G01X717623Y117701D02*
Y114582D01*
G01X718208Y115183D02*
X718405Y115297D01*
G01X720176Y118333D02*
X720373Y118447D01*
G01X720176Y119809D02*
X720373Y119923D01*
G01X718208Y121483D02*
X718405Y121596D01*
G01X718208Y122959D02*
X718405Y123073D01*
G01X718208Y124632D02*
X718405Y124746D01*
G01X718208Y126109D02*
X718405Y126222D01*
G01X720176Y127782D02*
X720373Y127896D01*
G01X717600Y114575D02*
X717494Y114538D01*
G01X718346Y117465D02*
X718167Y117641D01*
G01X718346Y112465D02*
X718167Y112641D01*
G01X718405Y127714D02*
X718208Y127828D01*
G01Y126351D02*
X718405Y126238D01*
G01Y124565D02*
X718208Y124678D01*
G01Y123202D02*
X718405Y123088D01*
G01X720373Y121415D02*
X720176Y121528D01*
G01X720373Y119939D02*
X720176Y120052D01*
G01X718208Y116902D02*
X718405Y116789D01*
G01X720373Y113639D02*
X720176Y113753D01*
G01X717494Y117745D02*
X717600Y117708D01*
G01X717494Y112745D02*
X717600Y112708D01*
G01X717665Y117696D02*
X718029D01*
G01Y114586D02*
X717665D01*
G01Y112696D02*
X718029D01*
G01X720461Y129282D02*
X720472Y129217D01*
G01X720428Y129341D02*
X720461Y129282D01*
G01X720373Y129387D02*
X720428Y129341D01*
G01X720461Y138731D02*
X720472Y138666D01*
G01X720428Y138789D02*
X720461Y138731D01*
G01X720373Y138836D02*
X720428Y138789D01*
G01X720461Y145030D02*
X720472Y144965D01*
G01X720428Y145089D02*
X720461Y145030D01*
G01X720373Y145135D02*
X720428Y145089D01*
G01X718492Y140600D02*
X718503Y140665D01*
G01X718459Y140541D02*
X718492Y140600D01*
G01X718405Y140494D02*
X718459Y140541D01*
G01X718492Y134300D02*
X718503Y134365D01*
G01X718459Y134241D02*
X718492Y134300D01*
G01X718405Y134195D02*
X718459Y134241D01*
G01X718492Y131151D02*
X718503Y131216D01*
G01X718459Y131092D02*
X718492Y131151D01*
G01X718405Y131045D02*
X718459Y131092D01*
G01X718491Y135774D02*
X718503Y135842D01*
G01X718457Y135715D02*
X718491Y135774D01*
G01X718405Y135671D02*
X718457Y135715D01*
G01X718491Y132625D02*
X718503Y132692D01*
G01X718457Y132566D02*
X718491Y132625D01*
G01X718405Y132522D02*
X718457Y132566D01*
G01X720460Y129475D02*
X720472Y129543D01*
G01X720426Y129416D02*
X720460Y129475D01*
G01X720373Y129372D02*
X720426Y129416D01*
G01X718457Y133969D02*
X718405Y134013D01*
G01X718491Y133910D02*
X718457Y133969D01*
G01X718503Y133843D02*
X718491Y133910D01*
G01X718457Y137119D02*
X718405Y137163D01*
G01X718491Y137060D02*
X718457Y137119D01*
G01X718503Y136993D02*
X718491Y137060D01*
G01X720426Y130820D02*
X720373Y130864D01*
G01X720460Y130761D02*
X720426Y130820D01*
G01X720472Y130693D02*
X720460Y130761D01*
G01X718459Y132491D02*
X718405Y132537D01*
G01X718492Y132433D02*
X718459Y132491D01*
G01X718503Y132367D02*
X718492Y132433D01*
G01X718459Y135641D02*
X718405Y135687D01*
G01X718492Y135582D02*
X718459Y135641D01*
G01X718503Y135516D02*
X718492Y135582D01*
G01X718459Y141940D02*
X718405Y141986D01*
G01X718492Y141882D02*
X718459Y141940D01*
G01X718503Y141815D02*
X718492Y141882D01*
G01X720427Y143689D02*
X720373Y143644D01*
G01X720460Y143748D02*
X720427Y143689D01*
G01X720472Y143814D02*
X720460Y143748D01*
G01X720427Y137390D02*
X720373Y137345D01*
G01X720460Y137449D02*
X720427Y137390D01*
G01X720472Y137515D02*
X720460Y137449D01*
G01X720176Y145249D02*
G03X720078Y145275I-98J-171D01*
G01Y143504D02*
G03X720176Y143530I0J197D01*
G01Y138950D02*
G03X720078Y138976I-98J-171D01*
G01Y137204D02*
G03X720176Y137231I-2J197D01*
G01X719998Y139586D02*
G03X720135Y139643I-1J197D01*
G01Y142641D02*
G03X719998Y142696I-136J-142D01*
G01X717524Y142756D02*
G03X717665Y142696I142J137D01*
G01X717429Y144527D02*
G03X717494Y144538I0J197D01*
G01X717665Y144586D02*
G03X717600Y144575I0J-197D01*
G01X718029Y144586D02*
G03X718167Y144643I-1J197D01*
G01X718109Y134055D02*
G03X718208Y134081I1J197D01*
G01Y135800D02*
G03X718109Y135826I-98J-171D01*
G01X718208Y142099D02*
G03X718109Y142126I-100J-170D01*
G01Y140354D02*
G03X718208Y140380I1J197D01*
G01X718109Y132382D02*
G03X718208Y132408I1J197D01*
G01Y134127D02*
G03X718109Y134153I-98J-171D01*
G01Y135531D02*
G03X718208Y135558I0J197D01*
G01Y137276D02*
G03X718109Y137303I-99J-170D01*
G01X717665Y139586D02*
G03X717524Y139527I-1J-197D01*
G01X720176Y129501D02*
G03X720078Y129527I-98J-171D01*
G01Y129232D02*
G03X720176Y129258I0J197D01*
G01Y130977D02*
G03X720078Y131004I-99J-170D01*
G01X718109Y130905D02*
G03X718208Y130932I0J197D01*
G01Y132650D02*
G03X718109Y132677I-99J-170D01*
G01X720472Y143814D02*
Y144965D01*
G01Y137515D02*
Y138666D01*
G01Y130693D02*
Y129543D01*
G01X720314Y142465D02*
Y139817D01*
G01X720205Y143546D02*
Y145233D01*
G01Y137247D02*
Y138933D01*
G01Y129485D02*
Y130961D01*
G01X720100Y131002D02*
Y129526D01*
G01Y138975D02*
Y137206D01*
G01Y145274D02*
Y143505D01*
G01X719767Y142696D02*
Y139586D01*
G01X719591D02*
Y142696D01*
G01X718503Y132367D02*
Y131216D01*
G01Y135516D02*
Y134365D01*
G01Y133843D02*
Y132692D01*
G01Y136993D02*
Y135842D01*
G01Y141815D02*
Y140665D01*
G01X718346Y147465D02*
Y144817D01*
G01X718236Y140397D02*
Y142083D01*
G01Y134098D02*
Y135784D01*
G01Y130948D02*
Y132634D01*
G01Y134098D02*
Y132634D01*
G01Y137260D02*
Y135784D01*
G01X718132Y135825D02*
Y137302D01*
G01Y132676D02*
Y134056D01*
G01Y132676D02*
Y130907D01*
G01Y135825D02*
Y134056D01*
G01Y142124D02*
Y140356D01*
G01X717799Y144586D02*
Y147696D01*
G01X717623Y147701D02*
Y144582D01*
G01X720135Y139643D02*
X720314Y139817D01*
G01X718167Y144643D02*
X718346Y144817D01*
G01X720176Y129258D02*
X720373Y129372D01*
G01X718208Y130932D02*
X718405Y131045D01*
G01X718208Y132408D02*
X718405Y132522D01*
G01X718208Y134081D02*
X718405Y134195D01*
G01X718208Y135558D02*
X718405Y135671D01*
G01X720176Y137231D02*
X720373Y137345D01*
G01X718208Y140380D02*
X718405Y140494D01*
G01X720176Y143530D02*
X720373Y143644D01*
G01X722440Y136614D02*
X720865Y138189D01*
G01X720314Y142465D02*
X720135Y142641D01*
G01X717600Y144575D02*
X717494Y144538D01*
G01X720373Y145135D02*
X720176Y145249D01*
G01X718208Y142099D02*
X718405Y141986D01*
G01X720373Y138836D02*
X720176Y138950D01*
G01X718405Y137163D02*
X718208Y137276D01*
G01Y135800D02*
X718405Y135687D01*
G01Y134013D02*
X718208Y134127D01*
G01Y132650D02*
X718405Y132537D01*
G01X720373Y130864D02*
X720176Y130977D01*
G01X720373Y129387D02*
X720176Y129501D01*
G01X718029Y144586D02*
X717665D01*
G01Y142696D02*
X719998D01*
G01Y139586D02*
X717665D01*
G01X720461Y154479D02*
X720472Y154414D01*
G01X720428Y154537D02*
X720461Y154479D01*
G01X720373Y154584D02*
X720428Y154537D01*
G01X718492Y159497D02*
X718503Y159562D01*
G01X718459Y159438D02*
X718492Y159497D01*
G01X718405Y159392D02*
X718459Y159438D01*
G01X718492Y156348D02*
X718503Y156413D01*
G01X718459Y156289D02*
X718492Y156348D01*
G01X718405Y156242D02*
X718459Y156289D01*
G01X718492Y150048D02*
X718503Y150113D01*
G01X718459Y149989D02*
X718492Y150048D01*
G01X718405Y149943D02*
X718459Y149989D01*
G01X718492Y146899D02*
X718503Y146964D01*
G01X718459Y146840D02*
X718492Y146899D01*
G01X718405Y146793D02*
X718459Y146840D01*
G01Y148239D02*
X718405Y148285D01*
G01X718492Y148181D02*
X718459Y148239D01*
G01X718503Y148115D02*
X718492Y148181D01*
G01X718459Y151389D02*
X718405Y151435D01*
G01X718492Y151330D02*
X718459Y151389D01*
G01X718503Y151264D02*
X718492Y151330D01*
G01X718459Y157688D02*
X718405Y157734D01*
G01X718492Y157630D02*
X718459Y157688D01*
G01X718503Y157563D02*
X718492Y157630D01*
G01X718459Y160838D02*
X718405Y160883D01*
G01X718492Y160779D02*
X718459Y160838D01*
G01X718503Y160713D02*
X718492Y160779D01*
G01X720427Y153138D02*
X720373Y153093D01*
G01X720460Y153197D02*
X720427Y153138D01*
G01X720472Y153263D02*
X720460Y153197D01*
G01X720176Y154698D02*
G03X720078Y154724I-98J-171D01*
G01Y152952D02*
G03X720176Y152979I-2J197D01*
G01X719998Y154586D02*
G03X720135Y154643I-1J197D01*
G01Y157641D02*
G03X719998Y157696I-136J-142D01*
G01X718208Y157847D02*
G03X718109Y157874I-99J-170D01*
G01Y156102D02*
G03X718208Y156128I1J197D01*
G01Y160997D02*
G03X718109Y161023I-98J-171D01*
G01Y159252D02*
G03X718208Y159278I1J197D01*
G01X717600Y152708D02*
G03X717665Y152696I68J185D01*
G01Y154586D02*
G03X717524Y154527I-1J-197D01*
G01Y157756D02*
G03X717665Y157696I142J137D01*
G01X717429Y159527D02*
G03X717494Y159538I0J197D01*
G01X717665Y159586D02*
G03X717600Y159575I0J-197D01*
G01X718029Y159586D02*
G03X718167Y159643I-1J197D01*
G01X718208Y148398D02*
G03X718109Y148425I-99J-170D01*
G01Y146653D02*
G03X718208Y146680I0J197D01*
G01Y151548D02*
G03X718109Y151574I-98J-171D01*
G01Y149803D02*
G03X718208Y149829I1J197D01*
G01X718167Y147641D02*
G03X718029Y147696I-136J-142D01*
G01X717600Y147708D02*
G03X717665Y147696I68J185D01*
G01X717494Y147745D02*
G03X717429Y147756I-65J-186D01*
G01Y149527D02*
G03X717494Y149538I0J197D01*
G01X717665Y149586D02*
G03X717600Y149575I0J-197D01*
G01X718029Y149586D02*
G03X718167Y149643I-1J197D01*
G01Y152641D02*
G03X718029Y152696I-136J-142D01*
G01X717494Y152745D02*
G03X717429Y152756I-65J-186D01*
G01X720472Y153263D02*
Y154414D01*
G01X720314Y157465D02*
Y154817D01*
G01X720205Y152995D02*
Y154682D01*
G01X720100Y154723D02*
Y152954D01*
G01X719767Y157696D02*
Y154586D01*
G01X719591D02*
Y157696D01*
G01X718503Y148115D02*
Y146964D01*
G01Y151264D02*
Y150113D01*
G01Y157563D02*
Y156413D01*
G01Y160713D02*
Y159562D01*
G01X718346Y152465D02*
Y149817D01*
G01Y162465D02*
Y159817D01*
G01X718236Y159295D02*
Y160981D01*
G01Y156145D02*
Y157831D01*
G01Y149846D02*
Y151532D01*
G01Y146696D02*
Y148382D01*
G01X718132Y148424D02*
Y146655D01*
G01Y151573D02*
Y149804D01*
G01Y157872D02*
Y156104D01*
G01Y161022D02*
Y159253D01*
G01X717799Y159586D02*
Y162696D01*
G01Y149586D02*
Y152696D01*
G01X717623Y152701D02*
Y149582D01*
G01Y162701D02*
Y159582D01*
G01X718167Y149643D02*
X718346Y149817D01*
G01X720135Y154643D02*
X720314Y154817D01*
G01X718167Y159643D02*
X718346Y159817D01*
G01X720314Y157465D02*
X720135Y157641D01*
G01X718208Y146680D02*
X718405Y146793D01*
G01X718208Y149829D02*
X718405Y149943D01*
G01X720176Y152979D02*
X720373Y153093D01*
G01X718208Y156128D02*
X718405Y156242D01*
G01X718208Y159278D02*
X718405Y159392D01*
G01X718346Y152465D02*
X718167Y152641D01*
G01X718346Y147465D02*
X718167Y147641D01*
G01X717600Y149575D02*
X717494Y149538D01*
G01X717600Y159575D02*
X717494Y159538D01*
G01X718208Y160997D02*
X718405Y160883D01*
G01X718208Y157847D02*
X718405Y157734D01*
G01X720373Y154584D02*
X720176Y154698D01*
G01X718208Y151548D02*
X718405Y151435D01*
G01X718208Y148398D02*
X718405Y148285D01*
G01X717494Y152745D02*
X717600Y152708D01*
G01X717494Y147745D02*
X717600Y147708D01*
G01X718029Y159586D02*
X717665D01*
G01Y157696D02*
X719998D01*
G01Y154586D02*
X717665D01*
G01Y152696D02*
X718029D01*
G01Y149586D02*
X717665D01*
G01Y147696D02*
X718029D01*
G01X720461Y163928D02*
X720472Y163863D01*
G01X720428Y163986D02*
X720461Y163928D01*
G01X720373Y164033D02*
X720428Y163986D01*
G01X718492Y168946D02*
X718503Y169011D01*
G01X718459Y168887D02*
X718492Y168946D01*
G01X718405Y168841D02*
X718459Y168887D01*
G01X718492Y165796D02*
X718503Y165861D01*
G01X718459Y165737D02*
X718492Y165796D01*
G01X718405Y165691D02*
X718459Y165737D01*
G01Y167137D02*
X718405Y167183D01*
G01X718492Y167078D02*
X718459Y167137D01*
G01X718503Y167012D02*
X718492Y167078D01*
G01X718459Y170287D02*
X718405Y170332D01*
G01X718492Y170228D02*
X718459Y170287D01*
G01X718503Y170162D02*
X718492Y170228D01*
G01X720427Y162587D02*
X720373Y162541D01*
G01X720460Y162646D02*
X720427Y162587D01*
G01X720472Y162712D02*
X720460Y162646D01*
G01X720176Y164146D02*
G03X720078Y164173I-99J-170D01*
G01X719998Y169586D02*
G03X720135Y169643I-1J197D01*
G01Y172641D02*
G03X719998Y172696I-136J-142D01*
G01X720078Y162401D02*
G03X720176Y162428I-1J197D01*
G01X718208Y167296D02*
G03X718109Y167322I-98J-171D01*
G01Y165551D02*
G03X718208Y165577I1J197D01*
G01Y170446D02*
G03X718109Y170472I-98J-171D01*
G01Y168700D02*
G03X718208Y168727I-1J197D01*
G01X717600Y162708D02*
G03X717665Y162696I68J185D01*
G01X717429Y164527D02*
G03X717494Y164538I0J197D01*
G01X717665Y164586D02*
G03X717600Y164575I0J-197D01*
G01X718029Y164586D02*
G03X718167Y164643I-1J197D01*
G01Y167641D02*
G03X718029Y167696I-136J-142D01*
G01X717600Y167708D02*
G03X717665Y167696I68J185D01*
G01X717494Y167745D02*
G03X717429Y167756I-65J-186D01*
G01X717665Y169586D02*
G03X717524Y169527I-1J-197D01*
G01Y172756D02*
G03X717665Y172696I142J137D01*
G01X718167Y162641D02*
G03X718029Y162696I-136J-142D01*
G01X717494Y162745D02*
G03X717429Y162756I-65J-186D01*
G01X720472Y162712D02*
Y163863D01*
G01X720314Y172465D02*
Y169817D01*
G01X720205Y162444D02*
Y164130D01*
G01X720100Y164172D02*
Y162403D01*
G01X719767Y172696D02*
Y169586D01*
G01X719591D02*
Y172696D01*
G01X718503Y167012D02*
Y165861D01*
G01Y170162D02*
Y169011D01*
G01X718346Y167465D02*
Y164817D01*
G01X718236Y168743D02*
Y170430D01*
G01Y165594D02*
Y167280D01*
G01X718132Y167321D02*
Y165552D01*
G01Y170471D02*
Y168702D01*
G01X717799Y164586D02*
Y167696D01*
G01X717623Y167701D02*
Y164582D01*
G01X718167Y164643D02*
X718346Y164817D01*
G01X720135Y169643D02*
X720314Y169817D01*
G01X721259Y174448D02*
X722440Y173267D01*
G01X720314Y172465D02*
X720135Y172641D01*
G01X718346Y167465D02*
X718167Y167641D01*
G01X718346Y162465D02*
X718167Y162641D01*
G01X720176Y162428D02*
X720373Y162541D01*
G01X718208Y165577D02*
X718405Y165691D01*
G01X718208Y168727D02*
X718405Y168841D01*
G01X718208Y170446D02*
X718405Y170332D01*
G01X718208Y167296D02*
X718405Y167183D01*
G01X720373Y164033D02*
X720176Y164146D01*
G01X717600Y164575D02*
X717494Y164538D01*
G01Y167745D02*
X717600Y167708D01*
G01X717494Y162745D02*
X717600Y162708D01*
G01X717665Y172696D02*
X719998D01*
G01Y169586D02*
X717665D01*
G01Y167696D02*
X718029D01*
G01Y164586D02*
X717665D01*
G01Y162696D02*
X718029D01*
G01X720472Y193956D02*
G03X722440Y195925I-1J1969D01*
G01X720472Y193956D02*
G03X722440Y195925I-1J1969D01*
G01X720472Y193956D02*
G03X722440Y195925I-1J1969D01*
G01X720472Y193956D02*
G03X722440Y195925I-1J1969D01*
G01D02*
Y183897D01*
G01X720394Y189606D02*
Y181852D01*
G01X720711Y188425D02*
X720394Y189606D01*
G01X720393Y181850D02*
X722440Y183897D01*
G01X720711Y188425D02*
X722440Y189423D01*
G01Y190787D02*
X720394Y189606D01*
G01X720472Y193957D02*
G03X722439Y195925I-1J1968D01*
G01X722440Y215630D02*
Y195925D01*
G01Y215630D02*
Y195925D01*
G01Y203582D02*
Y195925D01*
G01Y215630D02*
Y195925D01*
G01Y215630D02*
Y195925D01*
G01D02*
Y215630D01*
G01D02*
G03X720472Y217598I-1968J0D01*
G01X722440Y215630D02*
G03X720472Y217598I-1968J0D01*
G01X722440Y215630D02*
G03X720472Y217598I-1968J0D01*
G01X722440Y215630D02*
G03X720472Y217598I-1968J0D01*
G01X722439Y215630D02*
G03X720472Y217598I-1968J0D01*
G01Y276811D02*
G03X722440Y278779I0J1968D01*
G01X720472Y276811D02*
G03X722440Y278779I0J1968D01*
G01X720472Y276811D02*
G03X722440Y278779I0J1968D01*
G01X720472Y276811D02*
G03X722440Y278779I0J1968D01*
G01X720472Y276811D02*
G03X722440Y278780I0J1968D01*
G01Y355551D02*
Y278779D01*
G01Y355551D02*
Y278779D01*
G01Y355551D02*
Y278779D01*
G01Y355551D02*
Y278779D01*
G01Y278780D02*
Y355551D01*
G01Y355797D02*
Y423796D01*
G01X735363Y-725192D02*
Y-469286D01*
G01Y-725192D02*
X1680245D01*
G01Y-664928D02*
X735363D01*
G01Y-619802D02*
X1266589D01*
G01X750082Y-586955D02*
X756332Y-606955D01*
X762582Y-586955D01*
G01X772582Y-597955D02*
X780582D01*
X779832Y-595622D01*
X778582Y-594289D01*
X776832Y-593622D01*
X775082Y-593955D01*
X773582Y-594955D01*
X772582Y-597289D01*
X772082Y-599289D01*
Y-601288D01*
X772582Y-603289D01*
X773832Y-605289D01*
X775332Y-606622D01*
X777082Y-606955D01*
X778832Y-606288D01*
X780582Y-604289D01*
G01X792832Y-606955D02*
Y-593622D01*
G01Y-596288D02*
X794082Y-594955D01*
X795332Y-593955D01*
X797082Y-593622D01*
X798332Y-593955D01*
X799832Y-594955D01*
G01X812582Y-604622D02*
X813832Y-605955D01*
X815582Y-606955D01*
X817082D01*
X818582Y-606288D01*
X819582Y-605289D01*
X820082Y-603956D01*
X819832Y-601955D01*
X818832Y-600955D01*
X814332Y-598955D01*
X813332Y-596621D01*
X813832Y-594955D01*
X814832Y-593955D01*
X816332Y-593622D01*
X817832Y-593955D01*
X819332Y-594955D01*
G01X836332Y-593622D02*
Y-606955D01*
G01Y-588289D02*
X835832Y-587955D01*
Y-587288D01*
X836332Y-586955D01*
X836832Y-587288D01*
Y-587955D01*
X836332Y-588289D01*
G01X856332Y-606955D02*
X854832Y-606622D01*
X853332Y-605289D01*
X852332Y-602955D01*
X851832Y-600289D01*
X852332Y-597622D01*
X853332Y-595288D01*
X854832Y-593955D01*
X856332Y-593622D01*
X857832Y-593955D01*
X859332Y-595288D01*
X860332Y-597622D01*
X860582Y-600289D01*
X860332Y-602955D01*
X859332Y-605289D01*
X857832Y-606622D01*
X856332Y-606955D01*
G01X872082D02*
Y-593622D01*
G01Y-596955D02*
X873082Y-595288D01*
X874582Y-593955D01*
X876582Y-593622D01*
X878332Y-593955D01*
X879832Y-595288D01*
X880582Y-597622D01*
Y-606955D01*
G01X735363Y-574676D02*
X1680245D01*
G01X735363Y-529550D02*
X1680245D01*
G01X735363Y-469286D02*
X1680245D01*
G01X764534Y-637530D02*
X763034Y-636530D01*
X761284Y-635863D01*
X759284D01*
X757034Y-636863D01*
X755284Y-638530D01*
X754034Y-640530D01*
X753034Y-643863D01*
X752784Y-646863D01*
X753284Y-649863D01*
X754034Y-651863D01*
X755534Y-653863D01*
X757284Y-655196D01*
X759034Y-655863D01*
X760784D01*
X762534Y-655196D01*
X764034Y-654197D01*
X765284Y-652864D01*
G01X775534Y-655863D02*
Y-642530D01*
G01Y-645196D02*
X776784Y-643863D01*
X778034Y-642863D01*
X779784Y-642530D01*
X781034Y-642863D01*
X782534Y-643863D01*
G01X795284Y-646863D02*
X803284D01*
X802534Y-644530D01*
X801284Y-643197D01*
X799534Y-642530D01*
X797784Y-642863D01*
X796284Y-643863D01*
X795284Y-646197D01*
X794784Y-648197D01*
Y-650196D01*
X795284Y-652197D01*
X796534Y-654197D01*
X798034Y-655530D01*
X799784Y-655863D01*
X801534Y-655196D01*
X803284Y-653197D01*
G01X823534Y-655863D02*
Y-642530D01*
G01Y-644863D02*
X822534Y-643530D01*
X821034Y-642863D01*
X819284Y-642530D01*
X817534Y-643197D01*
X816034Y-644530D01*
X815034Y-646530D01*
X814534Y-649197D01*
X815034Y-651863D01*
X816034Y-653863D01*
X817534Y-655196D01*
X819284Y-655863D01*
X821034Y-655530D01*
X822534Y-654530D01*
X823534Y-653197D01*
G01X839034Y-635863D02*
Y-655863D01*
G01X835534Y-642530D02*
X842534D01*
G01X855284Y-646863D02*
X863284D01*
X862534Y-644530D01*
X861284Y-643197D01*
X859534Y-642530D01*
X857784Y-642863D01*
X856284Y-643863D01*
X855284Y-646197D01*
X854784Y-648197D01*
Y-650196D01*
X855284Y-652197D01*
X856534Y-654197D01*
X858034Y-655530D01*
X859784Y-655863D01*
X861534Y-655196D01*
X863284Y-653197D01*
G01X883534Y-635863D02*
Y-655863D01*
G01Y-652864D02*
X882534Y-654530D01*
X881034Y-655530D01*
X879284Y-655863D01*
X877284Y-655196D01*
X875784Y-653530D01*
X874784Y-651530D01*
X874534Y-649197D01*
X874784Y-646863D01*
X875784Y-644863D01*
X877284Y-643197D01*
X879284Y-642530D01*
X881034Y-642863D01*
X882284Y-643530D01*
X883534Y-644863D01*
G01X754034Y-562942D02*
Y-542942D01*
X760034D01*
X762034Y-543942D01*
X763534Y-546275D01*
X764034Y-548942D01*
X763534Y-551609D01*
X762284Y-553609D01*
X760034Y-554609D01*
X754034D01*
G01X784534Y-544609D02*
X783034Y-543609D01*
X781284Y-542942D01*
X779284D01*
X777034Y-543942D01*
X775284Y-545609D01*
X774034Y-547609D01*
X773034Y-550942D01*
X772784Y-553942D01*
X773284Y-556942D01*
X774034Y-558942D01*
X775534Y-560942D01*
X777284Y-562275D01*
X779034Y-562942D01*
X780784D01*
X782534Y-562275D01*
X784034Y-561276D01*
X785284Y-559943D01*
G01X801034Y-552275D02*
X802034Y-551275D01*
X802784Y-549609D01*
X803284Y-547275D01*
X802784Y-545275D01*
X801784Y-543942D01*
X800034Y-542942D01*
X793284D01*
Y-562942D01*
X801534D01*
X803284Y-561609D01*
X804284Y-559609D01*
X804784Y-557275D01*
X804284Y-554942D01*
X802784Y-552942D01*
X801034Y-552275D01*
X793284D01*
G01X833284Y-562942D02*
Y-542942D01*
X844784Y-562942D01*
Y-542942D01*
G01X859034Y-562942D02*
X857534Y-562609D01*
X856034Y-561276D01*
X855034Y-558942D01*
X854534Y-556276D01*
X855034Y-553609D01*
X856034Y-551275D01*
X857534Y-549942D01*
X859034Y-549609D01*
X860534Y-549942D01*
X862034Y-551275D01*
X863034Y-553609D01*
X863284Y-556276D01*
X863034Y-558942D01*
X862034Y-561276D01*
X860534Y-562609D01*
X859034Y-562942D01*
G01X879034Y-563609D02*
X878534Y-563275D01*
Y-562609D01*
X879034Y-562275D01*
X879534Y-562609D01*
Y-563275D01*
X879034Y-563609D01*
G01X762479Y-518729D02*
Y-493729D01*
X770669Y-514562D01*
X778859Y-493729D01*
Y-518729D01*
G01X795869D02*
X793979Y-518312D01*
X792089Y-516646D01*
X790829Y-513729D01*
X790199Y-510396D01*
X790829Y-507063D01*
X792089Y-504146D01*
X793979Y-502479D01*
X795869Y-502063D01*
X797759Y-502479D01*
X799649Y-504146D01*
X800909Y-507063D01*
X801224Y-510396D01*
X800909Y-513729D01*
X799649Y-516646D01*
X797759Y-518312D01*
X795869Y-518729D01*
G01X826739Y-493729D02*
Y-518729D01*
G01Y-514980D02*
X825479Y-517063D01*
X823589Y-518312D01*
X821384Y-518729D01*
X818864Y-517896D01*
X816974Y-515813D01*
X815714Y-513313D01*
X815399Y-510396D01*
X815714Y-507479D01*
X816974Y-504979D01*
X818864Y-502896D01*
X821384Y-502063D01*
X823589Y-502479D01*
X825164Y-503313D01*
X826739Y-504979D01*
G01X841544Y-507479D02*
X851624D01*
X850679Y-504562D01*
X849104Y-502896D01*
X846899Y-502063D01*
X844694Y-502479D01*
X842804Y-503729D01*
X841544Y-506646D01*
X840914Y-509146D01*
Y-511646D01*
X841544Y-514146D01*
X843119Y-516646D01*
X845009Y-518312D01*
X847214Y-518729D01*
X849419Y-517896D01*
X851624Y-515396D01*
G01X871469Y-518729D02*
Y-493729D01*
G01X784182Y-740940D02*
Y-758263D01*
G01Y619690D02*
Y602367D01*
G01X877989Y-752009D02*
X878146Y-750644D01*
X878381Y-749489D01*
X878694Y-748439D01*
X879086Y-747284D01*
X879713Y-745709D01*
X876579D01*
G01X877989Y608621D02*
X878146Y609986D01*
X878381Y611141D01*
X878694Y612191D01*
X879086Y613346D01*
X879713Y614921D01*
X876579D01*
G01X924339Y-664928D02*
Y-469407D01*
G01X932213Y-687398D02*
X936623Y-712398D01*
X941663Y-687398D01*
X946703Y-712398D01*
X951113Y-687398D01*
G01X966863Y-695732D02*
Y-712398D01*
G01Y-689065D02*
X966233Y-688648D01*
Y-687815D01*
X966863Y-687398D01*
X967493Y-687815D01*
Y-688648D01*
X966863Y-689065D01*
G01X987338Y-709482D02*
X988913Y-711148D01*
X991118Y-712398D01*
X993008D01*
X994898Y-711565D01*
X996158Y-710315D01*
X996788Y-708649D01*
X996473Y-706148D01*
X995213Y-704898D01*
X989543Y-702399D01*
X988283Y-699481D01*
X988913Y-697398D01*
X990173Y-696148D01*
X992063Y-695732D01*
X993953Y-696148D01*
X995843Y-697398D01*
G01X1017263Y-687398D02*
Y-712398D01*
G01X1012853Y-695732D02*
X1021673D01*
G01X1038053Y-712398D02*
Y-695732D01*
G01Y-699064D02*
X1039628Y-697398D01*
X1041203Y-696148D01*
X1043408Y-695732D01*
X1044983Y-696148D01*
X1046873Y-697398D01*
G01X1067663Y-712398D02*
X1065773Y-711981D01*
X1063883Y-710315D01*
X1062623Y-707398D01*
X1061993Y-704065D01*
X1062623Y-700732D01*
X1063883Y-697815D01*
X1065773Y-696148D01*
X1067663Y-695732D01*
X1069553Y-696148D01*
X1071443Y-697815D01*
X1072703Y-700732D01*
X1073018Y-704065D01*
X1072703Y-707398D01*
X1071443Y-710315D01*
X1069553Y-711981D01*
X1067663Y-712398D01*
G01X1087508D02*
Y-695732D01*
G01Y-699898D02*
X1088768Y-697815D01*
X1090658Y-696148D01*
X1093178Y-695732D01*
X1095383Y-696148D01*
X1097273Y-697815D01*
X1098218Y-700732D01*
Y-712398D01*
G01X1150193Y-689482D02*
X1148303Y-688231D01*
X1146098Y-687398D01*
X1143578D01*
X1140743Y-688648D01*
X1138538Y-690731D01*
X1136963Y-693232D01*
X1135703Y-697398D01*
X1135388Y-701148D01*
X1136018Y-704898D01*
X1136963Y-707398D01*
X1138853Y-709899D01*
X1141058Y-711565D01*
X1143263Y-712398D01*
X1145468D01*
X1147673Y-711565D01*
X1149563Y-710315D01*
X1151138Y-708649D01*
G01X1168463Y-712398D02*
X1166573Y-711981D01*
X1164683Y-710315D01*
X1163423Y-707398D01*
X1162793Y-704065D01*
X1163423Y-700732D01*
X1164683Y-697815D01*
X1166573Y-696148D01*
X1168463Y-695732D01*
X1170353Y-696148D01*
X1172243Y-697815D01*
X1173503Y-700732D01*
X1173818Y-704065D01*
X1173503Y-707398D01*
X1172243Y-710315D01*
X1170353Y-711981D01*
X1168463Y-712398D01*
G01X1189253D02*
Y-695732D01*
G01Y-699064D02*
X1190828Y-697398D01*
X1192403Y-696148D01*
X1194608Y-695732D01*
X1196183Y-696148D01*
X1198073Y-697398D01*
G01X1213193Y-720731D02*
Y-695732D01*
G01Y-699481D02*
X1214768Y-697398D01*
X1216343Y-696148D01*
X1218863Y-695732D01*
X1221068Y-696148D01*
X1223273Y-698231D01*
X1224218Y-701148D01*
X1224533Y-704065D01*
X1224218Y-706982D01*
X1223273Y-709899D01*
X1221383Y-711565D01*
X1218863Y-712398D01*
X1216658Y-711981D01*
X1214453Y-710732D01*
X1213193Y-709065D01*
G01X1244063Y-712398D02*
X1242173Y-711981D01*
X1240283Y-710315D01*
X1239023Y-707398D01*
X1238393Y-704065D01*
X1239023Y-700732D01*
X1240283Y-697815D01*
X1242173Y-696148D01*
X1244063Y-695732D01*
X1245953Y-696148D01*
X1247843Y-697815D01*
X1249103Y-700732D01*
X1249418Y-704065D01*
X1249103Y-707398D01*
X1247843Y-710315D01*
X1245953Y-711981D01*
X1244063Y-712398D01*
G01X1264853D02*
Y-695732D01*
G01Y-699064D02*
X1266428Y-697398D01*
X1268003Y-696148D01*
X1270208Y-695732D01*
X1271783Y-696148D01*
X1273673Y-697398D01*
G01X1300133Y-712398D02*
Y-695732D01*
G01Y-698648D02*
X1298873Y-696982D01*
X1296983Y-696148D01*
X1294778Y-695732D01*
X1292573Y-696565D01*
X1290683Y-698231D01*
X1289423Y-700732D01*
X1288793Y-704065D01*
X1289423Y-707398D01*
X1290683Y-709899D01*
X1292573Y-711565D01*
X1294778Y-712398D01*
X1296983Y-711981D01*
X1298873Y-710732D01*
X1300133Y-709065D01*
G01X1319663Y-687398D02*
Y-712398D01*
G01X1315253Y-695732D02*
X1324073D01*
G01X1344863D02*
Y-712398D01*
G01Y-689065D02*
X1344233Y-688648D01*
Y-687815D01*
X1344863Y-687398D01*
X1345493Y-687815D01*
Y-688648D01*
X1344863Y-689065D01*
G01X1370063Y-712398D02*
X1368173Y-711981D01*
X1366283Y-710315D01*
X1365023Y-707398D01*
X1364393Y-704065D01*
X1365023Y-700732D01*
X1366283Y-697815D01*
X1368173Y-696148D01*
X1370063Y-695732D01*
X1371953Y-696148D01*
X1373843Y-697815D01*
X1375103Y-700732D01*
X1375418Y-704065D01*
X1375103Y-707398D01*
X1373843Y-710315D01*
X1371953Y-711981D01*
X1370063Y-712398D01*
G01X1389908D02*
Y-695732D01*
G01Y-699898D02*
X1391168Y-697815D01*
X1393058Y-696148D01*
X1395578Y-695732D01*
X1397783Y-696148D01*
X1399673Y-697815D01*
X1400618Y-700732D01*
Y-712398D01*
G01X957409Y-740940D02*
Y-758263D01*
G01X963488Y-643222D02*
X964488Y-642222D01*
X965238Y-640556D01*
X965738Y-638222D01*
X965238Y-636222D01*
X964238Y-634889D01*
X962488Y-633889D01*
X955738D01*
Y-653889D01*
X963988D01*
X965738Y-652556D01*
X966738Y-650556D01*
X967238Y-648222D01*
X966738Y-645889D01*
X965238Y-643889D01*
X963488Y-643222D01*
X955738D01*
G01X985988Y-653889D02*
Y-640556D01*
G01Y-642889D02*
X984988Y-641556D01*
X983488Y-640889D01*
X981738Y-640556D01*
X979988Y-641223D01*
X978488Y-642556D01*
X977488Y-644556D01*
X976988Y-647223D01*
X977488Y-649889D01*
X978488Y-651889D01*
X979988Y-653222D01*
X981738Y-653889D01*
X983488Y-653556D01*
X984988Y-652556D01*
X985988Y-651223D01*
G01X997988Y-653889D02*
Y-640556D01*
G01Y-643222D02*
X999238Y-641889D01*
X1000488Y-640889D01*
X1002238Y-640556D01*
X1003488Y-640889D01*
X1004988Y-641889D01*
G01X1021488Y-653889D02*
Y-633889D01*
G01X1037738Y-644889D02*
X1045738D01*
X1044988Y-642556D01*
X1043738Y-641223D01*
X1041988Y-640556D01*
X1040238Y-640889D01*
X1038738Y-641889D01*
X1037738Y-644223D01*
X1037238Y-646223D01*
Y-648222D01*
X1037738Y-650223D01*
X1038988Y-652223D01*
X1040488Y-653556D01*
X1042238Y-653889D01*
X1043988Y-653222D01*
X1045738Y-651223D01*
G01X1057238Y-653889D02*
Y-640556D01*
G01Y-643889D02*
X1058238Y-642222D01*
X1059738Y-640889D01*
X1061738Y-640556D01*
X1063488Y-640889D01*
X1064988Y-642222D01*
X1065738Y-644556D01*
Y-653889D01*
G01X1096488Y-633889D02*
Y-653889D01*
X1106488D01*
G01X1121488Y-640556D02*
Y-653889D01*
G01Y-635223D02*
X1120988Y-634889D01*
Y-634222D01*
X1121488Y-633889D01*
X1121988Y-634222D01*
Y-634889D01*
X1121488Y-635223D01*
G01X1137238Y-640556D02*
Y-649889D01*
X1138238Y-652223D01*
X1139738Y-653556D01*
X1141488Y-653889D01*
X1143238Y-653556D01*
X1144738Y-652223D01*
X1145738Y-649889D01*
G01Y-653889D02*
Y-640556D01*
G01X967236Y-560967D02*
Y-540967D01*
X964236Y-544967D01*
G01Y-560967D02*
X970236D01*
G01X981736Y-557968D02*
X983236Y-559634D01*
X984986Y-560634D01*
X987236Y-560967D01*
X989486Y-560300D01*
X991236Y-558967D01*
X992486Y-556634D01*
X992736Y-553967D01*
X992236Y-551301D01*
X990986Y-549634D01*
X989236Y-548301D01*
X987486Y-547967D01*
X985736Y-548301D01*
X983486Y-549634D01*
X984236Y-540967D01*
X990986D01*
G01X1006736Y-560967D02*
X1007236Y-556634D01*
X1007986Y-552967D01*
X1008986Y-549634D01*
X1010236Y-545967D01*
X1012236Y-540967D01*
X1002236D01*
G01X1021736Y-557968D02*
X1023236Y-559634D01*
X1024986Y-560634D01*
X1027236Y-560967D01*
X1029486Y-560300D01*
X1031236Y-558967D01*
X1032486Y-556634D01*
X1032736Y-553967D01*
X1032236Y-551301D01*
X1030986Y-549634D01*
X1029236Y-548301D01*
X1027486Y-547967D01*
X1025736Y-548301D01*
X1023486Y-549634D01*
X1024236Y-540967D01*
X1030986D01*
G01X1047236D02*
X1045236Y-541634D01*
X1043736Y-543300D01*
X1042736Y-545300D01*
X1041986Y-547967D01*
X1041736Y-550967D01*
X1041986Y-553967D01*
X1042736Y-556634D01*
X1043736Y-558634D01*
X1045236Y-560300D01*
X1047236Y-560967D01*
X1049236Y-560300D01*
X1050736Y-558634D01*
X1051736Y-556634D01*
X1052486Y-553967D01*
X1052736Y-550967D01*
X1052486Y-547967D01*
X1051736Y-545300D01*
X1050736Y-543300D01*
X1049236Y-541634D01*
X1047236Y-540967D01*
G01X951862Y-490022D02*
Y-515022D01*
X964462D01*
G01X983362Y-498356D02*
Y-515022D01*
G01Y-491689D02*
X982732Y-491272D01*
Y-490439D01*
X983362Y-490022D01*
X983992Y-490439D01*
Y-491272D01*
X983362Y-491689D01*
G01X1004152Y-521272D02*
X1006357Y-522939D01*
X1008877Y-523355D01*
X1011082Y-522939D01*
X1012972Y-520856D01*
X1014232Y-517939D01*
Y-498356D01*
G01Y-501688D02*
X1012972Y-500022D01*
X1011082Y-498772D01*
X1008877Y-498356D01*
X1006357Y-499189D01*
X1004782Y-500855D01*
X1003522Y-503772D01*
X1002892Y-506689D01*
X1003207Y-509189D01*
X1004467Y-512106D01*
X1006357Y-514189D01*
X1008877Y-515022D01*
X1010767Y-514605D01*
X1012972Y-512939D01*
X1014232Y-511273D01*
G01X1028407Y-515022D02*
Y-490022D01*
G01Y-502105D02*
X1029982Y-500022D01*
X1031557Y-498772D01*
X1034077Y-498356D01*
X1035967Y-498772D01*
X1038172Y-500439D01*
X1039117Y-502939D01*
Y-515022D01*
G01X1058962Y-490022D02*
Y-515022D01*
G01X1054552Y-498356D02*
X1063372D01*
G01X1078807Y-515022D02*
Y-498356D01*
G01Y-502522D02*
X1080067Y-500439D01*
X1081957Y-498772D01*
X1084477Y-498356D01*
X1086682Y-498772D01*
X1088572Y-500439D01*
X1089517Y-503356D01*
Y-515022D01*
G01X1109362Y-498356D02*
Y-515022D01*
G01Y-491689D02*
X1108732Y-491272D01*
Y-490439D01*
X1109362Y-490022D01*
X1109992Y-490439D01*
Y-491272D01*
X1109362Y-491689D01*
G01X1129207Y-515022D02*
Y-498356D01*
G01Y-502522D02*
X1130467Y-500439D01*
X1132357Y-498772D01*
X1134877Y-498356D01*
X1137082Y-498772D01*
X1138972Y-500439D01*
X1139917Y-503356D01*
Y-515022D01*
G01X1155352Y-521272D02*
X1157557Y-522939D01*
X1160077Y-523355D01*
X1162282Y-522939D01*
X1164172Y-520856D01*
X1165432Y-517939D01*
Y-498356D01*
G01Y-501688D02*
X1164172Y-500022D01*
X1162282Y-498772D01*
X1160077Y-498356D01*
X1157557Y-499189D01*
X1155982Y-500855D01*
X1154722Y-503772D01*
X1154092Y-506689D01*
X1154407Y-509189D01*
X1155667Y-512106D01*
X1157557Y-514189D01*
X1160077Y-515022D01*
X1161967Y-514605D01*
X1164172Y-512939D01*
X1165432Y-511273D01*
G01X1203862Y-515022D02*
Y-490022D01*
X1211422D01*
X1213942Y-491272D01*
X1215832Y-494189D01*
X1216462Y-497522D01*
X1215832Y-500855D01*
X1214257Y-503356D01*
X1211422Y-504606D01*
X1203862D01*
G01X1227487Y-490022D02*
X1235362Y-515022D01*
X1243237Y-490022D01*
G01X1260562D02*
Y-515022D01*
G01X1253317Y-490022D02*
X1267807D01*
G01X1302772Y-515022D02*
Y-490022D01*
X1310962Y-510855D01*
X1319152Y-490022D01*
Y-515022D01*
G01X1336162Y-515855D02*
X1335532Y-515439D01*
Y-514605D01*
X1336162Y-514189D01*
X1336792Y-514605D01*
Y-515439D01*
X1336162Y-515855D01*
G01X1355377Y-494189D02*
X1357267Y-491689D01*
X1359472Y-490439D01*
X1361992Y-490022D01*
X1365142Y-490855D01*
X1367347Y-492939D01*
X1367977Y-495438D01*
X1367662Y-497939D01*
X1366402Y-500022D01*
X1360102Y-504189D01*
X1357267Y-507105D01*
X1355377Y-511273D01*
X1354747Y-515022D01*
X1367977D01*
G01X1403887D02*
X1411762Y-490022D01*
X1419637Y-515022D01*
G01X1416802Y-506272D02*
X1406722D01*
G01X1442632Y-490022D02*
Y-515022D01*
G01Y-511273D02*
X1441372Y-513356D01*
X1439482Y-514605D01*
X1437277Y-515022D01*
X1434757Y-514189D01*
X1432867Y-512106D01*
X1431607Y-509606D01*
X1431292Y-506689D01*
X1431607Y-503772D01*
X1432867Y-501272D01*
X1434757Y-499189D01*
X1437277Y-498356D01*
X1439482Y-498772D01*
X1441057Y-499606D01*
X1442632Y-501272D01*
G01X1467832Y-515022D02*
Y-498356D01*
G01Y-501272D02*
X1466572Y-499606D01*
X1464682Y-498772D01*
X1462477Y-498356D01*
X1460272Y-499189D01*
X1458382Y-500855D01*
X1457122Y-503356D01*
X1456492Y-506689D01*
X1457122Y-510022D01*
X1458382Y-512523D01*
X1460272Y-514189D01*
X1462477Y-515022D01*
X1464682Y-514605D01*
X1466572Y-513356D01*
X1467832Y-511689D01*
G01X1481692Y-523355D02*
Y-498356D01*
G01Y-502105D02*
X1483267Y-500022D01*
X1484842Y-498772D01*
X1487362Y-498356D01*
X1489567Y-498772D01*
X1491772Y-500855D01*
X1492717Y-503772D01*
X1493032Y-506689D01*
X1492717Y-509606D01*
X1491772Y-512523D01*
X1489882Y-514189D01*
X1487362Y-515022D01*
X1485157Y-514605D01*
X1482952Y-513356D01*
X1481692Y-511689D01*
G01X1512562Y-490022D02*
Y-515022D01*
G01X1508152Y-498356D02*
X1516972D01*
G01X1537762Y-515022D02*
X1535872Y-514605D01*
X1533982Y-512939D01*
X1532722Y-510022D01*
X1532092Y-506689D01*
X1532722Y-503356D01*
X1533982Y-500439D01*
X1535872Y-498772D01*
X1537762Y-498356D01*
X1539652Y-498772D01*
X1541542Y-500439D01*
X1542802Y-503356D01*
X1543117Y-506689D01*
X1542802Y-510022D01*
X1541542Y-512939D01*
X1539652Y-514605D01*
X1537762Y-515022D01*
G01X1558552D02*
Y-498356D01*
G01Y-501688D02*
X1560127Y-500022D01*
X1561702Y-498772D01*
X1563907Y-498356D01*
X1565482Y-498772D01*
X1567372Y-500022D01*
G01X1620292Y-492106D02*
X1618402Y-490855D01*
X1616197Y-490022D01*
X1613677D01*
X1610842Y-491272D01*
X1608637Y-493355D01*
X1607062Y-495856D01*
X1605802Y-500022D01*
X1605487Y-503772D01*
X1606117Y-507522D01*
X1607062Y-510022D01*
X1608952Y-512523D01*
X1611157Y-514189D01*
X1613362Y-515022D01*
X1615567D01*
X1617772Y-514189D01*
X1619662Y-512939D01*
X1621237Y-511273D01*
G01X1644232Y-515022D02*
Y-498356D01*
G01Y-501272D02*
X1642972Y-499606D01*
X1641082Y-498772D01*
X1638877Y-498356D01*
X1636672Y-499189D01*
X1634782Y-500855D01*
X1633522Y-503356D01*
X1632892Y-506689D01*
X1633522Y-510022D01*
X1634782Y-512523D01*
X1636672Y-514189D01*
X1638877Y-515022D01*
X1641082Y-514605D01*
X1642972Y-513356D01*
X1644232Y-511689D01*
G01X1659352Y-515022D02*
Y-498356D01*
G01Y-501688D02*
X1660927Y-500022D01*
X1662502Y-498772D01*
X1664707Y-498356D01*
X1666282Y-498772D01*
X1668172Y-500022D01*
G01X1694632Y-490022D02*
Y-515022D01*
G01Y-511273D02*
X1693372Y-513356D01*
X1691482Y-514605D01*
X1689277Y-515022D01*
X1686757Y-514189D01*
X1684867Y-512106D01*
X1683607Y-509606D01*
X1683292Y-506689D01*
X1683607Y-503772D01*
X1684867Y-501272D01*
X1686757Y-499189D01*
X1689277Y-498356D01*
X1691482Y-498772D01*
X1693057Y-499606D01*
X1694632Y-501272D01*
G01X957409Y619690D02*
Y602367D01*
G01X981266Y-611849D02*
Y-591849D01*
X978266Y-595849D01*
G01Y-611849D02*
X984266D01*
G01X1042635Y-12095D02*
X1041661Y-12817D01*
G01X1043122Y-11374D02*
X1042635Y-12095D01*
G01X1043610Y-9930D02*
X1043122Y-11374D01*
G01X1043610Y-7043D02*
Y-9930D01*
G01X1043122Y-5599D02*
X1043610Y-7043D01*
G01X1042635Y-4878D02*
X1043122Y-5599D01*
G01X1041661Y-4156D02*
X1042635Y-4878D01*
G01X1040687D02*
X1041661Y-4156D01*
G01X1040199Y-5599D02*
X1040687Y-4878D01*
G01X1039712Y-7043D02*
X1040199Y-5599D01*
G01X1039712Y-9930D02*
Y-7043D01*
G01X1040199Y-11374D02*
X1039712Y-9930D01*
G01X1040687Y-12095D02*
X1040199Y-11374D01*
G01X1041661Y-12817D02*
X1040687Y-12095D01*
G01X1039712Y7065D02*
X1044097D01*
G01X1043122Y13561D02*
X1039712Y7065D01*
G01X1043122Y4899D02*
Y13561D01*
G01X1042148Y256737D02*
X1042635Y258902D01*
G01X1041661Y253128D02*
X1042148Y256737D01*
G01X1034840Y261067D02*
X1035327Y260346D01*
G01X1032404D02*
X1032891Y261067D01*
G01X1031917Y258902D02*
X1032404Y260346D01*
G01X1031917Y256015D02*
Y258902D01*
G01X1032404Y254571D02*
X1031917Y256015D01*
G01X1032891Y253850D02*
X1032404Y254571D01*
G01X1033866Y253128D02*
X1032891Y253850D01*
G01X1034840D02*
X1033866Y253128D01*
G01X1035327Y254571D02*
X1034840Y253850D01*
G01X1035815Y256015D02*
X1035327Y254571D01*
G01Y257458D02*
X1035815Y256015D01*
G01X1033866Y258180D02*
X1035327Y257458D01*
G01X1032404D02*
X1033866Y258180D01*
G01X1031917Y256015D02*
X1032404Y257458D01*
G01X1042635Y258902D02*
X1043610Y261789D01*
G01X1033866D02*
X1034840Y261067D01*
G01X1032891D02*
X1033866Y261789D01*
G01X1043610D02*
X1039712D01*
G01X1032891Y351330D02*
X1032404Y352052D01*
G01X1033866Y350608D02*
X1032891Y351330D01*
G01X1034840D02*
X1033866Y350608D01*
G01X1035327Y352052D02*
X1034840Y351330D01*
G01X1035815Y353495D02*
X1035327Y352052D01*
G01X1035815Y356382D02*
Y353495D01*
G01X1035327Y357826D02*
X1035815Y356382D01*
G01X1034840Y358548D02*
X1035327Y357826D01*
G01X1033866Y359269D02*
X1034840Y358548D01*
G01X1032891D02*
X1033866Y359269D01*
G01X1032404Y357826D02*
X1032891Y358548D01*
G01X1031917Y356382D02*
X1032404Y357826D01*
G01Y354939D02*
X1031917Y356382D01*
G01X1033866Y354217D02*
X1032404Y354939D01*
G01X1035327D02*
X1033866Y354217D01*
G01X1035815Y356382D02*
X1035327Y354939D01*
G01X1043122Y355661D02*
X1041174Y354217D01*
G01X1043610Y356382D02*
X1043122Y355661D01*
G01X1043610Y357826D02*
Y356382D01*
G01X1043122Y358548D02*
X1043610Y357826D01*
G01X1042148Y359269D02*
X1043122Y358548D01*
G01X1041174Y359269D02*
X1042148D01*
G01X1040199Y358548D02*
X1041174Y359269D01*
G01X1039712Y357826D02*
X1040199Y358548D01*
G01X1039712Y350608D02*
X1043610D01*
G01X1040199Y352773D02*
X1039712Y350608D01*
G01X1041174Y354217D02*
X1040199Y352773D01*
G01X1051374Y-752009D02*
X1051922Y-751904D01*
X1052549Y-751589D01*
X1052941Y-751064D01*
X1053097Y-750329D01*
X1052941Y-749594D01*
X1052471Y-748964D01*
X1051766Y-748649D01*
X1050982D01*
X1050512Y-748439D01*
X1050121Y-747914D01*
X1049964Y-747179D01*
X1050199Y-746444D01*
X1050747Y-745919D01*
X1051374Y-745709D01*
X1052001Y-745919D01*
X1052549Y-746444D01*
X1052784Y-747179D01*
X1052627Y-747914D01*
X1052236Y-748439D01*
X1051766Y-748649D01*
X1050982D01*
X1050277Y-748964D01*
X1049807Y-749594D01*
X1049651Y-750329D01*
X1049807Y-751064D01*
X1050199Y-751589D01*
X1050826Y-751904D01*
X1051374Y-752009D01*
G01X1058226Y-12095D02*
X1057252Y-12817D01*
G01X1058713Y-11374D02*
X1058226Y-12095D01*
G01X1059200Y-9930D02*
X1058713Y-11374D01*
G01X1059200Y-7043D02*
Y-9930D01*
G01X1058713Y-5599D02*
X1059200Y-7043D01*
G01X1058226Y-4878D02*
X1058713Y-5599D01*
G01X1057252Y-4156D02*
X1058226Y-4878D01*
G01X1056277D02*
X1057252Y-4156D01*
G01X1055790Y-5599D02*
X1056277Y-4878D01*
G01X1055303Y-7043D02*
X1055790Y-5599D01*
G01X1055303Y-9930D02*
Y-7043D01*
G01X1055790Y-11374D02*
X1055303Y-9930D01*
G01X1056277Y-12095D02*
X1055790Y-11374D01*
G01X1057252Y-12817D02*
X1056277Y-12095D01*
G01X1048969D02*
X1049456Y-12817D01*
G01X1048969D02*
Y-12095D01*
G01X1049456Y-12817D02*
X1048969D01*
G01Y5621D02*
X1049456Y4899D01*
G01X1048969D02*
Y5621D01*
G01X1049456Y4899D02*
X1048969D01*
G01X1055790Y5621D02*
X1055303Y6343D01*
G01X1056764Y4899D02*
X1055790Y5621D01*
G01X1057739Y4899D02*
X1056764D01*
G01X1058713Y5621D02*
X1057739Y4899D01*
G01X1059200Y6343D02*
X1058713Y5621D01*
G01X1059687Y7787D02*
X1059200Y6343D01*
G01Y9230D02*
X1059687Y7787D01*
G01X1058713Y9952D02*
X1059200Y9230D01*
G01X1057739Y10674D02*
X1058713Y9952D01*
G01X1056764Y10674D02*
X1057739D01*
G01X1055790Y9952D02*
X1056764Y10674D01*
G01X1056277Y13561D02*
X1055790Y9952D01*
G01X1059200Y13561D02*
X1056277D01*
G01X1048969Y253850D02*
X1049456Y253128D01*
G01X1048969D02*
Y253850D01*
G01X1049456Y253128D02*
X1048969D01*
G01X1055790Y253850D02*
X1055303Y254571D01*
G01X1056764Y253128D02*
X1055790Y253850D01*
G01X1057739Y253128D02*
X1056764D01*
G01X1058713Y253850D02*
X1057739Y253128D01*
G01X1059200Y254571D02*
X1058713Y253850D01*
G01X1059687Y256015D02*
X1059200Y254571D01*
G01Y257458D02*
X1059687Y256015D01*
G01X1058713Y258180D02*
X1059200Y257458D01*
G01X1057739Y258902D02*
X1058713Y258180D01*
G01X1056764Y258902D02*
X1057739D01*
G01X1055790Y258180D02*
X1056764Y258902D01*
G01X1056277Y261789D02*
X1055790Y258180D01*
G01X1059200Y261789D02*
X1056277D01*
G01X1055790Y351330D02*
X1055303Y352052D01*
G01X1056764Y350608D02*
X1055790Y351330D01*
G01X1057739Y350608D02*
X1056764D01*
G01X1058713Y351330D02*
X1057739Y350608D01*
G01X1058713Y354939D02*
X1059687Y353495D01*
G01X1057739Y355661D02*
X1058713Y354939D01*
G01Y356382D02*
X1057739Y355661D01*
G01X1059200Y357104D02*
X1058713Y356382D01*
G01X1059200Y357826D02*
Y357104D01*
G01X1058713Y358548D02*
X1059200Y357826D01*
G01X1057739Y359269D02*
X1058713Y358548D01*
G01X1056764Y359269D02*
X1057739D01*
G01X1055790Y358548D02*
X1056764Y359269D01*
G01X1059687Y352773D02*
X1058713Y351330D01*
G01X1059687Y353495D02*
Y352773D01*
G01X1048969Y351330D02*
X1049456Y350608D01*
G01X1048969D02*
Y351330D01*
G01X1049456Y350608D02*
X1048969D01*
G01X1056764Y355661D02*
X1057739D01*
G01X1051374Y608621D02*
X1051922Y608726D01*
X1052549Y609041D01*
X1052941Y609566D01*
X1053097Y610301D01*
X1052941Y611036D01*
X1052471Y611666D01*
X1051766Y611981D01*
X1050982D01*
X1050512Y612191D01*
X1050121Y612716D01*
X1049964Y613451D01*
X1050199Y614186D01*
X1050747Y614711D01*
X1051374Y614921D01*
X1052001Y614711D01*
X1052549Y614186D01*
X1052784Y613451D01*
X1052627Y612716D01*
X1052236Y612191D01*
X1051766Y611981D01*
X1050982D01*
X1050277Y611666D01*
X1049807Y611036D01*
X1049651Y610301D01*
X1049807Y609566D01*
X1050199Y609041D01*
X1050826Y608726D01*
X1051374Y608621D01*
G01X1331863Y-14983D02*
X1073275D01*
G01X1066021Y-12095D02*
X1065047Y-12817D01*
G01X1066508Y-11374D02*
X1066021Y-12095D01*
G01X1066996Y-9930D02*
X1066508Y-11374D01*
G01X1066996Y-7043D02*
Y-9930D01*
G01X1066508Y-5599D02*
X1066996Y-7043D01*
G01X1066021Y-4878D02*
X1066508Y-5599D01*
G01X1065047Y-4156D02*
X1066021Y-4878D01*
G01X1064072D02*
X1065047Y-4156D01*
G01X1063585Y-5599D02*
X1064072Y-4878D01*
G01X1063098Y-7043D02*
X1063585Y-5599D01*
G01X1063098Y-9930D02*
Y-7043D01*
G01X1063585Y-11374D02*
X1063098Y-9930D01*
G01X1064072Y-12095D02*
X1063585Y-11374D01*
G01X1065047Y-12817D02*
X1064072Y-12095D01*
G01X1345052Y2734D02*
X1073275D01*
G01X1066021Y5621D02*
X1065047Y4899D01*
G01X1066508Y6343D02*
X1066021Y5621D01*
G01X1066996Y7787D02*
X1066508Y6343D01*
G01X1066996Y10674D02*
Y7787D01*
G01X1066508Y12117D02*
X1066996Y10674D01*
G01X1066021Y12839D02*
X1066508Y12117D01*
G01X1065047Y13561D02*
X1066021Y12839D01*
G01X1064072D02*
X1065047Y13561D01*
G01X1063585Y12117D02*
X1064072Y12839D01*
G01X1063098Y10674D02*
X1063585Y12117D01*
G01X1063098Y7787D02*
Y10674D01*
G01X1063585Y6343D02*
X1063098Y7787D01*
G01X1064072Y5621D02*
X1063585Y6343D01*
G01X1065047Y4899D02*
X1064072Y5621D01*
G01X1115919Y250962D02*
X1073275D01*
G01X1063585Y253850D02*
X1063098Y254571D01*
G01X1064559Y253128D02*
X1063585Y253850D01*
G01X1065534Y253128D02*
X1064559D01*
G01X1066508Y253850D02*
X1065534Y253128D01*
G01X1066996Y254571D02*
X1066508Y253850D01*
G01X1067483Y256015D02*
X1066996Y254571D01*
G01Y257458D02*
X1067483Y256015D01*
G01X1066508Y258180D02*
X1066996Y257458D01*
G01X1065534Y258902D02*
X1066508Y258180D01*
G01X1064559Y258902D02*
X1065534D01*
G01X1063585Y258180D02*
X1064559Y258902D01*
G01X1064072Y261789D02*
X1063585Y258180D01*
G01X1066996Y261789D02*
X1064072D01*
G01X1115919Y348443D02*
X1073275D01*
G01X1065047Y359269D02*
Y350608D01*
G01X1104042Y-69408D02*
X1102598Y-68920D01*
G01X1106929Y-69408D02*
X1104042D01*
G01X1108373Y-68920D02*
X1106929Y-69408D01*
G01X1109095Y-60151D02*
X1109816Y-59664D01*
G01Y-60151D02*
X1109095D01*
G01X1109816Y-59664D02*
Y-60151D01*
G01X1101877Y-52843D02*
X1101155Y-51868D01*
G01X1102598Y-53330D02*
X1101877Y-52843D01*
G01X1104042Y-53817D02*
X1102598Y-53330D01*
G01X1106929Y-53817D02*
X1104042D01*
G01X1108373Y-53330D02*
X1106929Y-53817D01*
G01X1109095Y-52843D02*
X1108373Y-53330D01*
G01X1109816Y-51868D02*
X1109095Y-52843D01*
G01Y-66485D02*
X1109816Y-67459D01*
G01X1108373Y-65997D02*
X1109095Y-66485D01*
G01X1106929Y-65510D02*
X1108373Y-65997D01*
G01X1104042Y-65510D02*
X1106929D01*
G01X1102598Y-65997D02*
X1104042Y-65510D01*
G01X1101877Y-66485D02*
X1102598Y-65997D01*
G01X1101155Y-67459D02*
X1101877Y-66485D01*
G01Y-68433D02*
X1101155Y-67459D01*
G01X1102598Y-68920D02*
X1101877Y-68433D01*
G01X1109095D02*
X1108373Y-68920D01*
G01X1109816Y-67459D02*
X1109095Y-68433D01*
G01Y-43099D02*
X1109816Y-44073D01*
G01X1108373Y-42611D02*
X1109095Y-43099D01*
G01X1106929Y-42124D02*
X1108373Y-42611D01*
G01X1104042Y-42124D02*
X1106929D01*
G01X1102598Y-42611D02*
X1104042Y-42124D01*
G01X1101877Y-43099D02*
X1102598Y-42611D01*
G01X1101155Y-44073D02*
X1101877Y-43099D01*
G01Y-45048D02*
X1101155Y-44073D01*
G01X1102598Y-45535D02*
X1101877Y-45048D01*
G01X1104042Y-46022D02*
X1102598Y-45535D01*
G01X1106929Y-46022D02*
X1104042D01*
G01X1108373Y-45535D02*
X1106929Y-46022D01*
G01X1109095Y-45048D02*
X1108373Y-45535D01*
G01X1109816Y-44073D02*
X1109095Y-45048D01*
G01Y-50894D02*
X1109816Y-51868D01*
G01X1108373Y-50407D02*
X1109095Y-50894D01*
G01X1106929Y-49920D02*
X1108373Y-50407D01*
G01X1104042Y-49920D02*
X1106929D01*
G01X1102598Y-50407D02*
X1104042Y-49920D01*
G01X1101877Y-50894D02*
X1102598Y-50407D01*
G01X1101155Y-51868D02*
X1101877Y-50894D01*
G01X1111982Y-18920D02*
Y-35845D01*
G01Y258836D02*
G03X1119856Y250962I7874J0D01*
G01X1111982Y258836D02*
G03X1119856Y250962I7874J0D01*
G01X1111982Y340569D02*
Y258836D01*
G01Y340569D02*
Y258836D01*
G01X1119856Y348443D02*
G03X1111982Y340569I0J-7874D01*
G01X1119856Y348443D02*
G03X1111982Y340569I0J-7874D01*
G01X1119856Y250962D02*
X1400171D01*
G01X1119856D02*
X1320052D01*
G01X1153320Y301199D02*
G03X1121824Y301198I-15748J0D01*
G03X1153320Y301199I15748J1D01*
G01X1453517Y348443D02*
X1119856D01*
G01X1453517D02*
X1119856D01*
G01X1127467Y369782D02*
X1128189Y370269D01*
G01X1126745Y368808D02*
X1127467Y369782D01*
G01Y367833D02*
X1126745Y368808D01*
G01X1128189Y367346D02*
X1127467Y367833D01*
G01X1129633Y366859D02*
X1128189Y367346D01*
G01X1126745Y392194D02*
X1127467Y393168D01*
G01Y391219D02*
X1126745Y392194D01*
G01X1128189Y390732D02*
X1127467Y391219D01*
G01X1129633Y390245D02*
X1128189Y390732D01*
G01X1126745Y383424D02*
X1130354Y382937D01*
G01X1126745Y386347D02*
Y383424D01*
G01X1128189Y393655D02*
X1129633Y394143D01*
G01X1127467Y393168D02*
X1128189Y393655D01*
G01X1130638Y-740940D02*
Y-758263D01*
G01X1144560Y301199D02*
G03X1130585Y301198I-6987J0D01*
G03X1144560Y301199I6987J1D01*
G01X1137572Y305135D02*
Y360580D01*
G01X1134685Y376116D02*
X1135407Y376603D01*
G01Y376116D02*
X1134685D01*
G01X1135407Y376603D02*
Y376116D01*
G01X1132520Y366859D02*
X1129633D01*
G01X1133963Y367346D02*
X1132520Y366859D01*
G01X1134685Y367833D02*
X1133963Y367346D01*
G01X1135407Y368808D02*
X1134685Y367833D01*
G01Y369782D02*
X1135407Y368808D01*
G01X1133963Y370269D02*
X1134685Y369782D01*
G01X1132520Y370757D02*
X1133963Y370269D01*
G01X1131076D02*
X1132520Y370757D01*
G01X1130354Y368808D02*
X1131076Y370269D01*
G01Y367346D02*
X1130354Y368808D01*
G01X1132520Y366859D02*
X1131076Y367346D01*
G01X1134685Y393168D02*
X1135407Y392194D01*
G01X1132520Y390245D02*
X1129633D01*
G01X1133963Y390732D02*
X1132520Y390245D01*
G01X1134685Y391219D02*
X1133963Y390732D01*
G01X1135407Y392194D02*
X1134685Y391219D01*
G01Y382937D02*
X1133963Y382450D01*
G01X1135407Y383911D02*
X1134685Y382937D01*
G01X1135407Y384885D02*
Y383911D01*
G01X1134685Y385860D02*
X1135407Y384885D01*
G01X1133963Y386347D02*
X1134685Y385860D01*
G01X1132520Y386835D02*
X1133963Y386347D01*
G01X1131076D02*
X1132520Y386835D01*
G01X1130354Y385860D02*
X1131076Y386347D01*
G01X1129633Y384885D02*
X1130354Y385860D01*
G01X1129633Y383911D02*
Y384885D01*
G01X1130354Y382937D02*
X1129633Y383911D01*
G01X1133963Y393655D02*
X1134685Y393168D01*
G01X1132520Y394143D02*
X1133963Y393655D01*
G01X1129633Y394143D02*
X1132520D01*
G01X1130638Y619690D02*
Y602367D01*
G01X1223271Y-751274D02*
X1223820Y-751799D01*
X1224446Y-752009D01*
X1225073Y-751799D01*
X1225621Y-751169D01*
X1226013Y-750224D01*
X1226170Y-749279D01*
Y-748124D01*
X1226013Y-747179D01*
X1225621Y-746339D01*
X1225151Y-745919D01*
X1224603Y-745709D01*
X1223976Y-745919D01*
X1223506Y-746339D01*
X1223193Y-746969D01*
X1223036Y-747809D01*
X1223193Y-748544D01*
X1223585Y-749279D01*
X1224055Y-749699D01*
X1224603Y-749804D01*
X1225230Y-749594D01*
X1225700Y-749069D01*
X1226170Y-748124D01*
G01X1223271Y609356D02*
X1223820Y608831D01*
X1224446Y608621D01*
X1225073Y608831D01*
X1225621Y609461D01*
X1226013Y610406D01*
X1226170Y611351D01*
Y612506D01*
X1226013Y613451D01*
X1225621Y614291D01*
X1225151Y614711D01*
X1224603Y614921D01*
X1223976Y614711D01*
X1223506Y614291D01*
X1223193Y613661D01*
X1223036Y612821D01*
X1223193Y612086D01*
X1223585Y611351D01*
X1224055Y610931D01*
X1224603Y610826D01*
X1225230Y611036D01*
X1225700Y611561D01*
X1226170Y612506D01*
G01X1240609Y-103408D02*
X1240122Y-101243D01*
G01X1241584Y-104852D02*
X1240609Y-103408D01*
G01X1242558Y-105574D02*
X1241584Y-104852D01*
G01X1243533Y-105574D02*
X1242558D01*
G01X1244507Y-104852D02*
X1243533Y-105574D01*
G01Y-96912D02*
X1244507Y-97634D01*
G01X1242558Y-96912D02*
X1243533D01*
G01X1241584Y-97634D02*
X1242558Y-96912D01*
G01X1241096Y-98355D02*
X1241584Y-97634D01*
G01X1240609Y-99078D02*
X1241096Y-98355D01*
G01X1240122Y-101243D02*
X1240609Y-99078D01*
G01X1236908Y290570D02*
X1242075D01*
G01Y289439D02*
X1236908D01*
G01Y285293D02*
X1235800D01*
G01X1243182D02*
X1242075D01*
G01X1243182Y294151D02*
Y285293D01*
G01X1242075Y290570D02*
Y294151D01*
G01Y285293D02*
Y289439D01*
G01X1236908D02*
Y285293D01*
G01Y294151D02*
Y290570D01*
G01X1235800Y285293D02*
Y294151D01*
G01X1242075D02*
X1243182D01*
G01X1235800D02*
X1236908D01*
G01X1244994Y-104130D02*
X1244507Y-104852D01*
G01X1252789Y-101965D02*
Y-103408D01*
G01X1248892D02*
Y-101965D01*
G01X1249866Y-104852D02*
X1248892Y-103408D01*
G01X1250841Y-105574D02*
X1249866Y-104852D01*
G01X1251815D02*
X1250841Y-105574D01*
G01X1252789Y-103408D02*
X1251815Y-104852D01*
G01X1258636Y-101243D02*
Y-105574D01*
G01X1255713Y-99799D02*
Y-105574D01*
G01X1244507Y-97634D02*
X1244994Y-98355D01*
G01X1251815Y-100521D02*
X1252789Y-101965D01*
G01X1250841Y-99799D02*
X1251815Y-100521D01*
G01X1249866D02*
X1250841Y-99799D01*
G01X1248892Y-101965D02*
X1249866Y-100521D01*
G01X1257661Y-99799D02*
X1258636Y-101243D01*
G01X1256687Y-99799D02*
X1257661D01*
G01X1255713Y-101243D02*
X1256687Y-99799D01*
G01X1260585D02*
X1261559Y-101243D01*
G01X1259610Y-99799D02*
X1260585D01*
G01X1258636Y-101243D02*
X1259610Y-99799D01*
G01X1250933Y293209D02*
X1256285D01*
G01X1259976Y291324D02*
X1260715D01*
G01X1258131D02*
X1259054D01*
G01X1253886Y290947D02*
X1252779D01*
G01X1260345Y290570D02*
X1259976D01*
G01X1252779Y290005D02*
X1253886D01*
G01X1250011Y289251D02*
X1251302D01*
G01X1251118Y287555D02*
X1250011D01*
G01X1252779Y290947D02*
X1251856Y290759D01*
G01X1253886Y285293D02*
X1254809Y285482D01*
G01X1252041Y289817D02*
X1252779Y290005D01*
G01X1254624Y286424D02*
X1253886Y286235D01*
G01X1260715Y291324D02*
X1261268Y291136D01*
G01X1253886Y290005D02*
X1254624Y289817D01*
G01X1252779Y286235D02*
X1252041Y286424D01*
G01X1254809Y290759D02*
X1253886Y290947D01*
G01X1251856Y285482D02*
X1252779Y285293D01*
G01X1253886Y286235D02*
X1252779D01*
G01Y285293D02*
X1253886D01*
G01X1259054D02*
X1258131D01*
G01X1255732Y290193D02*
X1254809Y290759D01*
G01X1248165Y287932D02*
X1244659Y289817D01*
G01X1260715Y290382D02*
X1260345Y290570D01*
G01X1245951Y289817D02*
X1248534Y288497D01*
G01X1254624Y289817D02*
X1255178Y289439D01*
G01X1252041Y286424D02*
X1251487Y286801D01*
G01X1250933Y286047D02*
X1251856Y285482D01*
G01X1260899Y290193D02*
X1260715Y290382D01*
G01X1255178Y289439D02*
X1255547Y288874D01*
G01X1248165Y291701D02*
X1248534Y291136D01*
G01X1256285Y289439D02*
X1255732Y290193D01*
G01X1250380Y286801D02*
X1250933Y286047D01*
G01X1251487Y286801D02*
X1251118Y287555D01*
G01X1250011D02*
X1250380Y286801D01*
G01X1255547Y288874D02*
X1255732Y288309D01*
G01X1256654Y288497D02*
X1256285Y289439D01*
G01X1259054Y290005D02*
Y285293D01*
G01Y291324D02*
Y290759D01*
G01X1258131Y285293D02*
Y291324D01*
G01X1256654Y287743D02*
Y288497D01*
G01X1256285Y293209D02*
Y294151D01*
G01X1255732Y288309D02*
Y287932D01*
G01X1250933Y290193D02*
Y293209D01*
G01X1250011Y294151D02*
Y289251D01*
G01X1256285Y286801D02*
X1256654Y287743D01*
G01X1255732Y287932D02*
X1255547Y287366D01*
G01X1255732Y286047D02*
X1256285Y286801D01*
G01X1255547Y287366D02*
X1255178Y286801D01*
G01X1248534Y288497D02*
X1248165Y287932D01*
G01X1259422Y290382D02*
X1259054Y290005D01*
G01Y290759D02*
X1259422Y291136D01*
G01X1259976Y290570D02*
X1259422Y290382D01*
G01Y291136D02*
X1259976Y291324D01*
G01X1248534Y291136D02*
X1245951Y289817D01*
G01X1244659D02*
X1248165Y291701D01*
G01X1254809Y285482D02*
X1255732Y286047D01*
G01X1251856Y290759D02*
X1250933Y290193D01*
G01X1255178Y286801D02*
X1254624Y286424D01*
G01X1251302Y289251D02*
X1252041Y289817D01*
G01X1256285Y294151D02*
X1250011D01*
G01X1262922Y-574484D02*
Y-664614D01*
G01X1266589Y-619802D02*
X1680245D01*
G01X1279698Y-587155D02*
Y-607155D01*
G01X1273948Y-587155D02*
X1285448D01*
G01X1295448Y-607155D02*
Y-587155D01*
G01Y-596821D02*
X1296698Y-595155D01*
X1297948Y-594155D01*
X1299948Y-593822D01*
X1301448Y-594155D01*
X1303198Y-595488D01*
X1303948Y-597489D01*
Y-607155D01*
G01X1319698Y-593822D02*
Y-607155D01*
G01Y-588489D02*
X1319198Y-588155D01*
Y-587488D01*
X1319698Y-587155D01*
X1320198Y-587488D01*
Y-588155D01*
X1319698Y-588489D01*
G01X1343698Y-595488D02*
X1341948Y-594155D01*
X1340448Y-593822D01*
X1338448Y-594489D01*
X1336948Y-595822D01*
X1335948Y-598155D01*
X1335698Y-600489D01*
X1335948Y-602822D01*
X1336948Y-604822D01*
X1338448Y-606488D01*
X1340448Y-607155D01*
X1342198Y-606488D01*
X1343698Y-605155D01*
G01X1355448Y-607155D02*
Y-587155D01*
G01X1363448Y-593822D02*
X1355448Y-601488D01*
G01X1358698Y-598488D02*
X1363948Y-607155D01*
G01X1375448D02*
Y-593822D01*
G01Y-597155D02*
X1376448Y-595488D01*
X1377948Y-594155D01*
X1379948Y-593822D01*
X1381698Y-594155D01*
X1383198Y-595488D01*
X1383948Y-597822D01*
Y-607155D01*
G01X1395948Y-598155D02*
X1403948D01*
X1403198Y-595822D01*
X1401948Y-594489D01*
X1400198Y-593822D01*
X1398448Y-594155D01*
X1396948Y-595155D01*
X1395948Y-597489D01*
X1395448Y-599489D01*
Y-601488D01*
X1395948Y-603489D01*
X1397198Y-605489D01*
X1398698Y-606822D01*
X1400448Y-607155D01*
X1402198Y-606488D01*
X1403948Y-604489D01*
G01X1415948Y-604822D02*
X1417198Y-606155D01*
X1418948Y-607155D01*
X1420448D01*
X1421948Y-606488D01*
X1422948Y-605489D01*
X1423448Y-604156D01*
X1423198Y-602155D01*
X1422198Y-601155D01*
X1417698Y-599155D01*
X1416698Y-596821D01*
X1417198Y-595155D01*
X1418198Y-594155D01*
X1419698Y-593822D01*
X1421198Y-594155D01*
X1422698Y-595155D01*
G01X1435948Y-604822D02*
X1437198Y-606155D01*
X1438948Y-607155D01*
X1440448D01*
X1441948Y-606488D01*
X1442948Y-605489D01*
X1443448Y-604156D01*
X1443198Y-602155D01*
X1442198Y-601155D01*
X1437698Y-599155D01*
X1436698Y-596821D01*
X1437198Y-595155D01*
X1438198Y-594155D01*
X1439698Y-593822D01*
X1441198Y-594155D01*
X1442698Y-595155D01*
G01X1261559Y-101243D02*
Y-105574D01*
G01X1265457D02*
X1264482Y-103408D01*
G01X1266431Y-105574D02*
X1265457D01*
G01X1267406Y-104852D02*
X1266431Y-105574D01*
G01X1268380Y-103408D02*
X1267406Y-104852D01*
G01X1268380Y-101965D02*
Y-103408D01*
G01X1276175Y-101965D02*
Y-103408D01*
G01X1272278D02*
Y-101965D01*
G01X1273252Y-104852D02*
X1272278Y-103408D01*
G01X1274226Y-105574D02*
X1273252Y-104852D01*
G01X1275201D02*
X1274226Y-105574D01*
G01X1276175Y-103408D02*
X1275201Y-104852D01*
G01X1264482Y-99799D02*
Y-108461D01*
G01X1267406Y-100521D02*
X1268380Y-101965D01*
G01X1266431Y-99799D02*
X1267406Y-100521D01*
G01X1265457D02*
X1266431Y-99799D01*
G01X1264482Y-101965D02*
X1265457Y-100521D01*
G01X1275201D02*
X1276175Y-101965D01*
G01X1274226Y-99799D02*
X1275201Y-100521D01*
G01X1273252D02*
X1274226Y-99799D01*
G01X1272278Y-101965D02*
X1273252Y-100521D01*
G01X1271233Y291324D02*
X1271972D01*
G01X1268281D02*
X1269019D01*
G01X1266435D02*
X1267358D01*
G01X1262929D02*
X1263667D01*
G01X1263298Y290570D02*
X1262745D01*
G01X1268650D02*
X1268281D01*
G01X1271603D02*
X1271049D01*
G01X1271972Y290382D02*
X1271603Y290570D01*
G01X1271972Y291324D02*
X1272526Y291136D01*
G01X1269019Y291324D02*
X1269573Y291136D01*
G01X1263667Y291324D02*
X1264221Y291136D01*
G01X1262006Y285293D02*
X1261083D01*
G01X1264959D02*
X1264036D01*
G01X1267358D02*
X1266435D01*
G01X1270311D02*
X1269388D01*
G01X1273263D02*
X1272341D01*
G01X1269019Y290382D02*
X1268650Y290570D01*
G01X1263667Y290382D02*
X1263298Y290570D01*
G01X1272526Y291136D02*
X1272895Y290759D01*
G01X1272156Y290193D02*
X1271972Y290382D01*
G01X1269573Y291136D02*
X1270126Y290570D01*
G01X1269204Y290193D02*
X1269019Y290382D01*
G01X1264221Y291136D02*
X1264590Y290759D01*
G01X1263852Y290193D02*
X1263667Y290382D01*
G01X1261268Y291136D02*
X1261822Y290570D01*
G01X1272341Y289817D02*
X1272156Y290193D01*
G01X1269388Y289817D02*
X1269204Y290193D01*
G01X1272895Y290759D02*
X1273263Y289817D01*
G01X1264590Y290759D02*
X1264959Y289817D01*
G01X1264036D02*
X1263852Y290193D01*
G01X1261083Y289817D02*
X1260899Y290193D01*
G01X1273263Y289817D02*
Y285293D01*
G01X1272341D02*
Y289817D01*
G01X1270311D02*
Y285293D01*
G01X1269388D02*
Y289817D01*
G01X1267358Y290005D02*
Y285293D01*
G01Y291324D02*
Y290759D01*
G01X1266435Y285293D02*
Y291324D01*
G01X1264959Y289817D02*
Y285293D01*
G01X1264036D02*
Y289817D01*
G01X1262006D02*
Y285293D01*
G01X1261083D02*
Y289817D01*
G01X1270495Y290193D02*
X1270311Y289817D01*
G01X1262191Y290193D02*
X1262006Y289817D01*
G01X1270680Y290382D02*
X1270495Y290193D01*
G01X1270126Y290570D02*
X1270680Y291136D01*
G01X1267727Y290382D02*
X1267358Y290005D01*
G01Y290759D02*
X1267727Y291136D01*
G01X1262375Y290382D02*
X1262191Y290193D01*
G01X1261822Y290570D02*
X1262375Y291136D01*
G01X1270680D02*
X1271233Y291324D01*
G01X1268281Y290570D02*
X1267727Y290382D01*
G01Y291136D02*
X1268281Y291324D01*
G01X1262375Y291136D02*
X1262929Y291324D01*
G01X1271049Y290570D02*
X1270680Y290382D01*
G01X1262745Y290570D02*
X1262375Y290382D01*
G01X1283483Y-101243D02*
Y-105574D01*
G01X1287868Y-103408D02*
Y-101965D01*
G01X1288843Y-104852D02*
X1287868Y-103408D01*
G01X1289817Y-105574D02*
X1288843Y-104852D01*
G01X1290791D02*
X1289817Y-105574D01*
G01X1291279Y-104130D02*
X1290791Y-104852D01*
G01X1280560Y-105574D02*
Y-99799D01*
G01X1282509D02*
X1283483Y-101243D01*
G01X1281535Y-99799D02*
X1282509D01*
G01X1280560Y-101243D02*
X1281535Y-99799D01*
G01X1291279Y-101965D02*
X1287868D01*
G01X1290791Y-100521D02*
X1291279Y-101965D01*
G01X1289817Y-99799D02*
X1290791Y-100521D01*
G01X1288843D02*
X1289817Y-99799D01*
G01X1287868Y-101965D02*
X1288843Y-100521D01*
G01X1303867Y-740940D02*
Y-758263D01*
G01X1299074Y-101243D02*
Y-105574D01*
G01X1305408D02*
Y-96912D01*
G01X1296151Y-105574D02*
Y-99799D01*
G01X1298100D02*
X1299074Y-101243D01*
G01X1297125Y-99799D02*
X1298100D01*
G01X1296151Y-101243D02*
X1297125Y-99799D01*
G01X1303946Y-100521D02*
X1306869D01*
G01X1303867Y619690D02*
Y602367D01*
G01X1316772Y-655863D02*
Y-635863D01*
X1321772D01*
X1323772Y-636863D01*
X1325272Y-638196D01*
X1326522Y-640196D01*
X1327522Y-642530D01*
X1327772Y-645863D01*
X1327522Y-649197D01*
X1326522Y-651530D01*
X1325272Y-653530D01*
X1323772Y-654863D01*
X1321772Y-655863D01*
X1316772D01*
G01X1346772D02*
Y-642530D01*
G01Y-644863D02*
X1345772Y-643530D01*
X1344272Y-642863D01*
X1342522Y-642530D01*
X1340772Y-643197D01*
X1339272Y-644530D01*
X1338272Y-646530D01*
X1337772Y-649197D01*
X1338272Y-651863D01*
X1339272Y-653863D01*
X1340772Y-655196D01*
X1342522Y-655863D01*
X1344272Y-655530D01*
X1345772Y-654530D01*
X1346772Y-653197D01*
G01X1362272Y-635863D02*
Y-655863D01*
G01X1358772Y-642530D02*
X1365772D01*
G01X1378522Y-646863D02*
X1386522D01*
X1385772Y-644530D01*
X1384522Y-643197D01*
X1382772Y-642530D01*
X1381022Y-642863D01*
X1379522Y-643863D01*
X1378522Y-646197D01*
X1378022Y-648197D01*
Y-650196D01*
X1378522Y-652197D01*
X1379772Y-654197D01*
X1381272Y-655530D01*
X1383022Y-655863D01*
X1384772Y-655196D01*
X1386522Y-653197D01*
G01X1320511Y-105574D02*
X1319537Y-104852D01*
G01X1321485Y-105574D02*
X1320511D01*
G01X1322460Y-104852D02*
X1321485Y-105574D01*
G01X1322947Y-104130D02*
X1322460Y-104852D01*
G01X1322947Y-102686D02*
Y-104130D01*
G01X1322460Y-101965D02*
X1322947Y-102686D01*
G01X1319537Y-104852D02*
X1318562Y-103408D01*
G01X1321485Y-101243D02*
X1322460Y-101965D01*
G01X1320511Y-100521D02*
X1321485Y-101243D01*
G01X1319537Y-99799D02*
X1320511Y-100521D01*
G01X1319049Y-99078D02*
X1319537Y-99799D01*
G01X1319049Y-98355D02*
Y-99078D01*
G01X1319537Y-97634D02*
X1319049Y-98355D01*
G01X1320511Y-96912D02*
X1319537Y-97634D01*
G01X1321485Y-96912D02*
X1320511D01*
G01X1322460Y-97634D02*
X1321485Y-96912D01*
G01X1322947Y-98355D02*
X1322460Y-97634D01*
G01X1323596Y-69408D02*
Y-65023D01*
G01X1317100Y-65997D02*
X1323596Y-69408D01*
G01X1325039Y-76716D02*
X1324318Y-77203D01*
G01X1325761Y-75741D02*
X1325039Y-76716D01*
G01X1325761Y-74767D02*
Y-75741D01*
G01X1325039Y-73792D02*
X1325761Y-74767D01*
G01X1324318Y-73305D02*
X1325039Y-73792D01*
G01X1322874Y-72818D02*
X1324318Y-73305D01*
G01X1321430D02*
X1322874Y-72818D01*
G01X1320709Y-73792D02*
X1321430Y-73305D01*
G01X1319987Y-74767D02*
X1320709Y-73792D01*
G01X1319987Y-75741D02*
Y-74767D01*
G01X1320709Y-76716D02*
X1319987Y-75741D01*
G01X1317100Y-76229D02*
X1320709Y-76716D01*
G01X1317100Y-73305D02*
Y-76229D01*
G01X1325761Y-65997D02*
X1317100D01*
G01X1321430Y-53330D02*
X1320709Y-52355D01*
G01X1322152Y-53817D02*
X1321430Y-53330D01*
G01X1322874Y-54304D02*
X1322152Y-53817D01*
G01X1323596Y-54304D02*
X1322874D01*
G01X1325039Y-60151D02*
X1325761Y-59664D01*
G01Y-60151D02*
X1325039D01*
G01X1325761Y-59664D02*
Y-60151D01*
G01X1317822Y-53330D02*
X1317100Y-52355D01*
G01X1318543Y-53817D02*
X1317822Y-53330D01*
G01X1319265Y-53817D02*
X1318543D01*
G01X1319987Y-53330D02*
X1319265Y-53817D01*
G01X1320709Y-52355D02*
X1319987Y-53330D01*
G01X1325039D02*
X1323596Y-54304D01*
G01X1325761Y-52355D02*
X1325039Y-53330D01*
G01X1321430Y-50407D02*
X1322874Y-49432D01*
G01X1320709Y-51381D02*
X1321430Y-50407D01*
G01X1320709Y-52355D02*
Y-51381D01*
G01X1325761D02*
Y-52355D01*
G01X1325039Y-50407D02*
X1325761Y-51381D01*
G01X1324318Y-49920D02*
X1325039Y-50407D01*
G01X1323596Y-49432D02*
X1324318Y-49920D01*
G01X1322874Y-49432D02*
X1323596D01*
G01X1325039Y-45535D02*
X1324318Y-46022D01*
G01X1325761Y-44560D02*
X1325039Y-45535D01*
G01X1325761Y-43586D02*
Y-44560D01*
G01X1325039Y-42611D02*
X1325761Y-43586D01*
G01X1324318Y-42124D02*
X1325039Y-42611D01*
G01X1322874Y-41637D02*
X1324318Y-42124D01*
G01X1321430D02*
X1322874Y-41637D01*
G01X1320709Y-42611D02*
X1321430Y-42124D01*
G01X1319987Y-43586D02*
X1320709Y-42611D01*
G01X1319987Y-44560D02*
Y-43586D01*
G01X1320709Y-45535D02*
X1319987Y-44560D01*
G01X1317100Y-45048D02*
X1320709Y-45535D01*
G01X1317100Y-42124D02*
Y-45048D01*
G01X1319987Y-50407D02*
X1320709Y-51381D01*
G01X1319265Y-49920D02*
X1319987Y-50407D01*
G01X1318543Y-49920D02*
X1319265D01*
G01X1317822Y-50407D02*
X1318543Y-49920D01*
G01X1317100Y-51381D02*
X1317822Y-50407D01*
G01X1317100Y-52355D02*
Y-51381D01*
G01X1327926Y243088D02*
G03X1320052Y250962I-7874J0D01*
G01X1327926Y243088D02*
G03X1320052Y250962I-7874J0D01*
G01X1334640Y-103408D02*
Y-101965D01*
G01X1335614Y-104852D02*
X1334640Y-103408D01*
G01X1336589Y-105574D02*
X1335614Y-104852D01*
G01X1337563D02*
X1336589Y-105574D01*
G01X1338537Y-103408D02*
X1337563Y-104852D01*
G01X1342435Y-103408D02*
Y-101965D01*
G01X1343409Y-104852D02*
X1342435Y-103408D01*
G01X1338537Y-96912D02*
Y-105574D01*
G01X1328793Y-99799D02*
Y-105574D01*
G01X1337563Y-100521D02*
X1338537Y-101965D01*
G01X1336589Y-99799D02*
X1337563Y-100521D01*
G01X1335614D02*
X1336589Y-99799D01*
G01X1334640Y-101965D02*
X1335614Y-100521D01*
G01X1345846Y-101965D02*
X1342435D01*
G01D02*
X1343409Y-100521D01*
G01X1328793Y-96912D02*
Y-97634D01*
G01X1327926Y-11046D02*
Y-35845D01*
G01X1364737Y2734D02*
G03X1333242I-15747J0D01*
G03X1364737I15747J0D01*
G01X1327926Y-7109D02*
G03X1335800Y-14983I7874J0D01*
G01X1327926Y-7109D02*
G03X1335800Y-14983I7874J0D01*
G01X1327926Y-7109D02*
Y243088D01*
G01Y-7109D02*
Y244072D01*
G01X1335800Y-14983D02*
X1459422D01*
G01X1335800D02*
X1459422D01*
G01X1355978Y2734D02*
G03X1342001I-6989J0D01*
G03X1355978I6988J0D01*
G01X1327926Y42891D02*
X1431076D01*
G01X1342336Y87033D02*
X1347011Y89546D01*
G01X1340367Y92813D02*
Y81002D01*
G01X1338891Y88038D02*
Y92813D01*
G01Y81002D02*
Y86530D01*
G01X1332001D02*
Y81002D01*
G01Y92813D02*
Y88038D01*
G01X1330525Y81002D02*
Y92813D01*
G01X1347011Y84520D02*
X1342336Y87033D01*
G01X1338891Y92813D02*
X1340367D01*
G01X1330525D02*
X1332001D01*
G01Y88038D02*
X1338891D01*
G01Y86530D02*
X1332001D01*
G01Y81002D02*
X1330525D01*
G01X1340367D02*
X1338891D01*
G01X1378517Y135411D02*
X1327926D01*
G01Y151553D02*
X1378517D01*
G01X1345909Y199599D02*
X1341233Y202112D01*
G01X1342956D02*
X1346401Y200352D01*
G01X1337789Y207891D02*
X1339265D01*
G01X1329422D02*
X1330899D01*
G01Y203117D02*
X1337789D01*
G01X1339265Y207891D02*
Y196080D01*
G01X1337789Y203117D02*
Y207891D01*
G01Y196080D02*
Y201609D01*
G01X1330899D02*
Y196080D01*
G01Y207891D02*
Y203117D01*
G01X1329422Y196080D02*
Y207891D01*
G01X1337789Y201609D02*
X1330899D01*
G01Y196080D02*
X1329422D01*
G01X1339265D02*
X1337789D01*
G01X1346401Y203871D02*
X1342956Y202112D01*
G01X1341233D02*
X1345909Y204624D01*
G01X1327926Y244072D02*
X1378517D01*
G01X1344384Y-105574D02*
X1343409Y-104852D01*
G01X1345358D02*
X1344384Y-105574D01*
G01X1345846Y-104130D02*
X1345358Y-104852D01*
G01Y-100521D02*
X1345846Y-101965D01*
G01X1344384Y-99799D02*
X1345358Y-100521D01*
G01X1343409D02*
X1344384Y-99799D01*
G01X1358601Y30306D02*
Y26159D01*
G01X1357493D02*
Y35017D01*
G01X1358601Y26159D02*
X1357493D01*
G01X1358601Y35017D02*
Y31437D01*
G01X1357493Y35017D02*
X1358601D01*
G01Y31437D02*
X1363768D01*
G01Y30306D02*
X1358601D01*
G01X1359314Y88038D02*
X1360052Y88792D01*
G01X1356115Y87787D02*
X1355623Y87284D01*
G01Y88289D02*
X1356115Y88792D01*
G01X1356854Y88038D02*
X1356115Y87787D01*
G01Y88792D02*
X1356854Y89043D01*
G01X1347503Y88792D02*
X1344058Y87033D01*
G01X1350948Y90802D02*
X1349472Y89043D01*
G01Y91054D02*
X1350948Y92813D01*
G01X1347503Y85274D02*
X1347011Y84520D01*
G01X1359806Y87535D02*
X1359560Y87033D01*
G01D02*
Y81002D01*
G01X1358330D02*
Y87033D01*
G01X1355623Y87284D02*
Y81002D01*
G01Y89043D02*
Y88289D01*
G01X1354393Y81002D02*
Y89043D01*
G01X1352424Y92813D02*
Y81002D01*
G01X1350948D02*
Y90802D01*
G01X1349472Y89043D02*
Y91054D01*
G01X1358330Y87033D02*
X1358084Y87535D01*
G01X1347011Y89546D02*
X1347503Y88792D01*
G01X1358576D02*
X1359314Y88038D01*
G01X1358084Y87535D02*
X1357838Y87787D01*
G01D02*
X1357346Y88038D01*
G01X1344058Y87033D02*
X1347503Y85274D01*
G01X1357838Y89043D02*
X1358576Y88792D01*
G01X1350948Y92813D02*
X1352424D01*
G01X1356854Y89043D02*
X1357838D01*
G01X1354393D02*
X1355623D01*
G01X1357346Y88038D02*
X1356854D01*
G01X1352424Y81002D02*
X1350948D01*
G01X1355623D02*
X1354393D01*
G01X1359560D02*
X1358330D01*
G01X1357228Y202112D02*
X1356982Y202614D01*
G01X1345909Y204624D02*
X1346401Y203871D01*
G01X1357474D02*
X1358212Y203117D01*
G01X1356982Y202614D02*
X1356735Y202865D01*
G01X1358458Y202112D02*
Y196080D01*
G01X1357228D02*
Y202112D01*
G01X1356735Y202865D02*
X1356243Y203117D01*
G01X1356735Y204122D02*
X1357474Y203871D01*
G01X1354521Y202363D02*
Y196080D01*
G01Y204122D02*
Y203368D01*
G01X1353291Y196080D02*
Y204122D01*
G01X1351322Y207891D02*
Y196080D01*
G01X1349846D02*
Y205881D01*
G01X1348369Y204122D02*
Y206132D01*
G01X1349846Y207891D02*
X1351322D01*
G01X1359688Y204122D02*
X1360672D01*
G01X1355751D02*
X1356735D01*
G01X1353291D02*
X1354521D01*
G01X1356243Y203117D02*
X1355751D01*
G01X1360180D02*
X1359442D01*
G01X1358704Y202614D02*
X1358458Y202112D01*
G01X1351322Y196080D02*
X1349846D01*
G01X1354521D02*
X1353291D01*
G01X1358458D02*
X1357228D01*
G01X1358950Y202865D02*
X1358704Y202614D01*
G01X1358212Y203117D02*
X1358950Y203871D01*
G01X1355013Y202865D02*
X1354521Y202363D01*
G01Y203368D02*
X1355013Y203871D01*
G01X1349846Y205881D02*
X1348369Y204122D01*
G01Y206132D02*
X1349846Y207891D01*
G01X1346401Y200352D02*
X1345909Y199599D01*
G01X1358950Y203871D02*
X1359688Y204122D01*
G01X1355751Y203117D02*
X1355013Y202865D01*
G01Y203871D02*
X1355751Y204122D01*
G01X1359442Y203117D02*
X1358950Y202865D01*
G01X1375210Y26348D02*
X1376133Y26913D01*
G01X1375026Y27290D02*
X1375579Y27667D01*
G01X1376133Y26913D02*
X1376686Y27478D01*
G01X1375579Y27667D02*
X1376317Y28798D01*
G01X1370781Y31437D02*
Y29740D01*
G01X1369304Y29929D02*
Y29175D01*
G01X1366352D02*
Y29929D01*
G01X1364875Y35017D02*
Y26159D01*
G01X1363768D02*
Y30306D01*
G01X1371704Y29929D02*
X1371888Y28798D01*
G01X1370781Y29740D02*
X1370965Y28798D01*
G01D02*
X1371150Y28232D01*
G01D02*
X1371519Y27478D01*
G01X1371888Y28798D02*
X1372626Y27667D01*
G01X1371519Y27478D02*
X1372073Y26913D01*
G01X1372626Y27667D02*
X1373180Y27290D01*
G01X1372073Y26913D02*
X1372995Y26348D01*
G01X1373180Y27290D02*
X1374103Y27102D01*
G01X1372995Y26348D02*
X1374103Y26159D01*
G01X1369304Y29175D02*
X1366352D01*
G01X1364875Y26159D02*
X1363768D01*
G01X1374103D02*
X1375210Y26348D01*
G01X1374103Y27102D02*
X1375026Y27290D01*
G01X1372995Y34829D02*
X1372073Y34263D01*
G01X1373180Y33887D02*
X1372626Y33510D01*
G01X1372073Y34263D02*
X1371519Y33698D01*
G01X1372626Y33510D02*
X1371888Y32379D01*
G01X1371519Y33698D02*
X1371150Y32944D01*
G01D02*
X1370965Y32379D01*
G01D02*
X1370781Y31437D01*
G01X1371888Y32379D02*
X1371704Y31248D01*
G01X1373399Y48265D02*
Y45805D01*
G01X1371704Y31248D02*
Y29929D01*
G01X1369304Y32191D02*
Y31437D01*
G01X1367887Y132419D02*
Y45805D01*
G01X1366352Y31437D02*
Y32191D01*
G01X1363768Y31437D02*
Y35017D01*
G01X1376317Y32379D02*
X1375579Y33510D01*
G01X1376686Y33698D02*
X1376133Y34263D01*
G01X1375579Y33510D02*
X1375026Y33887D01*
G01X1376133Y34263D02*
X1375210Y34829D01*
G01X1375026Y33887D02*
X1374103Y34075D01*
G01X1375210Y34829D02*
X1374103Y35017D01*
G01X1367887Y45805D02*
X1399186D01*
G01X1363768Y35017D02*
X1364875D01*
G01X1366352Y32191D02*
X1369304D01*
G01Y31437D02*
X1366352D01*
G01Y29929D02*
X1369304D01*
G01X1374103Y35017D02*
X1372995Y34829D01*
G01X1374103Y34075D02*
X1373180Y33887D01*
G01X1366706Y54072D02*
G03X1366509Y53876I0J-197D01*
G01Y53482D02*
G03X1366706Y53285I197J0D01*
G01Y56041D02*
G03X1366509Y55844I0J-197D01*
G01Y55450D02*
G03X1366706Y55254I197J1D01*
G01Y58009D02*
G03X1366509Y57813I0J-197D01*
G01Y57419D02*
G03X1366706Y57222I197J0D01*
G01Y59978D02*
G03X1366509Y59781I0J-197D01*
G01Y59387D02*
G03X1366706Y59191I197J1D01*
G01X1374580Y49446D02*
G03X1373399Y48265I0J-1181D01*
G01X1366509Y53876D02*
Y53482D01*
G01Y55844D02*
Y55450D01*
G01Y57813D02*
Y57419D01*
G01Y59781D02*
Y59387D01*
G01X1367887Y59978D02*
X1366706D01*
G01Y59191D02*
X1367887D01*
G01Y58009D02*
X1366706D01*
G01Y57222D02*
X1367887D01*
G01Y56041D02*
X1366706D01*
G01Y55254D02*
X1367887D01*
G01Y54072D02*
X1366706D01*
G01Y53285D02*
X1367887D01*
G01X1377336Y49446D02*
X1374580D01*
G01X1377336Y48265D02*
X1373399D01*
G01X1366706Y75726D02*
G03X1366509Y75529I0J-197D01*
G01X1366706Y77695D02*
G03X1366509Y77498I0J-197D01*
G01Y77104D02*
G03X1366706Y76907I197J0D01*
G01X1366509Y79072D02*
G03X1366706Y78876I197J1D01*
G01Y69820D02*
G03X1366509Y69624I0J-197D01*
G01Y69230D02*
G03X1366706Y69033I197J0D01*
G01Y71789D02*
G03X1366509Y71592I0J-197D01*
G01Y71198D02*
G03X1366706Y71002I197J1D01*
G01Y73758D02*
G03X1366509Y73561I0J-197D01*
G01Y73167D02*
G03X1366706Y72970I197J0D01*
G01X1366509Y75135D02*
G03X1366706Y74939I197J1D01*
G01X1375564Y67163D02*
G03Y62832I0J-2165D01*
G01X1366509Y69624D02*
Y69230D01*
G01Y71592D02*
Y71198D01*
G01Y73561D02*
Y73167D01*
G01Y75529D02*
Y75135D01*
G01Y77498D02*
Y77104D01*
G01Y79466D02*
Y79072D01*
G01X1366706Y78876D02*
X1367887D01*
G01Y77695D02*
X1366706D01*
G01Y76907D02*
X1367887D01*
G01Y75726D02*
X1366706D01*
G01Y74939D02*
X1367887D01*
G01Y73758D02*
X1366706D01*
G01Y72970D02*
X1367887D01*
G01Y71789D02*
X1366706D01*
G01Y71002D02*
X1367887D01*
G01Y69820D02*
X1366706D01*
G01Y69033D02*
X1367887D01*
G01X1377336Y67163D02*
X1375564D01*
G01Y62832D02*
X1377336D01*
G01X1366706Y79663D02*
G03X1366509Y79466I0J-197D01*
G01X1366706Y81632D02*
G03X1366509Y81435I0J-197D01*
G01Y81041D02*
G03X1366706Y80844I197J0D01*
G01Y83600D02*
G03X1366509Y83403I0J-197D01*
G01Y83009D02*
G03X1366706Y82813I197J1D01*
G01Y85569D02*
G03X1366509Y85372I0J-197D01*
G01Y84978D02*
G03X1366706Y84781I197J0D01*
G01Y87537D02*
G03X1366509Y87340I0J-197D01*
G01Y86946D02*
G03X1366706Y86750I197J1D01*
G01Y89506D02*
G03X1366509Y89309I0J-197D01*
G01Y88915D02*
G03X1366706Y88718I197J0D01*
G01Y91474D02*
G03X1366509Y91277I0J-197D01*
G01Y90883D02*
G03X1366706Y90687I197J1D01*
G01Y93443D02*
G03X1366509Y93246I0J-197D01*
G01Y92852D02*
G03X1366706Y92655I197J0D01*
G01Y95411D02*
G03X1366509Y95214I0J-197D01*
G01Y94820D02*
G03X1366706Y94624I197J1D01*
G01X1360545Y88038D02*
X1360052Y87787D01*
G01X1367188D02*
X1366944Y87537D01*
G01X1366696Y88289D02*
X1367116Y88718D01*
G01X1360052Y87787D02*
X1359806Y87535D01*
G01X1367926Y88038D02*
X1367188Y87787D01*
G01X1360052Y88792D02*
X1360791Y89043D01*
G01X1366696Y82813D02*
Y81632D01*
G01Y84781D02*
Y83600D01*
G01Y86750D02*
Y85569D01*
G01Y88718D02*
Y88289D01*
G01X1366509Y81435D02*
Y81041D01*
G01Y83403D02*
Y83009D01*
G01Y85372D02*
Y84978D01*
G01Y87340D02*
Y86946D01*
G01Y89309D02*
Y88915D01*
G01Y91277D02*
Y90883D01*
G01Y93246D02*
Y92852D01*
G01Y95214D02*
Y94820D01*
G01X1365466Y81002D02*
Y89043D01*
G01X1363497Y87033D02*
Y81002D01*
G01X1362267D02*
Y87033D01*
G01X1363005Y88289D02*
X1363497Y87033D01*
G01X1362267D02*
X1362021Y87535D01*
G01X1362513Y88792D02*
X1363005Y88289D01*
G01X1362021Y87535D02*
X1361775Y87787D01*
G01D02*
X1361283Y88038D01*
G01X1361775Y89043D02*
X1362513Y88792D01*
G01X1367887Y95411D02*
X1366706D01*
G01Y94624D02*
X1367887D01*
G01Y93443D02*
X1366706D01*
G01Y92655D02*
X1367887D01*
G01Y91474D02*
X1366706D01*
G01Y90687D02*
X1367887D01*
G01Y89506D02*
X1366706D01*
G01X1365466Y89043D02*
X1366509D01*
G01X1360791D02*
X1361775D01*
G01X1366706Y88718D02*
X1367887D01*
G01X1361283Y88038D02*
X1360545D01*
G01X1367887Y87537D02*
X1366706D01*
G01Y86750D02*
X1367887D01*
G01Y85569D02*
X1366706D01*
G01Y84781D02*
X1367887D01*
G01Y83600D02*
X1366706D01*
G01Y82813D02*
X1367887D01*
G01Y81632D02*
X1366706D01*
G01X1363497Y81002D02*
X1362267D01*
G01X1366509D02*
X1365466D01*
G01X1366706Y80844D02*
X1367887D01*
G01Y79663D02*
X1366706D01*
G01Y97380D02*
G03X1366509Y97183I0J-197D01*
G01Y96789D02*
G03X1366706Y96592I197J0D01*
G01Y99348D02*
G03X1366509Y99151I0J-197D01*
G01Y98758D02*
G03X1366706Y98561I197J0D01*
G01Y101317D02*
G03X1366509Y101120I0J-197D01*
G01Y100726D02*
G03X1366706Y100529I197J0D01*
G01Y103285D02*
G03X1366509Y103088I0J-197D01*
G01Y102695D02*
G03X1366706Y102498I197J0D01*
G01Y105254D02*
G03X1366509Y105057I0J-197D01*
G01Y104663D02*
G03X1366706Y104466I197J0D01*
G01Y107222D02*
G03X1366509Y107025I0J-197D01*
G01Y106632D02*
G03X1366706Y106435I197J0D01*
G01Y109191D02*
G03X1366509Y108994I0J-197D01*
G01Y108600D02*
G03X1366706Y108403I197J0D01*
G01Y111159D02*
G03X1366509Y110962I0J-197D01*
G01Y110569D02*
G03X1366706Y110372I197J0D01*
G01X1366509Y97183D02*
Y96789D01*
G01Y99151D02*
Y98758D01*
G01Y101120D02*
Y100726D01*
G01Y103088D02*
Y102695D01*
G01Y105057D02*
Y104663D01*
G01Y107025D02*
Y106632D01*
G01Y108994D02*
Y108600D01*
G01Y110962D02*
Y110569D01*
G01X1367887Y111159D02*
X1366706D01*
G01Y110372D02*
X1367887D01*
G01Y109191D02*
X1366706D01*
G01Y108403D02*
X1367887D01*
G01Y107222D02*
X1366706D01*
G01Y106435D02*
X1367887D01*
G01Y105254D02*
X1366706D01*
G01Y104466D02*
X1367887D01*
G01Y103285D02*
X1366706D01*
G01Y102498D02*
X1367887D01*
G01Y101317D02*
X1366706D01*
G01Y100529D02*
X1367887D01*
G01Y99348D02*
X1366706D01*
G01Y98561D02*
X1367887D01*
G01Y97380D02*
X1366706D01*
G01Y96592D02*
X1367887D01*
G01X1366706Y121002D02*
G03X1366509Y120805I0J-197D01*
G01Y120411D02*
G03X1366706Y120214I197J0D01*
G01Y122970D02*
G03X1366509Y122773I0J-197D01*
G01Y122380D02*
G03X1366706Y122183I197J0D01*
G01Y124939D02*
G03X1366509Y124742I0J-197D01*
G01Y124348D02*
G03X1366706Y124151I197J0D01*
G01Y113128D02*
G03X1366509Y112931I0J-197D01*
G01Y112537D02*
G03X1366706Y112340I197J0D01*
G01Y115096D02*
G03X1366509Y114899I0J-197D01*
G01Y114506D02*
G03X1366706Y114309I197J0D01*
G01Y117065D02*
G03X1366509Y116868I0J-197D01*
G01Y116474D02*
G03X1366706Y116277I197J0D01*
G01Y119033D02*
G03X1366509Y118836I0J-197D01*
G01Y118443D02*
G03X1366706Y118246I197J0D01*
G01X1366509Y112931D02*
Y112537D01*
G01Y114899D02*
Y114506D01*
G01Y116868D02*
Y116474D01*
G01Y118836D02*
Y118443D01*
G01Y120805D02*
Y120411D01*
G01Y122773D02*
Y122380D01*
G01Y124742D02*
Y124348D01*
G01X1367887Y124939D02*
X1366706D01*
G01Y124151D02*
X1367887D01*
G01Y122970D02*
X1366706D01*
G01Y122183D02*
X1367887D01*
G01Y121002D02*
X1366706D01*
G01Y120214D02*
X1367887D01*
G01Y119033D02*
X1366706D01*
G01Y118246D02*
X1367887D01*
G01Y117065D02*
X1366706D01*
G01Y116277D02*
X1367887D01*
G01Y115096D02*
X1366706D01*
G01Y114309D02*
X1367887D01*
G01Y113128D02*
X1366706D01*
G01Y112340D02*
X1367887D01*
G01X1373399Y129958D02*
G03X1374580Y128777I1181J0D01*
G01X1373399Y132419D02*
Y129958D01*
G01X1367887Y132419D02*
X1399186D01*
G01X1373399Y129958D02*
X1377336D01*
G01Y128777D02*
X1374580D01*
G01Y158108D02*
G03X1373399Y156927I0J-1181D01*
G01D02*
Y154466D01*
G01X1367887Y241080D02*
Y154466D01*
G01X1377336Y158108D02*
X1374580D01*
G01X1377336Y156927D02*
X1373399D01*
G01X1367887Y154466D02*
X1399186D01*
G01X1366706Y164702D02*
G03X1366509Y164506I0J-197D01*
G01Y164112D02*
G03X1366706Y163915I197J0D01*
G01Y166671D02*
G03X1366509Y166474I0J-197D01*
G01Y166080D02*
G03X1366706Y165883I197J0D01*
G01Y168639D02*
G03X1366509Y168443I0J-197D01*
G01Y168049D02*
G03X1366706Y167852I197J0D01*
G01X1366509Y177891D02*
G03X1366706Y177695I197J1D01*
G01X1375564Y175824D02*
G03Y171494I0J-2165D01*
G01X1366706Y162734D02*
G03X1366509Y162537I0J-197D01*
G01Y162143D02*
G03X1366706Y161946I197J0D01*
G01X1366509Y162537D02*
Y162143D01*
G01Y164506D02*
Y164112D01*
G01Y166474D02*
Y166080D01*
G01Y168443D02*
Y168049D01*
G01Y178285D02*
Y177891D01*
G01X1366706Y177695D02*
X1367887D01*
G01X1377336Y175824D02*
X1375564D01*
G01Y171494D02*
X1377336D01*
G01X1367887Y168639D02*
X1366706D01*
G01Y167852D02*
X1367887D01*
G01Y166671D02*
X1366706D01*
G01Y165883D02*
X1367887D01*
G01Y164702D02*
X1366706D01*
G01Y163915D02*
X1367887D01*
G01Y162734D02*
X1366706D01*
G01Y161946D02*
X1367887D01*
G01X1366706Y178482D02*
G03X1366509Y178285I0J-197D01*
G01X1366706Y180450D02*
G03X1366509Y180254I0J-197D01*
G01Y179860D02*
G03X1366706Y179663I197J0D01*
G01Y182419D02*
G03X1366509Y182222I0J-197D01*
G01Y181828D02*
G03X1366706Y181632I197J1D01*
G01Y184387D02*
G03X1366509Y184191I0J-197D01*
G01Y183797D02*
G03X1366706Y183600I197J0D01*
G01Y186356D02*
G03X1366509Y186159I0J-197D01*
G01Y185765D02*
G03X1366706Y185569I197J1D01*
G01Y188324D02*
G03X1366509Y188128I0J-197D01*
G01Y187734D02*
G03X1366706Y187537I197J0D01*
G01Y190293D02*
G03X1366509Y190096I0J-197D01*
G01Y189702D02*
G03X1366706Y189506I197J1D01*
G01Y192261D02*
G03X1366509Y192065I0J-197D01*
G01Y191671D02*
G03X1366706Y191474I197J0D01*
G01Y194230D02*
G03X1366509Y194033I0J-197D01*
G01Y193639D02*
G03X1366706Y193443I197J1D01*
G01X1366509Y180254D02*
Y179860D01*
G01Y182222D02*
Y181828D01*
G01Y184191D02*
Y183797D01*
G01Y186159D02*
Y185765D01*
G01Y188128D02*
Y187734D01*
G01Y190096D02*
Y189702D01*
G01Y192065D02*
Y191671D01*
G01Y194033D02*
Y193639D01*
G01X1367887Y194230D02*
X1366706D01*
G01Y193443D02*
X1367887D01*
G01Y192261D02*
X1366706D01*
G01Y191474D02*
X1367887D01*
G01Y190293D02*
X1366706D01*
G01Y189506D02*
X1367887D01*
G01Y188324D02*
X1366706D01*
G01Y187537D02*
X1367887D01*
G01Y186356D02*
X1366706D01*
G01Y185569D02*
X1367887D01*
G01Y184387D02*
X1366706D01*
G01Y183600D02*
X1367887D01*
G01Y182419D02*
X1366706D01*
G01Y181632D02*
X1367887D01*
G01Y180450D02*
X1366706D01*
G01Y179663D02*
X1367887D01*
G01Y178482D02*
X1366706D01*
G01Y204072D02*
G03X1366509Y203876I0J-197D01*
G01X1366706Y206041D02*
G03X1366509Y205844I0J-197D01*
G01Y205450D02*
G03X1366706Y205254I197J1D01*
G01Y208009D02*
G03X1366509Y207813I0J-197D01*
G01Y207419D02*
G03X1366706Y207222I197J0D01*
G01Y209978D02*
G03X1366509Y209781I0J-197D01*
G01Y209387D02*
G03X1366706Y209191I197J1D01*
G01X1366509Y211356D02*
G03X1366706Y211159I197J0D01*
G01Y196198D02*
G03X1366509Y196002I0J-197D01*
G01Y195608D02*
G03X1366706Y195411I197J0D01*
G01Y198167D02*
G03X1366509Y197970I0J-197D01*
G01Y197576D02*
G03X1366706Y197380I197J1D01*
G01Y200135D02*
G03X1366509Y199939I0J-197D01*
G01Y199545D02*
G03X1366706Y199348I197J0D01*
G01Y202104D02*
G03X1366509Y201907I0J-197D01*
G01Y201513D02*
G03X1366706Y201317I197J1D01*
G01X1366509Y203482D02*
G03X1366706Y203285I197J0D01*
G01X1361903Y203368D02*
X1362395Y202112D01*
G01X1361165D02*
X1360919Y202614D01*
G01X1367887Y202785D02*
X1367808Y202865D01*
G01X1361411Y203871D02*
X1361903Y203368D01*
G01X1360919Y202614D02*
X1360672Y202865D01*
G01X1366509Y196002D02*
Y195608D01*
G01Y197970D02*
Y197576D01*
G01Y199939D02*
Y199545D01*
G01Y201907D02*
Y201513D01*
G01Y203876D02*
Y203482D01*
G01Y205844D02*
Y205450D01*
G01Y207813D02*
Y207419D01*
G01Y209781D02*
Y209387D01*
G01X1365594Y202363D02*
Y196080D01*
G01Y204122D02*
Y203368D01*
G01X1364363Y196080D02*
Y204122D01*
G01X1362395Y202112D02*
Y196080D01*
G01X1361165D02*
Y202112D01*
G01X1367808Y202865D02*
X1367316Y203117D01*
G01X1360672Y202865D02*
X1360180Y203117D01*
G01X1367808Y204122D02*
X1367887Y204095D01*
G01X1360672Y204122D02*
X1361411Y203871D01*
G01X1366706Y211159D02*
X1367887D01*
G01Y209978D02*
X1366706D01*
G01Y209191D02*
X1367887D01*
G01Y208009D02*
X1366706D01*
G01Y207222D02*
X1367887D01*
G01Y206041D02*
X1366706D01*
G01Y205254D02*
X1367887D01*
G01X1366824Y204122D02*
X1367808D01*
G01X1364363D02*
X1365594D01*
G01X1367887Y204072D02*
X1366706D01*
G01Y203285D02*
X1367887D01*
G01X1367316Y203117D02*
X1366824D01*
G01X1367887Y202104D02*
X1366706D01*
G01Y201317D02*
X1367887D01*
G01Y200135D02*
X1366706D01*
G01Y199348D02*
X1367887D01*
G01Y198167D02*
X1366706D01*
G01Y197380D02*
X1367887D01*
G01Y196198D02*
X1366706D01*
G01X1362395Y196080D02*
X1361165D01*
G01X1365594D02*
X1364363D01*
G01X1366706Y195411D02*
X1367887D01*
G01X1366086Y202865D02*
X1365594Y202363D01*
G01Y203368D02*
X1366086Y203871D01*
G01X1366824Y203117D02*
X1366086Y202865D01*
G01X1366703Y204081D02*
X1366824Y204122D01*
G01X1366086Y203871D02*
X1366626Y204054D01*
G01X1366706Y211946D02*
G03X1366509Y211750I0J-197D01*
G01X1366706Y213915D02*
G03X1366509Y213718I0J-197D01*
G01Y213324D02*
G03X1366706Y213128I197J1D01*
G01Y215883D02*
G03X1366509Y215687I0J-197D01*
G01Y215293D02*
G03X1366706Y215096I197J0D01*
G01Y217852D02*
G03X1366509Y217655I0J-197D01*
G01Y217261D02*
G03X1366706Y217065I197J1D01*
G01Y219820D02*
G03X1366509Y219624I0J-197D01*
G01Y219230D02*
G03X1366706Y219033I197J0D01*
G01Y221789D02*
G03X1366509Y221592I0J-197D01*
G01Y221198D02*
G03X1366706Y221002I197J1D01*
G01Y223758D02*
G03X1366509Y223561I0J-197D01*
G01Y223167D02*
G03X1366706Y222970I197J0D01*
G01Y225726D02*
G03X1366509Y225529I0J-197D01*
G01Y225135D02*
G03X1366706Y224939I197J1D01*
G01Y227695D02*
G03X1366509Y227498I0J-197D01*
G01Y227104D02*
G03X1366706Y226907I197J0D01*
G01X1366509Y211750D02*
Y211356D01*
G01Y213718D02*
Y213324D01*
G01Y215687D02*
Y215293D01*
G01Y217655D02*
Y217261D01*
G01Y219624D02*
Y219230D01*
G01Y221592D02*
Y221198D01*
G01Y223561D02*
Y223167D01*
G01Y225529D02*
Y225135D01*
G01Y227498D02*
Y227104D01*
G01X1367887Y227695D02*
X1366706D01*
G01Y226907D02*
X1367887D01*
G01Y225726D02*
X1366706D01*
G01Y224939D02*
X1367887D01*
G01Y223758D02*
X1366706D01*
G01Y222970D02*
X1367887D01*
G01Y221789D02*
X1366706D01*
G01Y221002D02*
X1367887D01*
G01Y219820D02*
X1366706D01*
G01Y219033D02*
X1367887D01*
G01Y217852D02*
X1366706D01*
G01Y217065D02*
X1367887D01*
G01Y215883D02*
X1366706D01*
G01Y215096D02*
X1367887D01*
G01Y213915D02*
X1366706D01*
G01Y213128D02*
X1367887D01*
G01Y211946D02*
X1366706D01*
G01Y229663D02*
G03X1366509Y229466I0J-197D01*
G01Y229072D02*
G03X1366706Y228876I197J1D01*
G01Y231632D02*
G03X1366509Y231435I0J-197D01*
G01Y231041D02*
G03X1366706Y230844I197J0D01*
G01Y233600D02*
G03X1366509Y233403I0J-197D01*
G01Y233009D02*
G03X1366706Y232813I197J1D01*
G01X1373399Y238620D02*
G03X1374580Y237439I1181J0D01*
G01X1373399Y241080D02*
Y238620D01*
G01X1367887Y241080D02*
X1399186D01*
G01X1373399Y238620D02*
X1377336D01*
G01Y237439D02*
X1374580D01*
G01X1366509Y229466D02*
Y229072D01*
G01Y231435D02*
Y231041D01*
G01Y233403D02*
Y233009D01*
G01X1367887Y233600D02*
X1366706D01*
G01Y232813D02*
X1367887D01*
G01Y231632D02*
X1366706D01*
G01Y230844D02*
X1367887D01*
G01Y229663D02*
X1366706D01*
G01Y228876D02*
X1367887D01*
G01X1376686Y27478D02*
X1377056Y28232D01*
G01D02*
X1377240Y28798D01*
G01D02*
X1377424Y29740D01*
G01X1376317Y28798D02*
X1376502Y29929D01*
G01X1391081Y30683D02*
Y26159D01*
G01X1390158D02*
Y30683D01*
G01X1388128Y30871D02*
Y26159D01*
G01X1387206D02*
Y32191D01*
G01X1385729Y30683D02*
Y26159D01*
G01X1384806D02*
Y30683D01*
G01X1382776D02*
Y26159D01*
G01X1381854D02*
Y30683D01*
G01X1379824Y30871D02*
Y26159D01*
G01X1378901D02*
Y32191D01*
G01X1377424Y29740D02*
Y31437D01*
G01X1379824Y26159D02*
X1378901D01*
G01X1382776D02*
X1381854D01*
G01X1385729D02*
X1384806D01*
G01X1388128D02*
X1387206D01*
G01X1391081D02*
X1390158D01*
G01X1391450Y32002D02*
X1392004Y32191D01*
G01X1389051Y31437D02*
X1388497Y31248D01*
G01Y32002D02*
X1389051Y32191D01*
G01X1383146Y32002D02*
X1383699Y32191D01*
G01X1380746Y31437D02*
X1380193Y31248D01*
G01Y32002D02*
X1380746Y32191D01*
G01X1391819Y31437D02*
X1391450Y31248D01*
G01X1383515Y31437D02*
X1383146Y31248D01*
G01X1391450D02*
X1391266Y31059D01*
G01X1390896Y31437D02*
X1391450Y32002D01*
G01X1388497Y31248D02*
X1388128Y30871D01*
G01Y31625D02*
X1388497Y32002D01*
G01X1383146Y31248D02*
X1382961Y31059D01*
G01X1382592Y31437D02*
X1383146Y32002D01*
G01X1380193Y31248D02*
X1379824Y30871D01*
G01Y31625D02*
X1380193Y32002D01*
G01X1391266Y31059D02*
X1391081Y30683D01*
G01X1382961Y31059D02*
X1382776Y30683D01*
G01X1388128Y32191D02*
Y31625D01*
G01X1379824Y32191D02*
Y31625D01*
G01X1378517Y45805D02*
Y42891D01*
G01X1377336Y48265D02*
Y45805D01*
G01X1376502Y29929D02*
Y31248D01*
G01D02*
X1376317Y32379D01*
G01X1377424Y31437D02*
X1377240Y32379D01*
G01D02*
X1377056Y32944D01*
G01X1385360Y31625D02*
X1385729Y30683D01*
G01X1390158D02*
X1389974Y31059D01*
G01X1384806Y30683D02*
X1384622Y31059D01*
G01X1381854Y30683D02*
X1381669Y31059D01*
G01X1377056Y32944D02*
X1376686Y33698D01*
G01X1392926Y31059D02*
X1392742Y31248D01*
G01X1390343Y32002D02*
X1390896Y31437D01*
G01X1389974Y31059D02*
X1389789Y31248D01*
G01X1384991Y32002D02*
X1385360Y31625D01*
G01X1384622Y31059D02*
X1384437Y31248D01*
G01X1382038Y32002D02*
X1382592Y31437D01*
G01X1381669Y31059D02*
X1381485Y31248D01*
G01X1392742D02*
X1392373Y31437D01*
G01X1389789Y31248D02*
X1389420Y31437D01*
G01X1384437Y31248D02*
X1384068Y31437D01*
G01X1381485Y31248D02*
X1381115Y31437D01*
G01X1392742Y32191D02*
X1393296Y32002D01*
G01X1389789Y32191D02*
X1390343Y32002D01*
G01X1384437Y32191D02*
X1384991Y32002D01*
G01X1381485Y32191D02*
X1382038Y32002D01*
G01X1392004Y32191D02*
X1392742D01*
G01X1389051D02*
X1389789D01*
G01X1387206D02*
X1388128D01*
G01X1383699D02*
X1384437D01*
G01X1378901D02*
X1379824D01*
G01X1380746D02*
X1381485D01*
G01X1381115Y31437D02*
X1380746D01*
G01X1384068D02*
X1383515D01*
G01X1389420D02*
X1389051D01*
G01X1392373D02*
X1391819D01*
G01X1377336Y48265D02*
Y129958D01*
G01X1376391Y59230D02*
Y59939D01*
G01Y57261D02*
Y57970D01*
G01Y55293D02*
Y56002D01*
G01Y53324D02*
Y54033D01*
G01X1377336Y59939D02*
X1376391D01*
G01Y59230D02*
X1377336D01*
G01Y57970D02*
X1376391D01*
G01Y57261D02*
X1377336D01*
G01Y56002D02*
X1376391D01*
G01Y55293D02*
X1377336D01*
G01Y54033D02*
X1376391D01*
G01Y53324D02*
X1377336D01*
G01X1376391Y78915D02*
Y79624D01*
G01Y76946D02*
Y77655D01*
G01Y73009D02*
Y73718D01*
G01Y74978D02*
Y75687D01*
G01Y71041D02*
Y71750D01*
G01Y69072D02*
Y69781D01*
G01Y78915D02*
X1377336D01*
G01Y77655D02*
X1376391D01*
G01Y76946D02*
X1377336D01*
G01Y75687D02*
X1376391D01*
G01Y74978D02*
X1377336D01*
G01Y73718D02*
X1376391D01*
G01Y73009D02*
X1377336D01*
G01Y71750D02*
X1376391D01*
G01Y71041D02*
X1377336D01*
G01Y69781D02*
X1376391D01*
G01Y69072D02*
X1377336D01*
G01X1376391Y94663D02*
Y95372D01*
G01Y92695D02*
Y93403D01*
G01Y90726D02*
Y91435D01*
G01Y88758D02*
Y89466D01*
G01Y86789D02*
Y87498D01*
G01Y84820D02*
Y85529D01*
G01Y82852D02*
Y83561D01*
G01Y80883D02*
Y81592D01*
G01X1377336Y95372D02*
X1376391D01*
G01Y94663D02*
X1377336D01*
G01Y93403D02*
X1376391D01*
G01Y92695D02*
X1377336D01*
G01Y91435D02*
X1376391D01*
G01Y90726D02*
X1377336D01*
G01Y89466D02*
X1376391D01*
G01Y88758D02*
X1377336D01*
G01Y87498D02*
X1376391D01*
G01Y86789D02*
X1377336D01*
G01Y85529D02*
X1376391D01*
G01Y84820D02*
X1377336D01*
G01Y83561D02*
X1376391D01*
G01Y82852D02*
X1377336D01*
G01Y81592D02*
X1376391D01*
G01Y80883D02*
X1377336D01*
G01Y79624D02*
X1376391D01*
G01X1391194Y106750D02*
G03X1391982Y107537I1J787D01*
G01X1381548D02*
G03X1382336Y106750I788J1D01*
G01X1389645Y108994D02*
X1389445Y108863D01*
G01X1389243Y109125D02*
X1389445Y109256D01*
G01X1389780Y109125D02*
X1389645Y108994D01*
G01X1389445Y109256D02*
X1389578Y109387D01*
G01X1389712Y111619D02*
X1389578Y111487D01*
G01X1388238Y110306D02*
X1388104Y110175D01*
G01X1389377Y111750D02*
X1389511Y111881D01*
G01X1387903Y110437D02*
X1388037Y110569D01*
G01X1389846Y111815D02*
X1389712Y111619D01*
G01X1389846Y109256D02*
X1389780Y109125D01*
G01X1389511Y111881D02*
X1389578Y112012D01*
G01X1387836Y110306D02*
X1387903Y110437D01*
G01X1389913Y112012D02*
X1389846Y111815D01*
G01X1389913Y109519D02*
X1389846Y109256D01*
G01X1389578Y109387D02*
X1389645Y109650D01*
G01X1389578Y112012D02*
X1389645Y112275D01*
G01X1388104Y110175D02*
X1388037Y109913D01*
G01X1387769Y110044D02*
X1387836Y110306D01*
G01X1391982Y107537D02*
Y127183D01*
G01X1390919Y108206D02*
Y107878D01*
G01X1389913Y110044D02*
Y109519D01*
G01Y112275D02*
Y112012D01*
G01X1389445Y108863D02*
X1389243Y108797D01*
G01X1388439Y110437D02*
X1388238Y110306D01*
G01X1388037Y110569D02*
X1388238Y110700D01*
G01X1389645Y109650D02*
Y109913D01*
G01X1388037D02*
Y109650D01*
G01X1387769Y111356D02*
Y111684D01*
G01Y109519D02*
Y110044D01*
G01Y107878D02*
Y108206D01*
G01X1381548Y127183D02*
Y107537D01*
G01X1376391Y110411D02*
Y111120D01*
G01Y108443D02*
Y109151D01*
G01Y106474D02*
Y107183D01*
G01Y104506D02*
Y105214D01*
G01Y102537D02*
Y103246D01*
G01Y100569D02*
Y101277D01*
G01Y98600D02*
Y99309D01*
G01Y96632D02*
Y97340D01*
G01X1389846Y110306D02*
X1389913Y110044D01*
G01X1389645Y109913D02*
X1389578Y110175D01*
G01X1388037Y109650D02*
X1388104Y109387D01*
G01X1387836Y109256D02*
X1387769Y109519D01*
G01X1389578Y111487D02*
X1389377Y111422D01*
G01X1389780Y110437D02*
X1389846Y110306D01*
G01X1387903Y109125D02*
X1387836Y109256D01*
G01X1389645Y110569D02*
X1389780Y110437D01*
G01X1389578Y110175D02*
X1389445Y110306D01*
G01X1388104Y109387D02*
X1388238Y109256D01*
G01X1388037Y108994D02*
X1387903Y109125D01*
G01X1389445Y110700D02*
X1389645Y110569D01*
G01X1389445Y110306D02*
X1389243Y110437D01*
G01X1388238Y109256D02*
X1388439Y109125D01*
G01X1388238Y108863D02*
X1388037Y108994D01*
G01X1389243Y110765D02*
X1389445Y110700D01*
G01X1388707Y108732D02*
X1388238Y108863D01*
G01X1388975Y110831D02*
X1389243Y110765D01*
G01Y110437D02*
X1388975Y110503D01*
G01X1388439Y109125D02*
X1388707Y109059D01*
G01X1387769Y111684D02*
X1389042D01*
G01Y111356D02*
X1387769D01*
G01X1377336Y111120D02*
X1376391D01*
G01X1388707Y110831D02*
X1388975D01*
G01Y110503D02*
X1388707D01*
G01X1376391Y110411D02*
X1377336D01*
G01Y109151D02*
X1376391D01*
G01X1388707Y109059D02*
X1388975D01*
G01Y108732D02*
X1388707D01*
G01X1376391Y108443D02*
X1377336D01*
G01X1387769Y108206D02*
X1390919D01*
G01Y107878D02*
X1387769D01*
G01X1377336Y107183D02*
X1376391D01*
G01X1382336Y106750D02*
X1391194D01*
G01X1376391Y106474D02*
X1377336D01*
G01Y105214D02*
X1376391D01*
G01Y104506D02*
X1377336D01*
G01Y103246D02*
X1376391D01*
G01Y102537D02*
X1377336D01*
G01Y101277D02*
X1376391D01*
G01Y100569D02*
X1377336D01*
G01Y99309D02*
X1376391D01*
G01Y98600D02*
X1377336D01*
G01Y97340D02*
X1376391D01*
G01Y96632D02*
X1377336D01*
G01X1389042Y111684D02*
X1389377Y111750D01*
G01Y111422D02*
X1389042Y111356D01*
G01X1388707Y110503D02*
X1388439Y110437D01*
G01X1388975Y109059D02*
X1389243Y109125D01*
G01Y108797D02*
X1388975Y108732D01*
G01X1388238Y110700D02*
X1388707Y110831D01*
G01X1391982Y127183D02*
G03X1391194Y127970I-787J0D01*
G01X1382336D02*
G03X1381548Y127183I0J-788D01*
G01X1389645Y113981D02*
X1389377Y113784D01*
G01X1389712Y116606D02*
X1389578Y116474D01*
G01X1388372Y115359D02*
X1388171Y115162D01*
G01X1389377Y116737D02*
X1389511Y116868D01*
G01X1388037Y115490D02*
X1388171Y115621D01*
G01X1389712Y119033D02*
X1389511Y118836D01*
G01X1389846Y121592D02*
X1389712Y121461D01*
G01X1389511Y121724D02*
X1389578Y121789D01*
G01X1387903Y120280D02*
X1388037Y120411D01*
G01X1389846Y122642D02*
X1389645Y122445D01*
G01X1389511Y122773D02*
X1389578Y122839D01*
G01X1389445Y114178D02*
X1389578Y114374D01*
G01X1389846Y116802D02*
X1389712Y116606D01*
G01X1387903Y115293D02*
X1388037Y115490D01*
G01X1389846Y119230D02*
X1389712Y119033D01*
G01X1388305Y120346D02*
X1388171Y120149D01*
G01X1389846Y114309D02*
X1389645Y113981D01*
G01X1389511Y116868D02*
X1389578Y116999D01*
G01X1388171Y115162D02*
X1388104Y115031D01*
G01X1389445Y119230D02*
X1389578Y119493D01*
G01Y121789D02*
X1389645Y121920D01*
G01X1389578Y122839D02*
X1389645Y122970D01*
G01X1387836Y120149D02*
X1387903Y120280D01*
G01X1389913Y116999D02*
X1389846Y116802D01*
G01X1387836Y115096D02*
X1387903Y115293D01*
G01X1389913Y121789D02*
X1389846Y121592D01*
G01X1389913Y122839D02*
X1389846Y122642D01*
G01X1389578Y116999D02*
X1389645Y117261D01*
G01X1389913Y119493D02*
X1389846Y119230D01*
G01X1388104Y115031D02*
X1388037Y114768D01*
G01X1388171Y120149D02*
X1388104Y119886D01*
G01X1387769D02*
X1387836Y120149D01*
G01X1389913Y114702D02*
X1389846Y114309D01*
G01X1389578Y114374D02*
X1389645Y114768D01*
G01X1387769Y114702D02*
X1387836Y115096D01*
G01X1390919Y118180D02*
Y117852D01*
G01Y125858D02*
Y125332D01*
G01X1389913Y113193D02*
Y112865D01*
G01Y117261D02*
Y116999D01*
G01Y119886D02*
Y119493D01*
G01Y120805D02*
Y120477D01*
G01Y122052D02*
Y121789D01*
G01Y123102D02*
Y122839D01*
G01Y123758D02*
Y123430D01*
G01X1388037Y114768D02*
X1388104Y114309D01*
G01X1387836Y114243D02*
X1387769Y114702D01*
G01X1389846Y115096D02*
X1389913Y114702D01*
G01X1389846Y120149D02*
X1389913Y119886D01*
G01X1389578D02*
X1389511Y120149D01*
G01X1389846Y117524D02*
X1389913Y117261D01*
G01X1389645D02*
X1389578Y117524D01*
G01X1389645Y114768D02*
X1389578Y115031D01*
G01X1388104Y119624D02*
X1388171Y119361D01*
G01X1389846Y112537D02*
X1389913Y112275D01*
G01X1389645D02*
X1389578Y112537D01*
G01X1388506Y115424D02*
X1388372Y115359D01*
G01X1388171Y115621D02*
X1388439Y115752D01*
G01X1389578Y116474D02*
X1389445Y116409D01*
G01X1389511Y118836D02*
X1389377Y118771D01*
G01X1389243Y114046D02*
X1389445Y114178D01*
G01X1389243Y119099D02*
X1389445Y119230D01*
G01X1388506Y120477D02*
X1388305Y120346D01*
G01X1389645Y122970D02*
Y123102D01*
G01Y121920D02*
Y122117D01*
G01X1389578Y119493D02*
Y119886D01*
G01X1389109Y115424D02*
Y114046D01*
G01X1388841Y113718D02*
Y115490D01*
G01Y126185D02*
Y125004D01*
G01X1388573Y124939D02*
Y126251D01*
G01X1388439Y114046D02*
Y113718D01*
G01X1388104Y119886D02*
Y119624D01*
G01X1387769Y126513D02*
Y126907D01*
G01Y122380D02*
Y122708D01*
G01Y123430D02*
Y123758D01*
G01Y124283D02*
Y124676D01*
G01Y121330D02*
Y121658D01*
G01Y117852D02*
Y118180D01*
G01Y119493D02*
Y119886D01*
G01Y116343D02*
Y116671D01*
G01Y112865D02*
Y113193D01*
G01X1386697Y120477D02*
Y120805D01*
G01X1385682Y116474D02*
Y115883D01*
G01Y119033D02*
Y118443D01*
G01X1382533Y118639D02*
Y119033D01*
G01Y115883D02*
Y116277D01*
G01Y117196D02*
Y117721D01*
G01X1376391Y122222D02*
Y122931D01*
G01Y124191D02*
Y124899D01*
G01Y120254D02*
Y120962D01*
G01Y118285D02*
Y118994D01*
G01Y116317D02*
Y117025D01*
G01Y114348D02*
Y115057D01*
G01Y112380D02*
Y113088D01*
G01X1387836Y119230D02*
X1387769Y119493D01*
G01X1389846Y123298D02*
X1389913Y123102D01*
G01X1389645D02*
X1389578Y123298D01*
G01X1389846Y122248D02*
X1389913Y122052D01*
G01X1389780Y115293D02*
X1389846Y115096D01*
G01X1389645Y122117D02*
X1389578Y122248D01*
G01X1389780Y120280D02*
X1389846Y120149D01*
G01X1388707Y115490D02*
X1388506Y115424D01*
G01X1389042Y119033D02*
X1389243Y119099D01*
G01X1388841Y125004D02*
X1390650Y125595D01*
G01X1387769Y124676D02*
X1388573Y124939D01*
G01X1390919Y125332D02*
X1387769Y124283D01*
G01X1385682Y118443D02*
X1382868Y117458D01*
G01X1382533Y117721D02*
X1385012Y118639D01*
G01X1389712Y121461D02*
X1389377Y121330D01*
G01X1388037Y120411D02*
X1388171Y120477D01*
G01X1389377Y121658D02*
X1389511Y121724D01*
G01X1389377Y122708D02*
X1389511Y122773D01*
G01X1389578Y115031D02*
X1389511Y115162D01*
G01X1387970Y113981D02*
X1387836Y114243D01*
G01X1389511Y120149D02*
X1389377Y120346D01*
G01X1389712Y117721D02*
X1389846Y117524D01*
G01X1389578D02*
X1389445Y117721D01*
G01X1388171Y119361D02*
X1388305Y119165D01*
G01X1387970Y119033D02*
X1387836Y119230D01*
G01X1389645Y115490D02*
X1389780Y115293D01*
G01X1389712Y112734D02*
X1389846Y112537D01*
G01X1389578D02*
X1389445Y112734D01*
G01X1388104Y114309D02*
X1388238Y114112D01*
G01X1389712Y123430D02*
X1389846Y123298D01*
G01X1389578D02*
X1389445Y123430D01*
G01X1389645Y122445D02*
X1389846Y122248D01*
G01X1389578D02*
X1389511Y122314D01*
G01X1389645Y120411D02*
X1389780Y120280D01*
G01X1389578Y117852D02*
X1389712Y117721D01*
G01X1389445D02*
X1389310Y117852D01*
G01X1389511Y115621D02*
X1389645Y115490D01*
G01X1389511Y115162D02*
X1389310Y115359D01*
G01X1389578Y112865D02*
X1389712Y112734D01*
G01X1389445D02*
X1389310Y112865D01*
G01X1388171Y113784D02*
X1387970Y113981D01*
G01X1388305Y118771D02*
X1387970Y119033D01*
G01X1389377Y120346D02*
X1389176Y120477D01*
G01X1389511Y122314D02*
X1389377Y122380D01*
G01X1389511Y120477D02*
X1389645Y120411D01*
G01X1388305Y119165D02*
X1388439Y119099D01*
G01X1389243Y115752D02*
X1389511Y115621D01*
G01X1389310Y115359D02*
X1389176Y115424D01*
G01X1385012Y116277D02*
X1382533Y117196D01*
G01X1387769Y126907D02*
X1390919Y125858D01*
G01X1390650Y125595D02*
X1388841Y126185D01*
G01X1388573Y126251D02*
X1387769Y126513D01*
G01X1388439Y119099D02*
X1388640Y119033D01*
G01X1382868Y117458D02*
X1385682Y116474D01*
G01X1388238Y114112D02*
X1388439Y114046D01*
G01X1388573Y118705D02*
X1388305Y118771D01*
G01X1388439Y113718D02*
X1388171Y113784D01*
G01X1388841Y115818D02*
X1389243Y115752D01*
G01X1391194Y127970D02*
X1382336D01*
G01X1377336Y124899D02*
X1376391D01*
G01Y124191D02*
X1377336D01*
G01X1387769Y123758D02*
X1389913D01*
G01X1389445Y123430D02*
X1387769D01*
G01X1389913D02*
X1389712D01*
G01X1377336Y122931D02*
X1376391D01*
G01X1387769Y122708D02*
X1389377D01*
G01Y122380D02*
X1387769D01*
G01X1376391Y122222D02*
X1377336D01*
G01X1387769Y121658D02*
X1389377D01*
G01Y121330D02*
X1387769D01*
G01X1377336Y120962D02*
X1376391D01*
G01X1386697Y120805D02*
X1389913D01*
G01X1388171Y120477D02*
X1386697D01*
G01X1389176D02*
X1388506D01*
G01X1389913D02*
X1389511D01*
G01X1376391Y120254D02*
X1377336D01*
G01X1388640Y119033D02*
X1389042D01*
G01X1382533D02*
X1385682D01*
G01X1377336Y118994D02*
X1376391D01*
G01X1389109Y118705D02*
X1388573D01*
G01X1385012Y118639D02*
X1382533D01*
G01X1376391Y118285D02*
X1377336D01*
G01X1387769Y118180D02*
X1390919D01*
G01X1389310Y117852D02*
X1387769D01*
G01X1390919D02*
X1389578D01*
G01X1377336Y117025D02*
X1376391D01*
G01X1387769Y116671D02*
X1389109D01*
G01Y116343D02*
X1387769D01*
G01X1376391Y116317D02*
X1377336D01*
G01X1382533Y116277D02*
X1385012D01*
G01X1385682Y115883D02*
X1382533D01*
G01X1388841Y115490D02*
X1388707D01*
G01X1389176Y115424D02*
X1389109D01*
G01X1377336Y115057D02*
X1376391D01*
G01Y114348D02*
X1377336D01*
G01X1389109Y114046D02*
X1389243D01*
G01X1389109Y113718D02*
X1388841D01*
G01X1387769Y113193D02*
X1389913D01*
G01X1377336Y113088D02*
X1376391D01*
G01X1389310Y112865D02*
X1387769D01*
G01X1389913D02*
X1389578D01*
G01X1376391Y112380D02*
X1377336D01*
G01X1388439Y115752D02*
X1388841Y115818D01*
G01X1389445Y116409D02*
X1389109Y116343D01*
G01X1389377Y118771D02*
X1389109Y118705D01*
G01Y116671D02*
X1389377Y116737D01*
G01Y113784D02*
X1389109Y113718D01*
G01X1378517Y135411D02*
Y132419D01*
G01X1377336D02*
Y129958D01*
G01X1378517Y154466D02*
Y151553D01*
G01X1377336Y156927D02*
Y238620D01*
G01Y156927D02*
Y154466D01*
G01X1376391Y177734D02*
Y178443D01*
G01Y167891D02*
Y168600D01*
G01Y165923D02*
Y166632D01*
G01Y163954D02*
Y164663D01*
G01Y161986D02*
Y162695D01*
G01Y177734D02*
X1377336D01*
G01Y168600D02*
X1376391D01*
G01Y167891D02*
X1377336D01*
G01Y166632D02*
X1376391D01*
G01Y165923D02*
X1377336D01*
G01Y164663D02*
X1376391D01*
G01Y163954D02*
X1377336D01*
G01Y162695D02*
X1376391D01*
G01Y161986D02*
X1377336D01*
G01X1376391Y193482D02*
Y194191D01*
G01Y191513D02*
Y192222D01*
G01Y189545D02*
Y190254D01*
G01Y187576D02*
Y188285D01*
G01Y185608D02*
Y186317D01*
G01Y183639D02*
Y184348D01*
G01Y181671D02*
Y182380D01*
G01Y179702D02*
Y180411D01*
G01X1377336Y194191D02*
X1376391D01*
G01Y193482D02*
X1377336D01*
G01Y192222D02*
X1376391D01*
G01Y191513D02*
X1377336D01*
G01Y190254D02*
X1376391D01*
G01Y189545D02*
X1377336D01*
G01Y188285D02*
X1376391D01*
G01Y187576D02*
X1377336D01*
G01Y186317D02*
X1376391D01*
G01Y185608D02*
X1377336D01*
G01Y184348D02*
X1376391D01*
G01Y183639D02*
X1377336D01*
G01Y182380D02*
X1376391D01*
G01Y181671D02*
X1377336D01*
G01Y180411D02*
X1376391D01*
G01Y179702D02*
X1377336D01*
G01Y178443D02*
X1376391D01*
G01Y211198D02*
Y211907D01*
G01Y209230D02*
Y209939D01*
G01Y207261D02*
Y207970D01*
G01Y205293D02*
Y206002D01*
G01Y203324D02*
Y204033D01*
G01Y199387D02*
Y200096D01*
G01Y201356D02*
Y202065D01*
G01Y197419D02*
Y198128D01*
G01Y195450D02*
Y196159D01*
G01Y211198D02*
X1377336D01*
G01Y209939D02*
X1376391D01*
G01Y209230D02*
X1377336D01*
G01Y207970D02*
X1376391D01*
G01Y207261D02*
X1377336D01*
G01Y206002D02*
X1376391D01*
G01Y205293D02*
X1377336D01*
G01Y204033D02*
X1376391D01*
G01Y203324D02*
X1377336D01*
G01Y202065D02*
X1376391D01*
G01Y201356D02*
X1377336D01*
G01Y200096D02*
X1376391D01*
G01Y199387D02*
X1377336D01*
G01Y198128D02*
X1376391D01*
G01Y197419D02*
X1377336D01*
G01Y196159D02*
X1376391D01*
G01Y195450D02*
X1377336D01*
G01X1391194Y215411D02*
G03X1391982Y216198I0J788D01*
G01X1381548D02*
G03X1382336Y215411I788J1D01*
G01X1388037Y223430D02*
X1388104Y222970D01*
G01X1387836Y222905D02*
X1387769Y223364D01*
G01X1389846Y223758D02*
X1389913Y223364D01*
G01X1389846Y226185D02*
X1389913Y225923D01*
G01X1389645D02*
X1389578Y226185D01*
G01X1389645Y223430D02*
X1389578Y223692D01*
G01X1389846Y221198D02*
X1389913Y220936D01*
G01X1389645D02*
X1389578Y221198D01*
G01X1389846Y218968D02*
X1389913Y218705D01*
G01X1389645Y218574D02*
X1389578Y218836D01*
G01X1388037Y218311D02*
X1388104Y218049D01*
G01X1387836Y217918D02*
X1387769Y218180D01*
G01X1389780Y223954D02*
X1389846Y223758D01*
G01X1389578Y223692D02*
X1389511Y223823D01*
G01X1387970Y222642D02*
X1387836Y222905D01*
G01X1389780Y219099D02*
X1389846Y218968D01*
G01X1387903Y217787D02*
X1387836Y217918D01*
G01X1389712Y226382D02*
X1389846Y226185D01*
G01X1389578D02*
X1389445Y226382D01*
G01X1387970Y227695D02*
X1387836Y227891D01*
G01X1389645Y224151D02*
X1389780Y223954D01*
G01X1389712Y221395D02*
X1389846Y221198D01*
G01X1389578D02*
X1389445Y221395D01*
G01X1388104Y222970D02*
X1388238Y222773D01*
G01X1389578Y226513D02*
X1389712Y226382D01*
G01X1389445D02*
X1389310Y226513D01*
G01X1389511Y224283D02*
X1389645Y224151D01*
G01X1389511Y223823D02*
X1389310Y224020D01*
G01X1389578Y221527D02*
X1389712Y221395D01*
G01X1389445D02*
X1389310Y221527D01*
G01X1388171Y222445D02*
X1387970Y222642D01*
G01X1389645Y219230D02*
X1389780Y219099D01*
G01X1389578Y218836D02*
X1389445Y218968D01*
G01X1388104Y218049D02*
X1388238Y217918D01*
G01X1388037Y217655D02*
X1387903Y217787D01*
G01X1388305Y227432D02*
X1387970Y227695D01*
G01X1391982Y216198D02*
Y235844D01*
G01X1390919Y216868D02*
Y216540D01*
G01Y226842D02*
Y226513D01*
G01X1389913Y218705D02*
Y218180D01*
G01Y220936D02*
Y220674D01*
G01Y221855D02*
Y221527D01*
G01Y225923D02*
Y225661D01*
G01X1389445Y219361D02*
X1389645Y219230D01*
G01X1389445Y218968D02*
X1389243Y219099D01*
G01X1388238Y217918D02*
X1388439Y217787D01*
G01X1388238Y217524D02*
X1388037Y217655D01*
G01X1388305Y227826D02*
X1388439Y227760D01*
G01X1389243Y224414D02*
X1389511Y224283D01*
G01X1389310Y224020D02*
X1389176Y224086D01*
G01X1385012Y224939D02*
X1382533Y225858D01*
G01X1382868Y226120D02*
X1385682Y225135D01*
G01X1388439Y227760D02*
X1388640Y227695D01*
G01X1389913Y218180D02*
X1389846Y217918D01*
G01X1389578Y218049D02*
X1389645Y218311D01*
G01X1389578Y220674D02*
X1389645Y220936D01*
G01X1389913Y223364D02*
X1389846Y222970D01*
G01X1389578Y223036D02*
X1389645Y223430D01*
G01X1387769Y223364D02*
X1387836Y223758D01*
G01X1389645Y218311D02*
Y218574D01*
G01X1389109Y224086D02*
Y222708D01*
G01X1388841Y222380D02*
Y224151D01*
G01X1388439Y222708D02*
Y222380D01*
G01X1388037Y218574D02*
Y218311D01*
G01X1387769Y226513D02*
Y226842D01*
G01Y225004D02*
Y225332D01*
G01Y221527D02*
Y221855D01*
G01Y218180D02*
Y218705D01*
G01Y220017D02*
Y220346D01*
G01Y216540D02*
Y216868D01*
G01X1385682Y225135D02*
Y224545D01*
G01Y227695D02*
Y227104D01*
G01X1382533Y227301D02*
Y227695D01*
G01Y225858D02*
Y226382D01*
G01Y224545D02*
Y224939D01*
G01X1381548Y235844D02*
Y216198D01*
G01X1376391Y226946D02*
Y227655D01*
G01Y224978D02*
Y225687D01*
G01Y223009D02*
Y223718D01*
G01Y221041D02*
Y221750D01*
G01Y219072D02*
Y219781D01*
G01Y217104D02*
Y217813D01*
G01Y215135D02*
Y215844D01*
G01Y213167D02*
Y213876D01*
G01X1388238Y222773D02*
X1388439Y222708D01*
G01X1389243Y219427D02*
X1389445Y219361D01*
G01X1388707Y217393D02*
X1388238Y217524D01*
G01X1388573Y227367D02*
X1388305Y227432D01*
G01X1388439Y222380D02*
X1388171Y222445D01*
G01X1388975Y219493D02*
X1389243Y219427D01*
G01Y219099D02*
X1388975Y219165D01*
G01X1388439Y217787D02*
X1388707Y217721D01*
G01X1388841Y224480D02*
X1389243Y224414D01*
G01X1389913Y220674D02*
X1389846Y220477D01*
G01X1389913Y225661D02*
X1389846Y225464D01*
G01X1387836Y223758D02*
X1387903Y223954D01*
G01X1388104Y218836D02*
X1388037Y218574D01*
G01X1389578Y225661D02*
X1389645Y225923D01*
G01X1387769Y218705D02*
X1387836Y218968D01*
G01X1388104Y223692D02*
X1388037Y223430D01*
G01X1388640Y227695D02*
X1389042D01*
G01X1382533D02*
X1385682D01*
G01X1377336Y227655D02*
X1376391D01*
G01X1389109Y227367D02*
X1388573D01*
G01X1385012Y227301D02*
X1382533D01*
G01X1376391Y226946D02*
X1377336D01*
G01X1387769Y226842D02*
X1390919D01*
G01X1389310Y226513D02*
X1387769D01*
G01X1390919D02*
X1389578D01*
G01X1377336Y225687D02*
X1376391D01*
G01X1387769Y225332D02*
X1389109D01*
G01Y225004D02*
X1387769D01*
G01X1376391Y224978D02*
X1377336D01*
G01X1382533Y224939D02*
X1385012D01*
G01X1385682Y224545D02*
X1382533D01*
G01X1388841Y224151D02*
X1388707D01*
G01X1389176Y224086D02*
X1389109D01*
G01X1377336Y223718D02*
X1376391D01*
G01Y223009D02*
X1377336D01*
G01X1389109Y222708D02*
X1389243D01*
G01X1389109Y222380D02*
X1388841D01*
G01X1387769Y221855D02*
X1389913D01*
G01X1377336Y221750D02*
X1376391D01*
G01X1389310Y221527D02*
X1387769D01*
G01X1389913D02*
X1389578D01*
G01X1376391Y221041D02*
X1377336D01*
G01X1387769Y220346D02*
X1389042D01*
G01Y220017D02*
X1387769D01*
G01X1377336Y219781D02*
X1376391D01*
G01X1388707Y219493D02*
X1388975D01*
G01X1389846Y220477D02*
X1389712Y220280D01*
G01X1389445Y222839D02*
X1389578Y223036D01*
G01X1389846Y222970D02*
X1389645Y222642D01*
G01X1389846Y217918D02*
X1389780Y217787D01*
G01X1389511Y220543D02*
X1389578Y220674D01*
G01X1387836Y218968D02*
X1387903Y219099D01*
G01X1389511Y225529D02*
X1389578Y225661D01*
G01X1388171Y223823D02*
X1388104Y223692D01*
G01X1388975Y219165D02*
X1388707D01*
G01X1376391Y219072D02*
X1377336D01*
G01Y217813D02*
X1376391D01*
G01X1388707Y217721D02*
X1388975D01*
G01Y217393D02*
X1388707D01*
G01X1376391Y217104D02*
X1377336D01*
G01X1387769Y216868D02*
X1390919D01*
G01Y216540D02*
X1387769D01*
G01X1377336Y215844D02*
X1376391D01*
G01X1382336Y215411D02*
X1391194D01*
G01X1376391Y215135D02*
X1377336D01*
G01Y213876D02*
X1376391D01*
G01Y213167D02*
X1377336D01*
G01Y211907D02*
X1376391D01*
G01X1388439Y224414D02*
X1388841Y224480D01*
G01X1389445Y225070D02*
X1389109Y225004D01*
G01X1389846Y225464D02*
X1389712Y225267D01*
G01X1387903Y223954D02*
X1388037Y224151D01*
G01X1389846Y227891D02*
X1389712Y227695D01*
G01X1389042Y220346D02*
X1389377Y220411D01*
G01Y220083D02*
X1389042Y220017D01*
G01X1389377Y227432D02*
X1389109Y227367D01*
G01Y225332D02*
X1389377Y225398D01*
G01Y222445D02*
X1389109Y222380D01*
G01X1388707Y219165D02*
X1388439Y219099D01*
G01X1388975Y217721D02*
X1389243Y217787D01*
G01Y217458D02*
X1388975Y217393D01*
G01X1388238Y219361D02*
X1388707Y219493D01*
G01X1389780Y217787D02*
X1389645Y217655D01*
G01X1389445Y217918D02*
X1389578Y218049D01*
G01X1389712Y220280D02*
X1389578Y220149D01*
G01X1388238Y218968D02*
X1388104Y218836D01*
G01X1389377Y220411D02*
X1389511Y220543D01*
G01X1387903Y219099D02*
X1388037Y219230D01*
G01X1389712Y225267D02*
X1389578Y225135D01*
G01X1388372Y224020D02*
X1388171Y223823D01*
G01X1389377Y225398D02*
X1389511Y225529D01*
G01X1388037Y224151D02*
X1388171Y224283D01*
G01X1389712Y227695D02*
X1389511Y227498D01*
G01X1389645Y217655D02*
X1389445Y217524D01*
G01X1389243Y217787D02*
X1389445Y217918D01*
G01X1388439Y219099D02*
X1388238Y218968D01*
G01X1388037Y219230D02*
X1388238Y219361D01*
G01X1389243Y222708D02*
X1389445Y222839D01*
G01X1389243Y227760D02*
X1389445Y227891D01*
G01X1389645Y222642D02*
X1389377Y222445D01*
G01X1388506Y224086D02*
X1388372Y224020D01*
G01X1388171Y224283D02*
X1388439Y224414D01*
G01X1389578Y225135D02*
X1389445Y225070D01*
G01X1389511Y227498D02*
X1389377Y227432D01*
G01X1389445Y217524D02*
X1389243Y217458D01*
G01X1389578Y220149D02*
X1389377Y220083D01*
G01X1388707Y224151D02*
X1388506Y224086D01*
G01X1389042Y227695D02*
X1389243Y227760D01*
G01X1385682Y227104D02*
X1382868Y226120D01*
G01X1382533Y226382D02*
X1385012Y227301D01*
G01X1391982Y235844D02*
G03X1391194Y236632I-788J0D01*
G01X1382336D02*
G03X1381548Y235844I0J-788D01*
G01X1389645Y230779D02*
X1389578Y230910D01*
G01X1389780Y228941D02*
X1389846Y228810D01*
G01X1389511D02*
X1389377Y229007D01*
G01X1389846Y228810D02*
X1389913Y228548D01*
G01X1389578D02*
X1389511Y228810D01*
G01X1388104Y228285D02*
X1388171Y228023D01*
G01X1387836Y227891D02*
X1387769Y228154D01*
G01X1389846Y231960D02*
X1389913Y231763D01*
G01X1389645D02*
X1389578Y231960D01*
G01X1389846Y230910D02*
X1389913Y230713D01*
G01X1388171Y228023D02*
X1388305Y227826D01*
G01X1389712Y232091D02*
X1389846Y231960D01*
G01X1389578D02*
X1389445Y232091D01*
G01X1389645Y231107D02*
X1389846Y230910D01*
G01X1389578D02*
X1389511Y230976D01*
G01X1389645Y229072D02*
X1389780Y228941D01*
G01X1389377Y229007D02*
X1389176Y229138D01*
G01X1390919Y234519D02*
Y233994D01*
G01X1389913Y228548D02*
Y228154D01*
G01Y229466D02*
Y229138D01*
G01Y230713D02*
Y230450D01*
G01Y231763D02*
Y231500D01*
G01Y232419D02*
Y232091D01*
G01X1389511Y230976D02*
X1389377Y231041D01*
G01X1389511Y229138D02*
X1389645Y229072D01*
G01X1387769Y235569D02*
X1390919Y234519D01*
G01X1390650Y234256D02*
X1388841Y234847D01*
G01X1388573Y234913D02*
X1387769Y235175D01*
G01X1389645Y231632D02*
Y231763D01*
G01Y230582D02*
Y230779D01*
G01X1389578Y228154D02*
Y228548D01*
G01X1388841Y234847D02*
Y233666D01*
G01X1388573Y233600D02*
Y234913D01*
G01X1388104Y228548D02*
Y228285D01*
G01X1387769Y235175D02*
Y235569D01*
G01Y232944D02*
Y233338D01*
G01Y231041D02*
Y231369D01*
G01Y229991D02*
Y230319D01*
G01Y232091D02*
Y232419D01*
G01Y228154D02*
Y228548D01*
G01X1386697Y229138D02*
Y229466D01*
G01X1378517Y244072D02*
Y241080D01*
G01X1377336D02*
Y238620D01*
G01X1376391Y232852D02*
Y233561D01*
G01Y230883D02*
Y231592D01*
G01Y228915D02*
Y229624D01*
G01X1378517Y242104D02*
X1431076D01*
G01X1391194Y236632D02*
X1382336D01*
G01X1389913Y230450D02*
X1389846Y230254D01*
G01X1389913Y231500D02*
X1389846Y231304D01*
G01X1389913Y228154D02*
X1389846Y227891D01*
G01X1388171Y228810D02*
X1388104Y228548D01*
G01X1387769D02*
X1387836Y228810D01*
G01X1377336Y233561D02*
X1376391D01*
G01Y232852D02*
X1377336D01*
G01X1387769Y232419D02*
X1389913D01*
G01X1389445Y232091D02*
X1387769D01*
G01X1389913D02*
X1389712D01*
G01X1377336Y231592D02*
X1376391D01*
G01X1387769Y231369D02*
X1389377D01*
G01Y231041D02*
X1387769D01*
G01X1376391Y230883D02*
X1377336D01*
G01X1387769Y230319D02*
X1389377D01*
G01Y229991D02*
X1387769D01*
G01X1377336Y229624D02*
X1376391D01*
G01X1386697Y229466D02*
X1389913D01*
G01X1388171Y229138D02*
X1386697D01*
G01X1389176D02*
X1388506D01*
G01X1389913D02*
X1389511D01*
G01X1376391Y228915D02*
X1377336D01*
G01X1389445Y227891D02*
X1389578Y228154D01*
G01Y230450D02*
X1389645Y230582D01*
G01X1389578Y231500D02*
X1389645Y231632D01*
G01X1387836Y228810D02*
X1387903Y228941D01*
G01X1388305Y229007D02*
X1388171Y228810D01*
G01X1389846Y230254D02*
X1389712Y230122D01*
G01X1389511Y230385D02*
X1389578Y230450D01*
G01X1387903Y228941D02*
X1388037Y229072D01*
G01X1389846Y231304D02*
X1389645Y231107D01*
G01X1389511Y231435D02*
X1389578Y231500D01*
G01X1388506Y229138D02*
X1388305Y229007D01*
G01X1388037Y229072D02*
X1388171Y229138D01*
G01X1389377Y230319D02*
X1389511Y230385D01*
G01X1389377Y231369D02*
X1389511Y231435D01*
G01X1390919Y233994D02*
X1387769Y232944D01*
G01X1389712Y230122D02*
X1389377Y229991D01*
G01X1388841Y233666D02*
X1390650Y234256D01*
G01X1387769Y233338D02*
X1388573Y233600D01*
G01X1415131Y330726D02*
G03X1383635I-15748J0D01*
G03X1415131I15748J0D01*
G01X1406371D02*
G03X1392396I-6987J0D01*
G03X1406371I6987J0D01*
G01X1393609Y369295D02*
X1391444Y369782D01*
G01X1388556Y376116D02*
Y377091D01*
G01X1389278Y375142D02*
X1388556Y376116D01*
G01Y370757D02*
Y366859D01*
G01X1391444Y369782D02*
X1388556Y370757D01*
G01X1392165Y376116D02*
Y377091D01*
G01X1388556Y392194D02*
X1389278Y393168D01*
G01Y391219D02*
X1388556Y392194D01*
G01X1390000Y390732D02*
X1389278Y391219D01*
G01X1391444Y390245D02*
X1390000Y390732D01*
G01X1394331Y390245D02*
X1391444D01*
G01X1392165Y377091D02*
X1392887Y378065D01*
G01X1391444D02*
X1392165Y377091D01*
G01X1390722Y378552D02*
X1391444Y378065D01*
G01X1390000Y378552D02*
X1390722D01*
G01X1389278Y378065D02*
X1390000Y378552D01*
G01X1388556Y377091D02*
X1389278Y378065D01*
G01X1391444Y401938D02*
X1394331D01*
G01X1390000Y401451D02*
X1391444Y401938D01*
G01X1389278Y400963D02*
X1390000Y401451D01*
G01X1388556Y399989D02*
X1389278Y400963D01*
G01Y399015D02*
X1388556Y399989D01*
G01X1390000Y398528D02*
X1389278Y399015D01*
G01X1391444Y398040D02*
X1390000Y398528D01*
G01X1394331Y398040D02*
X1391444D01*
G01Y394143D02*
X1394331D01*
G01X1390000Y393655D02*
X1391444Y394143D01*
G01X1389278Y393168D02*
X1390000Y393655D01*
G01X1397831Y-752009D02*
Y-745709D01*
X1396891Y-746969D01*
G01Y-752009D02*
X1398771D01*
G01X1404131Y-745709D02*
X1403504Y-745919D01*
X1403034Y-746444D01*
X1402721Y-747074D01*
X1402486Y-747914D01*
X1402408Y-748859D01*
X1402486Y-749804D01*
X1402721Y-750644D01*
X1403034Y-751274D01*
X1403504Y-751799D01*
X1404131Y-752009D01*
X1404758Y-751799D01*
X1405228Y-751274D01*
X1405541Y-750644D01*
X1405776Y-749804D01*
X1405854Y-748859D01*
X1405776Y-747914D01*
X1405541Y-747074D01*
X1405228Y-746444D01*
X1404758Y-745919D01*
X1404131Y-745709D01*
G01X1394034Y30683D02*
Y26159D01*
G01X1393111D02*
Y30683D01*
G01X1394034Y26159D02*
X1393111D01*
G01X1399186Y45805D02*
G03X1399974Y46592I1J787D01*
G01X1393665Y31625D02*
X1394034Y30683D01*
G01X1393111D02*
X1392926Y31059D01*
G01X1393296Y32002D02*
X1393665Y31625D01*
G01X1398282Y52301D02*
G03X1398479Y52498I0J197D01*
G01Y52891D02*
G03X1398282Y53088I-197J0D01*
G01Y54269D02*
G03X1398479Y54466I0J197D01*
G01Y54860D02*
G03X1398282Y55057I-197J0D01*
G01Y56238D02*
G03X1398479Y56435I0J197D01*
G01Y56828D02*
G03X1398282Y57025I-197J0D01*
G01Y58206D02*
G03X1398479Y58403I0J197D01*
G01Y58797D02*
G03X1398282Y58994I-197J0D01*
G01Y60175D02*
G03X1398479Y60372I0J197D01*
G01Y60765D02*
G03X1398282Y60962I-197J0D01*
G01X1399974Y46592D02*
Y50726D01*
G01X1398479Y52891D02*
Y52498D01*
G01Y54860D02*
Y54466D01*
G01Y56828D02*
Y56435D01*
G01Y58797D02*
Y58403D01*
G01Y60765D02*
Y60372D01*
G01X1397021Y129269D02*
Y48954D01*
G01X1394659Y129269D02*
Y48954D01*
G01X1397021Y60962D02*
X1398282D01*
G01X1397021Y60175D02*
X1398282D01*
G01X1397021Y58994D02*
X1398282D01*
G01X1397021Y58206D02*
X1398282D01*
G01X1397021Y57025D02*
X1398282D01*
G01X1397021Y56238D02*
X1398282D01*
G01X1397021Y55057D02*
X1398282D01*
G01X1397021Y54269D02*
X1398282D01*
G01X1397021Y53088D02*
X1398282D01*
G01X1397021Y52301D02*
X1398282D01*
G01X1397021Y50726D02*
X1399974D01*
G01X1397021Y50135D02*
X1399974D01*
G01X1394659Y48954D02*
X1399974D01*
G01X1398282Y75923D02*
G03X1398479Y76120I0J197D01*
G01Y76513D02*
G03X1398282Y76710I-197J0D01*
G01Y77891D02*
G03X1398479Y78088I0J197D01*
G01Y78482D02*
G03X1398282Y78679I-197J0D01*
G01Y70017D02*
G03X1398479Y70214I0J197D01*
G01Y70608D02*
G03X1398282Y70805I-197J0D01*
G01Y71986D02*
G03X1398479Y72183I0J197D01*
G01Y72576D02*
G03X1398282Y72773I-197J0D01*
G01Y73954D02*
G03X1398479Y74151I0J197D01*
G01Y74545D02*
G03X1398282Y74742I-197J0D01*
G01X1398479Y70608D02*
Y70214D01*
G01Y72576D02*
Y72183D01*
G01Y74545D02*
Y74151D01*
G01Y76513D02*
Y76120D01*
G01Y78482D02*
Y78088D01*
G01X1397021Y78679D02*
X1398282D01*
G01X1397021Y77891D02*
X1398282D01*
G01X1397021Y76710D02*
X1398282D01*
G01X1397021Y75923D02*
X1398282D01*
G01X1397021Y74742D02*
X1398282D01*
G01X1397021Y73954D02*
X1398282D01*
G01X1397021Y72773D02*
X1398282D01*
G01X1397021Y71986D02*
X1398282D01*
G01X1397021Y70805D02*
X1398282D01*
G01X1397021Y70017D02*
X1398282D01*
G01Y79860D02*
G03X1398479Y80057I0J197D01*
G01Y80450D02*
G03X1398282Y80647I-197J0D01*
G01Y81828D02*
G03X1398479Y82025I0J197D01*
G01Y82419D02*
G03X1398282Y82616I-197J0D01*
G01Y83797D02*
G03X1398479Y83994I0J197D01*
G01Y84387D02*
G03X1398282Y84584I-197J0D01*
G01Y85765D02*
G03X1398479Y85962I0J197D01*
G01Y86356D02*
G03X1398282Y86553I-197J0D01*
G01Y87734D02*
G03X1398479Y87931I0J197D01*
G01Y88324D02*
G03X1398282Y88521I-197J0D01*
G01Y89702D02*
G03X1398479Y89899I0J197D01*
G01Y90293D02*
G03X1398282Y90490I-197J0D01*
G01Y91671D02*
G03X1398479Y91868I0J197D01*
G01Y92261D02*
G03X1398282Y92458I-197J0D01*
G01Y93639D02*
G03X1398479Y93836I0J197D01*
G01Y94230D02*
G03X1398282Y94427I-197J0D01*
G01Y95608D02*
G03X1398479Y95805I0J197D01*
G01Y80450D02*
Y80057D01*
G01Y82419D02*
Y82025D01*
G01Y84387D02*
Y83994D01*
G01Y86356D02*
Y85962D01*
G01Y88324D02*
Y87931D01*
G01Y90293D02*
Y89899D01*
G01Y92261D02*
Y91868D01*
G01Y94230D02*
Y93836D01*
G01X1397021Y95608D02*
X1398282D01*
G01X1397021Y94427D02*
X1398282D01*
G01X1397021Y93639D02*
X1398282D01*
G01X1397021Y92458D02*
X1398282D01*
G01X1397021Y91671D02*
X1398282D01*
G01X1397021Y90490D02*
X1398282D01*
G01X1397021Y89702D02*
X1398282D01*
G01X1397021Y88521D02*
X1398282D01*
G01X1397021Y87734D02*
X1398282D01*
G01X1397021Y86553D02*
X1398282D01*
G01X1397021Y85765D02*
X1398282D01*
G01X1397021Y84584D02*
X1398282D01*
G01X1397021Y83797D02*
X1398282D01*
G01X1397021Y82616D02*
X1398282D01*
G01X1397021Y81828D02*
X1398282D01*
G01X1397021Y80647D02*
X1398282D01*
G01X1397021Y79860D02*
X1398282D01*
G01Y97576D02*
G03X1398479Y97773I0J197D01*
G01Y98167D02*
G03X1398282Y98364I-197J0D01*
G01Y99545D02*
G03X1398479Y99742I0J197D01*
G01Y100135D02*
G03X1398282Y100332I-197J0D01*
G01Y101513D02*
G03X1398479Y101710I0J197D01*
G01Y102104D02*
G03X1398282Y102301I-197J0D01*
G01Y103482D02*
G03X1398479Y103679I0J197D01*
G01Y104072D02*
G03X1398282Y104269I-197J0D01*
G01Y105450D02*
G03X1398479Y105647I0J197D01*
G01Y106041D02*
G03X1398282Y106238I-197J0D01*
G01Y107419D02*
G03X1398479Y107616I0J197D01*
G01Y108009D02*
G03X1398282Y108206I-197J0D01*
G01Y109387D02*
G03X1398479Y109584I0J197D01*
G01Y109978D02*
G03X1398282Y110175I-197J0D01*
G01Y111356D02*
G03X1398479Y111553I0J197D01*
G01Y111946D02*
G03X1398282Y112143I-197J0D01*
G01X1398479Y96198D02*
G03X1398282Y96395I-197J0D01*
G01X1398479Y96198D02*
Y95805D01*
G01Y98167D02*
Y97773D01*
G01Y100135D02*
Y99742D01*
G01Y102104D02*
Y101710D01*
G01Y104072D02*
Y103679D01*
G01Y106041D02*
Y105647D01*
G01Y108009D02*
Y107616D01*
G01Y109978D02*
Y109584D01*
G01Y111946D02*
Y111553D01*
G01X1397021Y112143D02*
X1398282D01*
G01X1397021Y111356D02*
X1398282D01*
G01X1397021Y110175D02*
X1398282D01*
G01X1397021Y109387D02*
X1398282D01*
G01X1397021Y108206D02*
X1398282D01*
G01X1397021Y107419D02*
X1398282D01*
G01X1397021Y106238D02*
X1398282D01*
G01X1397021Y105450D02*
X1398282D01*
G01X1397021Y104269D02*
X1398282D01*
G01X1397021Y103482D02*
X1398282D01*
G01X1397021Y102301D02*
X1398282D01*
G01X1397021Y101513D02*
X1398282D01*
G01X1397021Y100332D02*
X1398282D01*
G01X1397021Y99545D02*
X1398282D01*
G01X1397021Y98364D02*
X1398282D01*
G01X1397021Y97576D02*
X1398282D01*
G01X1397021Y96395D02*
X1398282D01*
G01X1398479Y119820D02*
G03X1398282Y120017I-197J0D01*
G01Y121198D02*
G03X1398479Y121395I0J197D01*
G01Y121789D02*
G03X1398282Y121986I-197J0D01*
G01Y123167D02*
G03X1398479Y123364I0J197D01*
G01Y123758D02*
G03X1398282Y123954I-197J-1D01*
G01Y125135D02*
G03X1398479Y125332I0J197D01*
G01Y125726D02*
G03X1398282Y125923I-197J0D01*
G01Y113324D02*
G03X1398479Y113521I0J197D01*
G01Y113915D02*
G03X1398282Y114112I-197J0D01*
G01Y115293D02*
G03X1398479Y115490I0J197D01*
G01Y115883D02*
G03X1398282Y116080I-197J0D01*
G01Y117261D02*
G03X1398479Y117458I0J197D01*
G01Y117852D02*
G03X1398282Y118049I-197J0D01*
G01Y119230D02*
G03X1398479Y119427I0J197D01*
G01X1399974Y127498D02*
Y131632D01*
G01X1398479Y113915D02*
Y113521D01*
G01Y115883D02*
Y115490D01*
G01Y117852D02*
Y117458D01*
G01Y119820D02*
Y119427D01*
G01Y121789D02*
Y121395D01*
G01Y123758D02*
Y123364D01*
G01Y125726D02*
Y125332D01*
G01X1399974Y128088D02*
X1397021D01*
G01Y127498D02*
X1399974D01*
G01X1397021Y125923D02*
X1398282D01*
G01X1397021Y125135D02*
X1398282D01*
G01X1397021Y123954D02*
X1398282D01*
G01X1397021Y123167D02*
X1398282D01*
G01X1397021Y121986D02*
X1398282D01*
G01X1397021Y121198D02*
X1398282D01*
G01X1397021Y120017D02*
X1398282D01*
G01X1397021Y119230D02*
X1398282D01*
G01X1397021Y118049D02*
X1398282D01*
G01X1397021Y117261D02*
X1398282D01*
G01X1397021Y116080D02*
X1398282D01*
G01X1397021Y115293D02*
X1398282D01*
G01X1397021Y114112D02*
X1398282D01*
G01X1397021Y113324D02*
X1398282D01*
G01X1399974Y131632D02*
G03X1399186Y132419I-787J0D01*
G01X1399974Y129269D02*
X1394659D01*
G01X1398282Y160962D02*
G03X1398479Y161159I0J197D01*
G01Y161553D02*
G03X1398282Y161750I-197J0D01*
G01X1399186Y154466D02*
G03X1399974Y155254I0J788D01*
G01D02*
Y159387D01*
G01X1398479Y161553D02*
Y161159D01*
G01X1397021Y237931D02*
Y157616D01*
G01X1394659Y237931D02*
Y157616D01*
G01X1397021Y161750D02*
X1398282D01*
G01X1397021Y160962D02*
X1398282D01*
G01X1397021Y159387D02*
X1399974D01*
G01X1397021Y158797D02*
X1399974D01*
G01X1394659Y157616D02*
X1399974D01*
G01X1398282Y164899D02*
G03X1398479Y165096I0J197D01*
G01Y165490D02*
G03X1398282Y165687I-197J0D01*
G01Y166868D02*
G03X1398479Y167065I0J197D01*
G01Y167458D02*
G03X1398282Y167655I-197J0D01*
G01Y168836D02*
G03X1398479Y169033I0J197D01*
G01Y169427D02*
G03X1398282Y169624I-197J0D01*
G01Y162931D02*
G03X1398479Y163128I0J197D01*
G01Y163521D02*
G03X1398282Y163718I-197J0D01*
G01X1398479Y163521D02*
Y163128D01*
G01Y165490D02*
Y165096D01*
G01Y167458D02*
Y167065D01*
G01Y169427D02*
Y169033D01*
G01X1397021Y169624D02*
X1398282D01*
G01X1397021Y168836D02*
X1398282D01*
G01X1397021Y167655D02*
X1398282D01*
G01X1397021Y166868D02*
X1398282D01*
G01X1397021Y165687D02*
X1398282D01*
G01X1397021Y164899D02*
X1398282D01*
G01X1397021Y163718D02*
X1398282D01*
G01X1397021Y162931D02*
X1398282D01*
G01Y178679D02*
G03X1398479Y178876I0J197D01*
G01Y179269D02*
G03X1398282Y179466I-197J0D01*
G01Y180647D02*
G03X1398479Y180844I0J197D01*
G01Y181238D02*
G03X1398282Y181435I-197J0D01*
G01Y182616D02*
G03X1398479Y182813I0J197D01*
G01Y183206D02*
G03X1398282Y183403I-197J0D01*
G01Y184584D02*
G03X1398479Y184781I0J197D01*
G01Y185175D02*
G03X1398282Y185372I-197J0D01*
G01Y186553D02*
G03X1398479Y186750I0J197D01*
G01Y187143D02*
G03X1398282Y187340I-197J0D01*
G01Y188521D02*
G03X1398479Y188718I0J197D01*
G01Y189112D02*
G03X1398282Y189309I-197J0D01*
G01Y190490D02*
G03X1398479Y190687I0J197D01*
G01Y191080D02*
G03X1398282Y191277I-197J0D01*
G01Y192458D02*
G03X1398479Y192655I0J197D01*
G01Y193049D02*
G03X1398282Y193246I-197J0D01*
G01Y194427D02*
G03X1398479Y194624I0J197D01*
G01Y179269D02*
Y178876D01*
G01Y181238D02*
Y180844D01*
G01Y183206D02*
Y182813D01*
G01Y185175D02*
Y184781D01*
G01Y187143D02*
Y186750D01*
G01Y189112D02*
Y188718D01*
G01Y191080D02*
Y190687D01*
G01Y193049D02*
Y192655D01*
G01Y195017D02*
Y194624D01*
G01X1397021Y194427D02*
X1398282D01*
G01X1397021Y193246D02*
X1398282D01*
G01X1397021Y192458D02*
X1398282D01*
G01X1397021Y191277D02*
X1398282D01*
G01X1397021Y190490D02*
X1398282D01*
G01X1397021Y189309D02*
X1398282D01*
G01X1397021Y188521D02*
X1398282D01*
G01X1397021Y187340D02*
X1398282D01*
G01X1397021Y186553D02*
X1398282D01*
G01X1397021Y185372D02*
X1398282D01*
G01X1397021Y184584D02*
X1398282D01*
G01X1397021Y183403D02*
X1398282D01*
G01X1397021Y182616D02*
X1398282D01*
G01X1397021Y181435D02*
X1398282D01*
G01X1397021Y180647D02*
X1398282D01*
G01X1397021Y179466D02*
X1398282D01*
G01X1397021Y178679D02*
X1398282D01*
G01Y206238D02*
G03X1398479Y206435I0J197D01*
G01Y206828D02*
G03X1398282Y207025I-197J0D01*
G01Y208206D02*
G03X1398479Y208403I0J197D01*
G01Y208797D02*
G03X1398282Y208994I-197J0D01*
G01Y210175D02*
G03X1398479Y210372I0J197D01*
G01Y210765D02*
G03X1398282Y210962I-197J0D01*
G01X1398479Y202891D02*
G03X1398282Y203088I-197J0D01*
G01Y204269D02*
G03X1398479Y204466I0J197D01*
G01Y204860D02*
G03X1398282Y205057I-197J0D01*
G01X1398479Y195017D02*
G03X1398282Y195214I-197J0D01*
G01Y196395D02*
G03X1398479Y196592I0J197D01*
G01Y196986D02*
G03X1398282Y197183I-197J0D01*
G01Y198364D02*
G03X1398479Y198561I0J197D01*
G01Y198954D02*
G03X1398282Y199151I-197J0D01*
G01Y200332D02*
G03X1398479Y200529I0J197D01*
G01Y200923D02*
G03X1398282Y201120I-197J0D01*
G01Y202301D02*
G03X1398479Y202498I0J197D01*
G01Y196986D02*
Y196592D01*
G01Y198954D02*
Y198561D01*
G01Y200923D02*
Y200529D01*
G01Y202891D02*
Y202498D01*
G01Y206828D02*
Y206435D01*
G01Y204860D02*
Y204466D01*
G01Y208797D02*
Y208403D01*
G01Y210765D02*
Y210372D01*
G01X1397021Y210962D02*
X1398282D01*
G01X1397021Y210175D02*
X1398282D01*
G01X1397021Y208994D02*
X1398282D01*
G01X1397021Y208206D02*
X1398282D01*
G01X1397021Y207025D02*
X1398282D01*
G01X1397021Y206238D02*
X1398282D01*
G01X1397021Y205057D02*
X1398282D01*
G01X1397021Y204269D02*
X1398282D01*
G01X1397021Y203088D02*
X1398282D01*
G01X1397021Y202301D02*
X1398282D01*
G01X1397021Y201120D02*
X1398282D01*
G01X1397021Y200332D02*
X1398282D01*
G01X1397021Y199151D02*
X1398282D01*
G01X1397021Y198364D02*
X1398282D01*
G01X1397021Y197183D02*
X1398282D01*
G01X1397021Y196395D02*
X1398282D01*
G01X1397021Y195214D02*
X1398282D01*
G01Y212143D02*
G03X1398479Y212340I0J197D01*
G01Y212734D02*
G03X1398282Y212931I-197J0D01*
G01Y214112D02*
G03X1398479Y214309I0J197D01*
G01Y214702D02*
G03X1398282Y214899I-197J0D01*
G01Y216080D02*
G03X1398479Y216277I0J197D01*
G01Y216671D02*
G03X1398282Y216868I-197J0D01*
G01Y218049D02*
G03X1398479Y218246I0J197D01*
G01Y218639D02*
G03X1398282Y218836I-197J0D01*
G01Y220017D02*
G03X1398479Y220214I0J197D01*
G01Y220608D02*
G03X1398282Y220805I-197J0D01*
G01Y221986D02*
G03X1398479Y222183I0J197D01*
G01Y222576D02*
G03X1398282Y222773I-197J0D01*
G01Y223954D02*
G03X1398479Y224151I0J197D01*
G01Y224545D02*
G03X1398282Y224742I-197J0D01*
G01Y225923D02*
G03X1398479Y226120I0J197D01*
G01Y226513D02*
G03X1398282Y226710I-197J0D01*
G01X1398479Y212734D02*
Y212340D01*
G01Y214702D02*
Y214309D01*
G01Y216671D02*
Y216277D01*
G01Y218639D02*
Y218246D01*
G01Y220608D02*
Y220214D01*
G01Y222576D02*
Y222183D01*
G01Y224545D02*
Y224151D01*
G01Y226513D02*
Y226120D01*
G01X1397021Y226710D02*
X1398282D01*
G01X1397021Y225923D02*
X1398282D01*
G01X1397021Y224742D02*
X1398282D01*
G01X1397021Y223954D02*
X1398282D01*
G01X1397021Y222773D02*
X1398282D01*
G01X1397021Y221986D02*
X1398282D01*
G01X1397021Y220805D02*
X1398282D01*
G01X1397021Y220017D02*
X1398282D01*
G01X1397021Y218836D02*
X1398282D01*
G01X1397021Y218049D02*
X1398282D01*
G01X1397021Y216868D02*
X1398282D01*
G01X1397021Y216080D02*
X1398282D01*
G01X1397021Y214899D02*
X1398282D01*
G01X1397021Y214112D02*
X1398282D01*
G01X1397021Y212931D02*
X1398282D01*
G01X1397021Y212143D02*
X1398282D01*
G01Y227891D02*
G03X1398479Y228088I0J197D01*
G01Y228482D02*
G03X1398282Y228679I-197J0D01*
G01Y229860D02*
G03X1398479Y230057I0J197D01*
G01Y230450D02*
G03X1398282Y230647I-197J0D01*
G01Y231828D02*
G03X1398479Y232025I0J197D01*
G01Y232419D02*
G03X1398282Y232616I-197J0D01*
G01Y233797D02*
G03X1398479Y233994I0J197D01*
G01Y234387D02*
G03X1398282Y234584I-197J0D01*
G01X1399974Y240293D02*
G03X1399186Y241080I-787J0D01*
G01X1400171Y250962D02*
Y242104D01*
G01X1399974Y236159D02*
Y240293D01*
G01X1398479Y228482D02*
Y228088D01*
G01Y230450D02*
Y230057D01*
G01Y232419D02*
Y232025D01*
G01Y234387D02*
Y233994D01*
G01X1399974Y237931D02*
X1394659D01*
G01X1399974Y236750D02*
X1397021D01*
G01Y236159D02*
X1399974D01*
G01X1397021Y234584D02*
X1398282D01*
G01X1397021Y233797D02*
X1398282D01*
G01X1397021Y232616D02*
X1398282D01*
G01X1397021Y231828D02*
X1398282D01*
G01X1397021Y230647D02*
X1398282D01*
G01X1397021Y229860D02*
X1398282D01*
G01X1397021Y228679D02*
X1398282D01*
G01X1397021Y227891D02*
X1398282D01*
G01X1399383Y334663D02*
Y360580D01*
G01X1397218Y368808D02*
X1393609Y369295D01*
G01X1396496Y375142D02*
X1395774Y374654D01*
G01X1397218Y376116D02*
X1396496Y375142D01*
G01X1397218Y377091D02*
Y376116D01*
G01X1396496Y393168D02*
X1397218Y392194D01*
G01X1395774Y390732D02*
X1394331Y390245D01*
G01X1396496Y391219D02*
X1395774Y390732D01*
G01X1397218Y392194D02*
X1396496Y391219D01*
G01Y383911D02*
X1397218Y384398D01*
G01Y383911D02*
X1396496D01*
G01X1397218Y384398D02*
Y383911D01*
G01X1395052Y379039D02*
X1396496Y378065D01*
G01X1394331Y379039D02*
X1395052D01*
G01X1392887Y378065D02*
X1394331Y379039D01*
G01X1396496Y378065D02*
X1397218Y377091D01*
G01X1396496Y400963D02*
X1397218Y399989D01*
G01X1395774Y401451D02*
X1396496Y400963D01*
G01X1394331Y401938D02*
X1395774Y401451D01*
G01Y398528D02*
X1394331Y398040D01*
G01X1396496Y399015D02*
X1395774Y398528D01*
G01X1397218Y399989D02*
X1396496Y399015D01*
G01X1395774Y393655D02*
X1396496Y393168D01*
G01X1394331Y394143D02*
X1395774Y393655D01*
G01X1397831Y608621D02*
Y614921D01*
X1396891Y613661D01*
G01Y608621D02*
X1398771D01*
G01X1404131Y614921D02*
X1403504Y614711D01*
X1403034Y614186D01*
X1402721Y613556D01*
X1402486Y612716D01*
X1402408Y611771D01*
X1402486Y610826D01*
X1402721Y609986D01*
X1403034Y609356D01*
X1403504Y608831D01*
X1404131Y608621D01*
X1404758Y608831D01*
X1405228Y609356D01*
X1405541Y609986D01*
X1405776Y610826D01*
X1405854Y611771D01*
X1405776Y612716D01*
X1405541Y613556D01*
X1405228Y614186D01*
X1404758Y614711D01*
X1404131Y614921D01*
G01X1418748Y70441D02*
X1418246Y69948D01*
G01X1417492Y70933D02*
X1417743Y71179D01*
G01X1418748Y74378D02*
X1417995Y73639D01*
G01X1417492Y74870D02*
X1417743Y75116D01*
G01Y71179D02*
X1417995Y71671D01*
G01X1417743Y75116D02*
X1417995Y75608D01*
G01X1419000Y71179D02*
X1418748Y70441D01*
G01X1419000Y75116D02*
X1418748Y74378D01*
G01X1418246Y69948D02*
X1416989Y69456D01*
G01Y70687D02*
X1417492Y70933D01*
G01X1416989Y74624D02*
X1417492Y74870D01*
G01X1419000Y72163D02*
Y71179D01*
G01Y76100D02*
Y75116D01*
G01Y78561D02*
Y77330D01*
G01X1417995Y75608D02*
Y76100D01*
G01Y71671D02*
Y72409D01*
G01X1410958Y77330D02*
Y78561D01*
G01Y73393D02*
Y74624D01*
G01Y69456D02*
Y70687D01*
G01X1418748Y76838D02*
X1419000Y76100D01*
G01X1417995D02*
X1417743Y76838D01*
G01X1418748Y72901D02*
X1419000Y72163D01*
G01X1417995Y72409D02*
X1417743Y72901D01*
G01X1418246Y77330D02*
X1418748Y76838D01*
G01X1417743D02*
X1417241Y77330D01*
G01X1417995Y73639D02*
X1418748Y72901D01*
G01X1417743D02*
X1417492Y73147D01*
G01D02*
X1416989Y73393D01*
G01X1410958Y78561D02*
X1419000D01*
G01X1417241Y77330D02*
X1410958D01*
G01X1419000D02*
X1418246D01*
G01X1410958Y74624D02*
X1416989D01*
G01Y73393D02*
X1410958D01*
G01Y70687D02*
X1416989D01*
G01Y69456D02*
X1410958D01*
G01X1421764Y93078D02*
X1422518Y94309D01*
G01X1417743Y82252D02*
X1417995Y82744D01*
G01X1420759Y92340D02*
X1421764Y93078D01*
G01X1418748Y81513D02*
X1418246Y81021D01*
G01X1417492Y82006D02*
X1417743Y82252D01*
G01X1418748Y85450D02*
X1417995Y84712D01*
G01X1417492Y85943D02*
X1417743Y86189D01*
G01X1416738Y92094D02*
X1417492Y92832D01*
G01X1415984Y93078D02*
X1416487Y93570D01*
G01X1421261Y94555D02*
X1420759Y93817D01*
G01X1416487Y93570D02*
X1416989Y94309D01*
G01X1417492Y92832D02*
X1418246Y94063D01*
G01X1417743Y86189D02*
X1417995Y86681D01*
G01X1419000Y82252D02*
X1418748Y81513D01*
G01X1419000Y86189D02*
X1418748Y85450D01*
G01X1421513Y95293D02*
X1421261Y94555D01*
G01X1416989Y94309D02*
X1417241Y95047D01*
G01X1422518Y94309D02*
X1422769Y95539D01*
G01X1418246Y94063D02*
X1418497Y95293D01*
G01X1418246Y81021D02*
X1416989Y80529D01*
G01Y81759D02*
X1417492Y82006D01*
G01X1416989Y85696D02*
X1417492Y85943D01*
G01X1420759Y93817D02*
X1420005Y93324D01*
G01X1422769Y95539D02*
Y96523D01*
G01X1421513Y96769D02*
Y95293D01*
G01X1420005Y93324D02*
Y92094D01*
G01X1419000Y83236D02*
Y82252D01*
G01Y87173D02*
Y86189D01*
G01Y89633D02*
Y88403D01*
G01X1418497Y95293D02*
Y96523D01*
G01X1417995Y86681D02*
Y87173D01*
G01Y82744D02*
Y83482D01*
G01X1417241Y95047D02*
Y96769D01*
G01X1412215D02*
Y95047D01*
G01X1410958Y88403D02*
Y89633D01*
G01Y84466D02*
Y85696D01*
G01Y80529D02*
Y81759D01*
G01Y96523D02*
Y95293D01*
G01D02*
X1411209Y94063D01*
G01X1420005Y92094D02*
X1420759Y92340D01*
G01X1415230Y92832D02*
X1415984Y93078D01*
G01X1415482Y91602D02*
X1416738Y92094D01*
G01X1418748Y87911D02*
X1419000Y87173D01*
G01X1417995D02*
X1417743Y87911D01*
G01X1418748Y83974D02*
X1419000Y83236D01*
G01X1412215Y95047D02*
X1412466Y94309D01*
G01X1417995Y83482D02*
X1417743Y83974D01*
G01X1411209Y94063D02*
X1411963Y92832D01*
G01X1412466Y94309D02*
X1412969Y93570D01*
G01X1418246Y88403D02*
X1418748Y87911D01*
G01X1417743D02*
X1417241Y88403D01*
G01X1417995Y84712D02*
X1418748Y83974D01*
G01X1417743D02*
X1417492Y84220D01*
G01X1411963Y92832D02*
X1412969Y92094D01*
G01Y93570D02*
X1413722Y93078D01*
G01X1417492Y84220D02*
X1416989Y84466D01*
G01X1412969Y92094D02*
X1414225Y91602D01*
G01X1413722Y93078D02*
X1414476Y92832D01*
G01D02*
X1415230D01*
G01X1414225Y91602D02*
X1415482D01*
G01X1410958Y89633D02*
X1419000D01*
G01X1417241Y88403D02*
X1410958D01*
G01X1419000D02*
X1418246D01*
G01X1410958Y85696D02*
X1416989D01*
G01Y84466D02*
X1410958D01*
G01Y81759D02*
X1416989D01*
G01Y80529D02*
X1410958D01*
G01X1412969Y98246D02*
X1412466Y97508D01*
G01X1411963Y98984D02*
X1411209Y97754D01*
G01X1414476Y102921D02*
X1416989Y107596D01*
G01Y105874D02*
X1415230Y102429D01*
G01X1412466Y97508D02*
X1412215Y96769D01*
G01X1413722Y98738D02*
X1412969Y98246D01*
G01X1419502Y102921D02*
X1418748Y102429D01*
G01X1412969Y99722D02*
X1411963Y98984D01*
G01X1411209Y97754D02*
X1410958Y96523D01*
G01X1422769Y111041D02*
Y109565D01*
G01X1417995Y117931D02*
Y111041D01*
G01X1416487D02*
Y117931D01*
G01X1410958Y109565D02*
Y111041D01*
G01X1422769Y96523D02*
X1422518Y97754D01*
G01X1418497Y96523D02*
X1418246Y97754D01*
G01X1421261Y97508D02*
X1421513Y96769D01*
G01X1414476Y98984D02*
X1413722Y98738D01*
G01X1414225Y100214D02*
X1412969Y99722D01*
G01X1417241Y96769D02*
X1416989Y97508D01*
G01X1418748Y102429D02*
X1416989Y105874D01*
G01Y107596D02*
X1419502Y102921D01*
G01X1422518Y97754D02*
X1421764Y98984D01*
G01X1420759Y98246D02*
X1421261Y97508D01*
G01X1418246Y97754D02*
X1417241Y99230D01*
G01X1416989Y97508D02*
X1416487Y98246D01*
G01D02*
X1415984Y98738D01*
G01X1421764Y98984D02*
X1420759Y99722D01*
G01X1415230Y102429D02*
X1414476Y102921D01*
G01X1420005Y98738D02*
X1420759Y98246D01*
G01Y99722D02*
X1419502Y100214D01*
G01X1419251Y98984D02*
X1420005Y98738D01*
G01X1415984D02*
X1415230Y98984D01*
G01X1417743Y99230D02*
X1419251Y98984D01*
G01X1419502Y100214D02*
X1417743Y100460D01*
G01X1417995Y111041D02*
X1422769D01*
G01X1410958D02*
X1416487D01*
G01X1422769Y109565D02*
X1410958D01*
G01X1417743Y100460D02*
X1415984D01*
G01X1417241Y99230D02*
X1417743D01*
G01X1415230Y98984D02*
X1414476D01*
G01X1415984Y100460D02*
X1414225Y100214D01*
G01X1422769Y119407D02*
Y117931D01*
G01X1410958D02*
Y119407D01*
G01D02*
X1422769D01*
G01X1416487Y117931D02*
X1410958D01*
G01X1422769D02*
X1417995D01*
G01X1431076Y10352D02*
G03X1433045Y8383I1969J0D01*
G01X1431076Y10352D02*
G03X1433045Y8383I1969J0D01*
G01X1431076Y10352D02*
Y348443D01*
G01Y10352D02*
Y27084D01*
G01X1433045Y8383D02*
X1459422D01*
G01X1433045D02*
X1459422D01*
G01X1438163Y29053D02*
G03X1440131Y31021I0J1968D01*
G01X1438163Y29053D02*
G03X1440131Y31021I0J1968D01*
G01X1433045Y29053D02*
G03X1431076Y27084I0J-1969D01*
G01X1433045Y29053D02*
G03X1431076Y27084I0J-1969D01*
G01X1438163Y29053D02*
X1433045D01*
G01X1438163D02*
X1433045D01*
G01X1440131Y156336D02*
Y31021D01*
G01Y156336D02*
Y31021D01*
G01X1437183Y114991D02*
X1437297Y115214D01*
G01X1437183Y116776D02*
X1437297Y116999D01*
G01X1437183Y120011D02*
X1437297Y120234D01*
G01X1437183Y121796D02*
X1437297Y122019D01*
G01X1437753Y114991D02*
X1437639Y114657D01*
G01X1437753Y116776D02*
X1437639Y116441D01*
G01X1437753Y120011D02*
X1437639Y119676D01*
G01X1437753Y121796D02*
X1437639Y121461D01*
G01X1438778Y125700D02*
X1438892Y126258D01*
G01X1439348Y125588D02*
X1439462Y126258D01*
G01D02*
X1439348Y126927D01*
G01X1434108Y126258D02*
X1434222Y125588D01*
G01X1438892Y126258D02*
X1438778Y126815D01*
G01X1434677Y126258D02*
X1434791Y125700D01*
G01X1437639Y114657D02*
X1437411Y114433D01*
G01X1437070Y114880D02*
X1437183Y114991D01*
G01X1437639Y116441D02*
X1437297Y116107D01*
G01X1437070Y116665D02*
X1437183Y116776D01*
G01X1437639Y119676D02*
X1437411Y119453D01*
G01X1437070Y119899D02*
X1437183Y120011D01*
G01X1437639Y121461D02*
X1437297Y121126D01*
G01X1437070Y121684D02*
X1437183Y121796D01*
G01X1438550Y125365D02*
X1438778Y125700D01*
G01X1435019Y127150D02*
X1434791Y126815D01*
G01X1439006Y125031D02*
X1439348Y125588D01*
G01X1434563Y127485D02*
X1434222Y126927D01*
G01X1434791Y126815D02*
X1434677Y126258D01*
G01X1434222Y126927D02*
X1434108Y126258D01*
G01X1437753Y115437D02*
Y114991D01*
G01Y117222D02*
Y116776D01*
G01Y118338D02*
Y117780D01*
G01Y120457D02*
Y120011D01*
G01Y122242D02*
Y121796D01*
G01Y123358D02*
Y122800D01*
G01X1437297Y122019D02*
Y122242D01*
G01Y120234D02*
Y120569D01*
G01Y116999D02*
Y117222D01*
G01Y115214D02*
Y115549D01*
G01X1434108Y122800D02*
Y123358D01*
G01Y121015D02*
Y121572D01*
G01Y117780D02*
Y118338D01*
G01Y119230D02*
Y119788D01*
G01Y115995D02*
Y116553D01*
G01Y114210D02*
Y114768D01*
G01X1437639Y122576D02*
X1437753Y122242D01*
G01X1437297D02*
X1437183Y122576D01*
G01X1437639Y120792D02*
X1437753Y120457D01*
G01X1437639Y117557D02*
X1437753Y117222D01*
G01X1437297D02*
X1437183Y117557D01*
G01X1437639Y115772D02*
X1437753Y115437D01*
G01X1438665Y124696D02*
X1439006Y125031D01*
G01X1434905Y127819D02*
X1434563Y127485D01*
G01X1437297Y120569D02*
X1437183Y120792D01*
G01X1437297Y115549D02*
X1437183Y115772D01*
G01X1439348Y126927D02*
X1439006Y127485D01*
G01X1434222Y125588D02*
X1434563Y125031D01*
G01X1438778Y126815D02*
X1438550Y127150D01*
G01X1437411Y114433D02*
X1436842Y114210D01*
G01Y114768D02*
X1437070Y114880D01*
G01X1436842Y116553D02*
X1437070Y116665D01*
G01X1436842Y119788D02*
X1437070Y119899D01*
G01X1436842Y121572D02*
X1437070Y121684D01*
G01X1438209Y124473D02*
X1438665Y124696D01*
G01X1437867Y124919D02*
X1438550Y125365D01*
G01X1435702Y127596D02*
X1435019Y127150D01*
G01X1434791Y125700D02*
X1435019Y125365D01*
G01X1437867Y124361D02*
X1438209Y124473D01*
G01X1437411Y119453D02*
X1436842Y119230D01*
G01X1435361Y128043D02*
X1434905Y127819D01*
G01X1439006Y127485D02*
X1438665Y127819D01*
G01X1437411Y122800D02*
X1437639Y122576D01*
G01X1437183D02*
X1436956Y122800D01*
G01X1434563Y125031D02*
X1434905Y124696D01*
G01X1437297Y121126D02*
X1437639Y120792D01*
G01X1437183D02*
X1437070Y120903D01*
G01X1437411Y117780D02*
X1437639Y117557D01*
G01X1437183D02*
X1436956Y117780D01*
G01X1435702Y128154D02*
X1435361Y128043D01*
G01X1437297Y116107D02*
X1437639Y115772D01*
G01X1437183D02*
X1437070Y115883D01*
G01X1438550Y127150D02*
X1437867Y127596D01*
G01X1435019Y125365D02*
X1435702Y124919D01*
G01X1438665Y127819D02*
X1438209Y128043D01*
G01X1434905Y124696D02*
X1435361Y124473D01*
G01X1437070Y120903D02*
X1436842Y121015D01*
G01X1437070Y115883D02*
X1436842Y115995D01*
G01X1438209Y128043D02*
X1437867Y128154D01*
G01X1435361Y124473D02*
X1435702Y124361D01*
G01X1437867Y128154D02*
X1437297Y128265D01*
G01X1435702Y124361D02*
X1436272Y124250D01*
G01X1437867Y127596D02*
X1437183Y127708D01*
G01X1435702Y124919D02*
X1436386Y124808D01*
G01X1437297Y128265D02*
X1436272D01*
G01X1437183Y127708D02*
X1436386D01*
G01Y124808D02*
X1437183D01*
G01X1436272Y124250D02*
X1437297D01*
G01X1434108Y123358D02*
X1437753D01*
G01X1436956Y122800D02*
X1434108D01*
G01X1437753D02*
X1437411D01*
G01X1434108Y121572D02*
X1436842D01*
G01Y121015D02*
X1434108D01*
G01Y119788D02*
X1436842D01*
G01Y119230D02*
X1434108D01*
G01Y118338D02*
X1437753D01*
G01X1436956Y117780D02*
X1434108D01*
G01X1437753D02*
X1437411D01*
G01X1434108Y116553D02*
X1436842D01*
G01Y115995D02*
X1434108D01*
G01Y114768D02*
X1436842D01*
G01Y114210D02*
X1434108D01*
G01X1436386Y127708D02*
X1435702Y127596D01*
G01X1437183Y124808D02*
X1437867Y124919D01*
G01X1436272Y128265D02*
X1435702Y128154D01*
G01X1437297Y124250D02*
X1437867Y124361D01*
G01X1439462Y132504D02*
Y131835D01*
G01Y136297D02*
Y135628D01*
G01X1437753Y130943D02*
Y129158D01*
G01X1437297D02*
Y130943D01*
G01Y135628D02*
Y132504D01*
G01X1436614D02*
Y135628D01*
G01X1436386Y130943D02*
Y129158D01*
G01X1435930D02*
Y130943D01*
G01X1434108Y135628D02*
Y136297D01*
G01Y131835D02*
Y132504D01*
G01Y136297D02*
X1439462D01*
G01X1436614Y135628D02*
X1434108D01*
G01X1439462D02*
X1437297D01*
G01Y132504D02*
X1439462D01*
G01X1434108D02*
X1436614D01*
G01X1439462Y131835D02*
X1434108D01*
G01X1437297Y130943D02*
X1437753D01*
G01X1435930D02*
X1436386D01*
G01Y129158D02*
X1435930D01*
G01X1437753D02*
X1437297D01*
G01X1440131Y156336D02*
G03X1438163Y158305I-1968J1D01*
G01X1431076Y160273D02*
G03X1433045Y158305I1969J1D01*
G01X1431076Y160273D02*
G03X1433045Y158305I1969J1D01*
G01X1440131Y156336D02*
G03X1438163Y158305I-1968J1D01*
G01X1431076Y177006D02*
Y160273D01*
G01X1433045Y158305D02*
X1438163D01*
G01X1433045D02*
X1438163D01*
G01X1433045Y178974D02*
G03X1431076Y177006I0J-1969D01*
G01X1433045Y178974D02*
G03X1431076Y177006I0J-1969D01*
G01X1459422Y178974D02*
X1433045D01*
G01X1459422D02*
X1433045D01*
G01X1441982Y197370D02*
Y197806D01*
G01Y198677D02*
Y199112D01*
G01X1441129Y200746D02*
Y195628D01*
G01X1440489Y198677D02*
Y200746D01*
G01Y195628D02*
Y198023D01*
G01X1437503D02*
Y195628D01*
G01Y200746D02*
Y198677D01*
G01X1436863Y195628D02*
Y200746D01*
G01X1440489D02*
X1441129D01*
G01X1436863D02*
X1437503D01*
G01X1441982Y199112D02*
X1443688D01*
G01X1437503Y198677D02*
X1440489D01*
G01X1443688D02*
X1441982D01*
G01X1440489Y198023D02*
X1437503D01*
G01X1441982Y197806D02*
X1443688D01*
G01Y197370D02*
X1441982D01*
G01X1437503Y195628D02*
X1436863D01*
G01X1441129D02*
X1440489D01*
G01X1441641Y372042D02*
X1442362Y371067D01*
G01X1440919Y372529D02*
X1441641Y372042D01*
G01X1440197Y372529D02*
X1440919D01*
G01X1439475Y372042D02*
X1440197Y372529D01*
G01X1438753Y371067D02*
X1439475Y372042D01*
G01X1438753Y370093D02*
Y371067D01*
G01X1439475Y369119D02*
X1438753Y370093D01*
G01X1440197Y368631D02*
X1439475Y369119D01*
G01X1440919Y368631D02*
X1440197D01*
G01X1441641Y369119D02*
X1440919Y368631D01*
G01X1442362Y370093D02*
X1441641Y369119D01*
G01Y378863D02*
X1442362Y379837D01*
G01X1441641Y377888D02*
Y378863D01*
G01X1442362Y376914D02*
X1441641Y377888D01*
G01X1438753Y377401D02*
X1442362Y376914D01*
G01X1438753Y380324D02*
Y377401D01*
G01Y395915D02*
Y392017D01*
G01X1441641Y402248D02*
X1442362Y403223D01*
G01X1441641Y401274D02*
Y402248D01*
G01X1442362Y400300D02*
X1441641Y401274D01*
G01X1438753Y400787D02*
X1442362Y400300D01*
G01X1438753Y403710D02*
Y400787D01*
G01X1443806Y394453D02*
X1441641Y394940D01*
G01D02*
X1438753Y395915D01*
G01X1451898Y-574484D02*
Y-664614D01*
G01X1454173Y-74767D02*
X1454895Y-73792D01*
G01X1454173Y-75741D02*
Y-74767D01*
G01X1454895Y-76716D02*
X1454173Y-75741D01*
G01X1455617Y-77203D02*
X1454895Y-76716D01*
G01X1456339Y-77690D02*
X1455617Y-77203D01*
G01X1457060Y-77690D02*
X1456339D01*
G01X1455617Y-69408D02*
X1454895Y-68920D01*
G01X1456339Y-69895D02*
X1455617Y-69408D01*
G01X1457060Y-69895D02*
X1456339D01*
G01X1452008Y-69408D02*
X1451286Y-68920D01*
G01X1452730Y-69408D02*
X1452008D01*
G01X1453452Y-68920D02*
X1452730Y-69408D01*
G01X1458504Y-68920D02*
X1457060Y-69895D01*
G01X1453452Y-73792D02*
X1454173Y-74767D01*
G01X1452730Y-73305D02*
X1453452Y-73792D01*
G01X1452008Y-73305D02*
X1452730D01*
G01X1451286Y-73792D02*
X1452008Y-73305D01*
G01X1450564Y-74767D02*
X1451286Y-73792D01*
G01X1450564Y-75741D02*
Y-74767D01*
G01X1451286Y-76716D02*
X1450564Y-75741D01*
G01X1452008Y-77203D02*
X1451286Y-76716D01*
G01X1452730Y-77203D02*
X1452008D01*
G01X1453452Y-76716D02*
X1452730Y-77203D01*
G01X1454173Y-75741D02*
X1453452Y-76716D01*
G01X1458504D02*
X1457060Y-77690D01*
G01X1459226Y-75741D02*
X1458504Y-76716D01*
G01Y-73792D02*
X1459226Y-74767D01*
G01X1457782Y-73305D02*
X1458504Y-73792D01*
G01X1457060Y-72818D02*
X1457782Y-73305D01*
G01X1456339Y-72818D02*
X1457060D01*
G01X1454895Y-73792D02*
X1456339Y-72818D01*
G01X1454895Y-65997D02*
X1456339Y-65023D01*
G01X1454173Y-66972D02*
X1454895Y-65997D01*
G01X1454173Y-67946D02*
Y-66972D01*
G01X1454895Y-68920D02*
X1454173Y-67946D01*
G01X1458504Y-65997D02*
X1459226Y-66972D01*
G01X1457782Y-65510D02*
X1458504Y-65997D01*
G01X1457060Y-65023D02*
X1457782Y-65510D01*
G01X1456339Y-65023D02*
X1457060D01*
G01X1450564Y-49920D02*
Y-53817D01*
G01X1458504Y-60151D02*
X1459226Y-59664D01*
G01Y-60151D02*
X1458504D01*
G01X1453452Y-65997D02*
X1454173Y-66972D01*
G01X1452730Y-65510D02*
X1453452Y-65997D01*
G01X1452008Y-65510D02*
X1452730D01*
G01X1451286Y-65997D02*
X1452008Y-65510D01*
G01X1450564Y-66972D02*
X1451286Y-65997D01*
G01X1450564Y-67946D02*
Y-66972D01*
G01X1451286Y-68920D02*
X1450564Y-67946D01*
G01X1454173D02*
X1453452Y-68920D01*
G01X1459226Y-67946D02*
X1458504Y-68920D01*
G01X1452008Y-50407D02*
X1450564Y-49920D01*
G01X1453452Y-50894D02*
X1452008Y-50407D01*
G01X1455617Y-51381D02*
X1453452Y-50894D01*
G01X1459226Y-51868D02*
X1455617Y-51381D01*
G01X1458504Y-45535D02*
X1457782Y-46022D01*
G01X1459226Y-44560D02*
X1458504Y-45535D01*
G01Y-42611D02*
X1459226Y-43586D01*
G01X1457782Y-42124D02*
X1458504Y-42611D01*
G01X1456339Y-41637D02*
X1457782Y-42124D01*
G01X1454895D02*
X1456339Y-41637D01*
G01X1454173Y-42611D02*
X1454895Y-42124D01*
G01X1453452Y-43586D02*
X1454173Y-42611D01*
G01X1453452Y-44560D02*
Y-43586D01*
G01X1454173Y-45535D02*
X1453452Y-44560D01*
G01X1450564Y-45048D02*
X1454173Y-45535D01*
G01X1450564Y-42124D02*
Y-45048D01*
G01X1449580Y204584D02*
G03X1451548Y202616I1969J1D01*
G01X1449580Y204584D02*
G03X1451548Y202616I1969J1D01*
G01X1457763Y198786D02*
X1457976Y198241D01*
G01D02*
Y195628D01*
G01X1457443D02*
Y198241D01*
G01X1447846Y198568D02*
X1447739Y199221D01*
G01X1445074Y197806D02*
X1445180Y197152D01*
G01X1448379Y198677D02*
X1448272Y199221D01*
G01X1444541Y197697D02*
X1444647Y197152D01*
G01X1448272Y199221D02*
X1448166Y199548D01*
G01X1444647Y197152D02*
X1444754Y196826D01*
G01X1452964Y198786D02*
X1453178Y198241D01*
G01X1457443D02*
X1457336Y198459D01*
G01X1455737Y198241D02*
X1455630Y198459D01*
G01X1452645Y198241D02*
X1452538Y198459D01*
G01X1450938Y198241D02*
X1450832Y198459D01*
G01X1448166Y199548D02*
X1447953Y199983D01*
G01X1444754Y196826D02*
X1444967Y196390D01*
G01X1447739Y197152D02*
X1447846Y197806D01*
G01X1456270Y198241D02*
Y195628D01*
G01X1455737D02*
Y198241D01*
G01X1454564Y198350D02*
Y195628D01*
G01Y199112D02*
Y198786D01*
G01X1454030Y195628D02*
Y199112D01*
G01X1453178Y198241D02*
Y195628D01*
G01X1452645D02*
Y198241D01*
G01X1451471D02*
Y195628D01*
G01X1450938D02*
Y198241D01*
G01X1449765Y198350D02*
Y195628D01*
G01Y199112D02*
Y198786D01*
G01X1449580Y259860D02*
Y204584D01*
G01Y259860D02*
Y204584D01*
G01X1449232Y195628D02*
Y199112D01*
G01X1448379Y197697D02*
Y198677D01*
G01X1447846Y197806D02*
Y198568D01*
G01X1445074D02*
Y197806D01*
G01X1444541Y198677D02*
Y197697D01*
G01X1443688Y197806D02*
Y197370D01*
G01Y199112D02*
Y198677D01*
G01X1447739Y199221D02*
X1447313Y199875D01*
G01X1445180Y197152D02*
X1445607Y196499D01*
G01X1457549Y199004D02*
X1457763Y198786D01*
G01X1457336Y198459D02*
X1457229Y198568D01*
G01X1455843Y199004D02*
X1456163Y198677D01*
G01X1455630Y198459D02*
X1455523Y198568D01*
G01X1452751Y199004D02*
X1452964Y198786D01*
G01X1452538Y198459D02*
X1452431Y198568D01*
G01X1451045Y199004D02*
X1451365Y198677D01*
G01X1450832Y198459D02*
X1450725Y198568D01*
G01X1447953Y199983D02*
X1447633Y200310D01*
G01X1456376Y198459D02*
X1456270Y198241D01*
G01X1448166Y196826D02*
X1448272Y197152D01*
G01X1444754Y199548D02*
X1444647Y199221D01*
G01X1448272Y197152D02*
X1448379Y197697D01*
G01X1444647Y199221D02*
X1444541Y198677D01*
G01X1445180Y199221D02*
X1445074Y198568D01*
G01X1444967Y196390D02*
X1445287Y196063D01*
G01X1451578Y198459D02*
X1451471Y198241D01*
G01X1447953Y196390D02*
X1448166Y196826D01*
G01X1444967Y199983D02*
X1444754Y199548D01*
G01X1447313Y199875D02*
X1446993Y200093D01*
G01X1445607Y196499D02*
X1445927Y196281D01*
G01X1447633Y200310D02*
X1447100Y200637D01*
G01X1445287Y196063D02*
X1445820Y195737D01*
G01X1457229Y198568D02*
X1457016Y198677D01*
G01X1455523Y198568D02*
X1455310Y198677D01*
G01X1452431Y198568D02*
X1452218Y198677D01*
G01X1447313Y196499D02*
X1447739Y197152D01*
G01X1445607Y199875D02*
X1445180Y199221D01*
G01X1450725Y198568D02*
X1450512Y198677D01*
G01X1456483Y198568D02*
X1456376Y198459D01*
G01X1456163Y198677D02*
X1456483Y199004D01*
G01X1454777Y198568D02*
X1454564Y198350D01*
G01Y198786D02*
X1454777Y199004D01*
G01X1451685Y198568D02*
X1451578Y198459D01*
G01X1451365Y198677D02*
X1451685Y199004D01*
G01X1447633Y196063D02*
X1447953Y196390D01*
G01X1449979Y198568D02*
X1449765Y198350D01*
G01Y198786D02*
X1449979Y199004D01*
G01X1445287Y200310D02*
X1444967Y199983D01*
G01X1457229Y199112D02*
X1457549Y199004D01*
G01X1455523Y199112D02*
X1455843Y199004D01*
G01X1452431Y199112D02*
X1452751Y199004D01*
G01X1450725Y199112D02*
X1451045Y199004D01*
G01X1446993Y200093D02*
X1446460Y200201D01*
G01X1445927Y196281D02*
X1446460Y196172D01*
G01X1447100Y200637D02*
X1446460Y200746D01*
G01X1445820Y195737D02*
X1446460Y195628D01*
G01X1447100Y195737D02*
X1447633Y196063D01*
G01X1445820Y200637D02*
X1445287Y200310D01*
G01X1446993Y196281D02*
X1447313Y196499D01*
G01X1445927Y200093D02*
X1445607Y199875D01*
G01X1459422Y202616D02*
X1451548D01*
G01X1459422D02*
X1451548D01*
G01X1456696Y198677D02*
X1456483Y198568D01*
G01X1451898Y198677D02*
X1451685Y198568D01*
G01X1456803Y199112D02*
X1457229D01*
G01X1455097D02*
X1455523D01*
G01X1454030D02*
X1454564D01*
G01X1452005D02*
X1452431D01*
G01X1450298D02*
X1450725D01*
G01X1449232D02*
X1449765D01*
G01X1450512Y198677D02*
X1450298D01*
G01X1452218D02*
X1451898D01*
G01X1455310D02*
X1455097D01*
G01X1457016D02*
X1456696D01*
G01X1451471Y195628D02*
X1450938D01*
G01X1449765D02*
X1449232D01*
G01X1453178D02*
X1452645D01*
G01X1454564D02*
X1454030D01*
G01X1456270D02*
X1455737D01*
G01X1457976D02*
X1457443D01*
G01X1456483Y199004D02*
X1456803Y199112D01*
G01X1455097Y198677D02*
X1454777Y198568D01*
G01Y199004D02*
X1455097Y199112D01*
G01X1451685Y199004D02*
X1452005Y199112D01*
G01X1450298Y198677D02*
X1449979Y198568D01*
G01Y199004D02*
X1450298Y199112D01*
G01X1446460Y200746D02*
X1445820Y200637D01*
G01X1446460Y195628D02*
X1447100Y195737D01*
G01X1446460Y200201D02*
X1445927Y200093D01*
G01X1446460Y196172D02*
X1446993Y196281D01*
G01X1451548Y261828D02*
G03X1449580Y259860I0J-1968D01*
G01X1451548Y261828D02*
G03X1449580Y259860I0J-1968D01*
G01Y263797D02*
Y362352D01*
G01X1459422Y261828D02*
X1451548D01*
G01X1459422D02*
X1451548D01*
G01X1461391Y340569D02*
G03X1453517Y348443I-7874J0D01*
G01X1461391Y340569D02*
G03X1453517Y348443I-7874J0D01*
G01X1446693Y369119D02*
X1445249Y368144D01*
G01X1447415Y370093D02*
X1446693Y369119D01*
G01X1444528Y368144D02*
X1443084Y369119D01*
G01X1445249Y368144D02*
X1444528D01*
G01X1447415Y371067D02*
Y370093D01*
G01X1446693Y372042D02*
X1447415Y371067D01*
G01X1445249Y373016D02*
X1446693Y372042D01*
G01X1444528Y373016D02*
X1445249D01*
G01X1443806Y372529D02*
X1444528Y373016D01*
G01X1443084Y372042D02*
X1443806Y372529D01*
G01X1442362Y371067D02*
X1443084Y372042D01*
G01X1442362Y370093D02*
Y371067D01*
G01X1443084Y369119D02*
X1442362Y370093D01*
G01X1446693Y376914D02*
X1445971Y376426D01*
G01X1447415Y377888D02*
X1446693Y376914D01*
G01X1447415Y378863D02*
Y377888D01*
G01X1446693Y379837D02*
X1447415Y378863D01*
G01X1445971Y380324D02*
X1446693Y379837D01*
G01X1444528Y380811D02*
X1445971Y380324D01*
G01X1443084D02*
X1444528Y380811D01*
G01X1442362Y379837D02*
X1443084Y380324D01*
G01X1446693Y385683D02*
X1447415Y386170D01*
G01Y385683D02*
X1446693D01*
G01X1447415Y386170D02*
Y385683D01*
G01X1446693Y400300D02*
X1445971Y399812D01*
G01X1447415Y401274D02*
X1446693Y400300D01*
G01X1447415Y402248D02*
Y401274D01*
G01X1446693Y403223D02*
X1447415Y402248D01*
G01X1445971Y403710D02*
X1446693Y403223D01*
G01X1444528Y404197D02*
X1445971Y403710D01*
G01X1443084D02*
X1444528Y404197D01*
G01X1442362Y403223D02*
X1443084Y403710D01*
G01X1447415Y393966D02*
X1443806Y394453D01*
G01X1459226Y-74767D02*
Y-75741D01*
G01Y-66972D02*
Y-67946D01*
G01Y-59664D02*
Y-60151D01*
G01Y-43586D02*
Y-44560D01*
G01X1461391Y-16951D02*
Y-35845D01*
G01X1459422Y-14983D02*
G03X1461391Y-13014I0J1969D01*
G01X1459422Y-14983D02*
G03X1461391Y-13014I0J1969D01*
G01D02*
Y6415D01*
G01Y-13014D02*
Y6415D01*
G01D02*
G03X1459422Y8383I-1968J0D01*
G01X1461391Y6415D02*
G03X1459422Y8383I-1968J0D01*
G01Y178974D02*
G03X1461391Y180943I1J1968D01*
G01X1459422Y178974D02*
G03X1461391Y180943I1J1968D01*
G01Y200647D02*
Y180943D01*
G01Y200647D02*
Y180943D01*
G01X1463359Y202616D02*
X1510242D01*
G01X1461391Y200647D02*
G03X1459422Y202616I-1968J1D01*
G01X1461391Y200647D02*
G03X1459422Y202616I-1968J1D01*
G01X1463359Y261828D02*
X1510242D01*
G01X1459422D02*
G03X1461391Y263797I0J1969D01*
G01X1459422Y261828D02*
G03X1461391Y263797I0J1969D01*
G01Y340569D02*
Y263797D01*
G01Y340569D02*
Y263797D01*
G01X1477095Y-740940D02*
Y-758263D01*
G01X1484941Y-637222D02*
X1486441Y-635223D01*
X1488191Y-634222D01*
X1490191Y-633889D01*
X1492691Y-634556D01*
X1494441Y-636222D01*
X1494941Y-638222D01*
X1494691Y-640223D01*
X1493691Y-641889D01*
X1488691Y-645222D01*
X1486441Y-647556D01*
X1484941Y-650890D01*
X1484441Y-653889D01*
X1494941D01*
G01X1509691Y-633889D02*
X1507691Y-634556D01*
X1506191Y-636222D01*
X1505191Y-638222D01*
X1504441Y-640889D01*
X1504191Y-643889D01*
X1504441Y-646889D01*
X1505191Y-649556D01*
X1506191Y-651556D01*
X1507691Y-653222D01*
X1509691Y-653889D01*
X1511691Y-653222D01*
X1513191Y-651556D01*
X1514191Y-649556D01*
X1514941Y-646889D01*
X1515191Y-643889D01*
X1514941Y-640889D01*
X1514191Y-638222D01*
X1513191Y-636222D01*
X1511691Y-634556D01*
X1509691Y-633889D01*
G01X1529691Y-653889D02*
Y-633889D01*
X1526691Y-637889D01*
G01Y-653889D02*
X1532691D01*
G01X1544941Y-645556D02*
X1546691Y-643222D01*
X1548191Y-641889D01*
X1550191Y-641223D01*
X1551941Y-641889D01*
X1553191Y-643222D01*
X1554191Y-645222D01*
X1554441Y-647556D01*
X1554191Y-649556D01*
X1553191Y-651556D01*
X1551691Y-653222D01*
X1549941Y-653889D01*
X1547941Y-653222D01*
X1546191Y-651223D01*
X1545191Y-648222D01*
X1544941Y-644889D01*
X1545441Y-640556D01*
X1546191Y-638222D01*
X1547441Y-635889D01*
X1549191Y-634222D01*
X1550941Y-633889D01*
X1552691Y-634556D01*
X1553941Y-636222D01*
G01X1566441Y-647223D02*
X1572941D01*
G01X1589691Y-633889D02*
X1587691Y-634556D01*
X1586191Y-636222D01*
X1585191Y-638222D01*
X1584441Y-640889D01*
X1584191Y-643889D01*
X1584441Y-646889D01*
X1585191Y-649556D01*
X1586191Y-651556D01*
X1587691Y-653222D01*
X1589691Y-653889D01*
X1591691Y-653222D01*
X1593191Y-651556D01*
X1594191Y-649556D01*
X1594941Y-646889D01*
X1595191Y-643889D01*
X1594941Y-640889D01*
X1594191Y-638222D01*
X1593191Y-636222D01*
X1591691Y-634556D01*
X1589691Y-633889D01*
G01X1604941Y-645556D02*
X1606691Y-643222D01*
X1608191Y-641889D01*
X1610191Y-641223D01*
X1611941Y-641889D01*
X1613191Y-643222D01*
X1614191Y-645222D01*
X1614441Y-647556D01*
X1614191Y-649556D01*
X1613191Y-651556D01*
X1611691Y-653222D01*
X1609941Y-653889D01*
X1607941Y-653222D01*
X1606191Y-651223D01*
X1605191Y-648222D01*
X1604941Y-644889D01*
X1605441Y-640556D01*
X1606191Y-638222D01*
X1607441Y-635889D01*
X1609191Y-634222D01*
X1610941Y-633889D01*
X1612691Y-634556D01*
X1613941Y-636222D01*
G01X1626441Y-647223D02*
X1632941D01*
G01X1644941Y-637222D02*
X1646441Y-635223D01*
X1648191Y-634222D01*
X1650191Y-633889D01*
X1652691Y-634556D01*
X1654441Y-636222D01*
X1654941Y-638222D01*
X1654691Y-640223D01*
X1653691Y-641889D01*
X1648691Y-645222D01*
X1646441Y-647556D01*
X1644941Y-650890D01*
X1644441Y-653889D01*
X1654941D01*
G01X1665441Y-651556D02*
X1667191Y-653222D01*
X1669191Y-653889D01*
X1671191Y-653222D01*
X1672941Y-651223D01*
X1674191Y-648222D01*
X1674691Y-645222D01*
Y-641556D01*
X1674191Y-638556D01*
X1672941Y-635889D01*
X1671441Y-634556D01*
X1669691Y-633889D01*
X1667691Y-634556D01*
X1666191Y-635889D01*
X1665191Y-637889D01*
X1664691Y-640556D01*
X1665191Y-642889D01*
X1666441Y-645222D01*
X1667941Y-646556D01*
X1669691Y-646889D01*
X1671691Y-646223D01*
X1673191Y-644556D01*
X1674691Y-641556D01*
G01X1497584Y-605181D02*
Y-585181D01*
X1494584Y-589181D01*
G01Y-605181D02*
X1500584D01*
G01X1517584Y-605848D02*
X1517084Y-605514D01*
Y-604848D01*
X1517584Y-604514D01*
X1518084Y-604848D01*
Y-605514D01*
X1517584Y-605848D01*
G01X1532834Y-596848D02*
X1534584Y-594514D01*
X1536084Y-593181D01*
X1538084Y-592515D01*
X1539834Y-593181D01*
X1541084Y-594514D01*
X1542084Y-596514D01*
X1542334Y-598848D01*
X1542084Y-600848D01*
X1541084Y-602848D01*
X1539584Y-604514D01*
X1537834Y-605181D01*
X1535834Y-604514D01*
X1534084Y-602515D01*
X1533084Y-599514D01*
X1532834Y-596181D01*
X1533334Y-591848D01*
X1534084Y-589514D01*
X1535334Y-587181D01*
X1537084Y-585514D01*
X1538834Y-585181D01*
X1540584Y-585848D01*
X1541834Y-587514D01*
G01X1550084Y-605181D02*
Y-591848D01*
G01Y-595515D02*
X1550834Y-593848D01*
X1552084Y-592515D01*
X1553834Y-591848D01*
X1555584Y-592515D01*
X1556834Y-593848D01*
X1557584Y-595515D01*
Y-605181D01*
G01Y-595515D02*
X1558334Y-593848D01*
X1559584Y-592515D01*
X1561334Y-591848D01*
X1563084Y-592515D01*
X1564334Y-593848D01*
X1565084Y-595848D01*
Y-605181D01*
G01X1570084D02*
Y-591848D01*
G01Y-595515D02*
X1570834Y-593848D01*
X1572084Y-592515D01*
X1573834Y-591848D01*
X1575584Y-592515D01*
X1576834Y-593848D01*
X1577584Y-595515D01*
Y-605181D01*
G01Y-595515D02*
X1578334Y-593848D01*
X1579584Y-592515D01*
X1581334Y-591848D01*
X1583084Y-592515D01*
X1584334Y-593848D01*
X1585084Y-595848D01*
Y-605181D01*
G01X1477095Y619690D02*
Y602367D01*
G01X1524804Y205503D02*
X1524317Y206225D01*
G01X1525778Y204781D02*
X1524804Y205503D01*
G01Y209834D02*
X1525778Y210556D01*
G01X1525291Y213443D02*
X1524804Y209834D01*
G01X1517008Y205503D02*
X1516521Y206225D01*
G01X1517983Y204781D02*
X1517008Y205503D01*
G01X1518957Y204781D02*
X1517983D01*
G01X1519932Y205503D02*
X1518957Y204781D01*
G01X1520419Y206225D02*
X1519932Y205503D01*
G01X1520906Y207669D02*
X1520419Y206225D01*
G01Y209112D02*
X1520906Y207669D01*
G01X1519932Y209834D02*
X1520419Y209112D01*
G01X1518957Y210556D02*
X1519932Y209834D01*
G01X1517983Y210556D02*
X1518957D01*
G01X1517008Y209834D02*
X1517983Y210556D01*
G01X1517496Y213443D02*
X1517008Y209834D01*
G01X1520419Y213443D02*
X1517496D01*
G01X1520419Y272655D02*
X1516521D01*
G01X1519445Y269768D02*
X1520419Y272655D01*
G01X1518957Y267603D02*
X1519445Y269768D01*
G01X1518470Y263994D02*
X1518957Y267603D01*
G01X1524804Y271212D02*
X1525291Y271933D01*
G01X1524317Y269768D02*
X1524804Y271212D01*
G01X1524317Y266881D02*
Y269768D01*
G01X1524804Y265437D02*
X1524317Y266881D01*
G01X1525291Y264716D02*
X1524804Y265437D01*
G01X1533573Y205503D02*
X1534061Y204781D01*
G01X1533573D02*
Y205503D01*
G01X1534061Y204781D02*
X1533573D01*
G01X1526752D02*
X1525778D01*
G01X1527727Y205503D02*
X1526752Y204781D01*
G01X1528214Y206225D02*
X1527727Y205503D01*
G01X1528701Y207669D02*
X1528214Y206225D01*
G01Y209112D02*
X1528701Y207669D01*
G01X1527727Y209834D02*
X1528214Y209112D01*
G01X1526752Y210556D02*
X1527727Y209834D01*
G01X1525778Y210556D02*
X1526752D01*
G01X1539907Y204781D02*
X1543805D01*
G01X1540394Y206946D02*
X1539907Y204781D01*
G01X1541369Y208390D02*
X1540394Y206946D01*
G01X1528214Y213443D02*
X1525291D01*
G01X1540394Y212721D02*
X1541369Y213443D01*
G01X1539907Y211999D02*
X1540394Y212721D01*
G01Y271933D02*
X1541369Y272655D01*
G01X1533573Y264716D02*
X1534061Y263994D01*
G01X1533573D02*
Y264716D01*
G01X1534061Y263994D02*
X1533573D01*
G01X1527240Y264716D02*
X1526265Y263994D01*
G01X1527727Y265437D02*
X1527240Y264716D01*
G01X1528214Y266881D02*
X1527727Y265437D01*
G01X1528214Y269768D02*
Y266881D01*
G01X1527727Y271212D02*
X1528214Y269768D01*
G01X1527240Y271933D02*
X1527727Y271212D01*
G01X1526265Y272655D02*
X1527240Y271933D01*
G01X1525291D02*
X1526265Y272655D01*
G01Y263994D02*
X1525291Y264716D01*
G01X1540394D02*
X1539907Y265437D01*
G01X1541369Y263994D02*
X1540394Y264716D01*
G01X1543317Y209834D02*
X1541369Y208390D01*
G01X1543805Y210556D02*
X1543317Y209834D01*
G01X1543805Y211999D02*
Y210556D01*
G01X1550626D02*
X1551113Y211999D01*
G01X1550138Y208390D02*
X1550626Y210556D01*
G01X1549651Y204781D02*
X1550138Y208390D01*
G01X1543317Y212721D02*
X1543805Y211999D01*
G01X1542343Y213443D02*
X1543317Y212721D01*
G01X1541369Y213443D02*
X1542343D01*
G01X1551600D02*
X1547702D01*
G01X1551113Y211999D02*
X1551600Y213443D01*
G01X1542343Y269046D02*
X1543317Y268324D01*
G01Y269768D02*
X1542343Y269046D01*
G01X1543805Y270490D02*
X1543317Y269768D01*
G01X1543805Y271212D02*
Y270490D01*
G01X1543317Y271933D02*
X1543805Y271212D01*
G01X1542343Y272655D02*
X1543317Y271933D01*
G01X1541369Y272655D02*
X1542343D01*
G01Y263994D02*
X1541369D01*
G01X1543317Y264716D02*
X1542343Y263994D01*
G01X1543805Y265437D02*
X1543317Y264716D01*
G01X1544292Y266159D02*
X1543805Y265437D01*
G01X1544292Y266881D02*
Y266159D01*
G01X1543317Y268324D02*
X1544292Y266881D01*
G01X1549651Y272655D02*
Y263994D01*
G01X1541369Y269046D02*
X1542343D01*
G01X1571059Y-752009D02*
Y-745709D01*
X1570119Y-746969D01*
G01Y-752009D02*
X1571999D01*
G01X1577359D02*
Y-745709D01*
X1576419Y-746969D01*
G01Y-752009D02*
X1578299D01*
G01X1571059Y608621D02*
Y614921D01*
X1570119Y613661D01*
G01Y608621D02*
X1571999D01*
G01X1577359D02*
Y614921D01*
X1576419Y613661D01*
G01Y608621D02*
X1578299D01*
G01X1680245Y-725192D02*
Y-469407D01*
G01X1695993Y602367D02*
Y-740940D01*
G01X1700516Y-681931D02*
Y-675631D01*
X1703492D01*
G01X1702396Y-678676D02*
X1700516D01*
G01X1695993Y-561413D02*
X1713315D01*
G01X1703571Y-445710D02*
X1700437D01*
Y-439410D01*
X1703571D01*
G01X1702317Y-442455D02*
X1700437D01*
G01X1695993Y-325192D02*
X1713315D01*
G01X1700281Y-209490D02*
Y-203190D01*
X1701847D01*
X1702474Y-203505D01*
X1702944Y-203925D01*
X1703336Y-204555D01*
X1703649Y-205290D01*
X1703727Y-206340D01*
X1703649Y-207390D01*
X1703336Y-208125D01*
X1702944Y-208755D01*
X1702474Y-209175D01*
X1701847Y-209490D01*
X1700281D01*
G01X1695993Y-88972D02*
X1713315D01*
G01X1703727Y32506D02*
X1703257Y32821D01*
X1702709Y33031D01*
X1702082D01*
X1701377Y32716D01*
X1700829Y32191D01*
X1700437Y31561D01*
X1700124Y30511D01*
X1700046Y29566D01*
X1700202Y28621D01*
X1700437Y27991D01*
X1700907Y27361D01*
X1701456Y26941D01*
X1702004Y26731D01*
X1702552D01*
X1703101Y26941D01*
X1703571Y27256D01*
X1703962Y27676D01*
G01X1695993Y147249D02*
X1713315D01*
G01X1702631Y266311D02*
X1702944Y266626D01*
X1703179Y267151D01*
X1703336Y267886D01*
X1703179Y268516D01*
X1702866Y268936D01*
X1702317Y269251D01*
X1700202D01*
Y262951D01*
X1702787D01*
X1703336Y263371D01*
X1703649Y264001D01*
X1703806Y264736D01*
X1703649Y265471D01*
X1703179Y266101D01*
X1702631Y266311D01*
X1700202D01*
G01X1695993Y383469D02*
X1713315D01*
G01X1700046Y499172D02*
X1702004Y505472D01*
X1703962Y499172D01*
G01X1703257Y501377D02*
X1700751D01*
G01X1713315Y619690D02*
Y-758263D01*
M02*
